G04 ================== begin FILE IDENTIFICATION RECORD ==================*
G04 Layout Name:  15126-1b.brd*
G04 Film Name:    SE_REF_L1*
G04 File Format:  Gerber RS274X*
G04 File Origin:  Cadence Allegro 16.6-2015-S079*
G04 Origin Date:  Fri Feb 10 17:23:32 2017*
G04 *
G04 Layer:  BOARD GEOMETRY/PANEL_OUTLINE*
G04 Layer:  BOARD GEOMETRY/SE_REF_L1_TBL*
G04 Layer:  BOARD GEOMETRY/SE_REF_L1_TOP*
G04 *
G04 Offset:    (0.00 0.00)*
G04 Mirror:    No*
G04 Mode:      Positive*
G04 Rotation:  0*
G04 FullContactRelief:  No*
G04 UndefLineWidth:     6.00*
G04 ================== end FILE IDENTIFICATION RECORD ====================*
%FSLAX35Y35*MOIN*%
%IR0*IPPOS*OFA0.00000B0.00000*MIA0B0*SFA1.00000B1.00000*%
%ADD10C,.02*%
%ADD11C,.006*%
%ADD12C,.0042*%
%ADD13C,.0065*%
%ADD14C,.00425*%
G75*
%LPD*%
G75*
G54D10*
G01X2026678Y631398D02*
Y527448D01*
G01D02*
X2744178D01*
G01X2026678Y562098D02*
X2744178D01*
G01X2026678Y596748D02*
X2744178D01*
G01X2026678Y631398D02*
X2744178D01*
G01X2201678D02*
Y527448D01*
G01X2429178Y631398D02*
Y527448D01*
G01X2534178Y631398D02*
Y527448D01*
G01X2744178Y631398D02*
Y527448D01*
G54D11*
G01X-17372Y-95792D02*
Y-113292D01*
G01X-22394Y-95792D02*
X-12350D01*
G01X-3584Y-113292D02*
Y-95792D01*
G01Y-104250D02*
X-2492Y-102792D01*
X-1400Y-101917D01*
X346Y-101626D01*
X1656Y-101917D01*
X3185Y-103084D01*
X3840Y-104834D01*
Y-113292D01*
G01X17628Y-101626D02*
Y-113292D01*
G01Y-96959D02*
X17191Y-96667D01*
Y-96084D01*
X17628Y-95792D01*
X18065Y-96084D01*
Y-96667D01*
X17628Y-96959D01*
G01X31853Y-111251D02*
X32945Y-112417D01*
X34473Y-113292D01*
X35783D01*
X37093Y-112709D01*
X37966Y-111834D01*
X38403Y-110668D01*
X38185Y-108917D01*
X37311Y-108042D01*
X33381Y-106292D01*
X32508Y-104250D01*
X32945Y-102792D01*
X33818Y-101917D01*
X35128Y-101626D01*
X36438Y-101917D01*
X37748Y-102792D01*
G01X67071Y-117667D02*
X68600Y-118834D01*
X70346Y-119125D01*
X71874Y-118834D01*
X73185Y-117376D01*
X74058Y-115334D01*
Y-101626D01*
G01Y-103959D02*
X73185Y-102792D01*
X71874Y-101917D01*
X70346Y-101626D01*
X68600Y-102209D01*
X67508Y-103375D01*
X66634Y-105417D01*
X66198Y-107459D01*
X66416Y-109209D01*
X67290Y-111251D01*
X68600Y-112709D01*
X70346Y-113292D01*
X71656Y-113000D01*
X73185Y-111834D01*
X74058Y-110668D01*
G01X84353Y-105417D02*
X91340D01*
X90685Y-103375D01*
X89593Y-102209D01*
X88065Y-101626D01*
X86536Y-101917D01*
X85226Y-102792D01*
X84353Y-104834D01*
X83916Y-106584D01*
Y-108334D01*
X84353Y-110084D01*
X85445Y-111834D01*
X86755Y-113000D01*
X88283Y-113292D01*
X89811Y-112709D01*
X91340Y-110959D01*
G01X102071Y-113292D02*
Y-101626D01*
G01Y-103959D02*
X103163Y-102792D01*
X104255Y-101917D01*
X105783Y-101626D01*
X106874Y-101917D01*
X108185Y-102792D01*
G01X118698Y-113292D02*
Y-95792D01*
G01Y-104542D02*
X119790Y-102792D01*
X121100Y-101917D01*
X122410Y-101626D01*
X124374Y-102209D01*
X125685Y-103375D01*
X126558Y-105417D01*
Y-107750D01*
X126121Y-110084D01*
X125248Y-111834D01*
X123720Y-113000D01*
X122410Y-113292D01*
X121100Y-113000D01*
X119790Y-112126D01*
X118698Y-110668D01*
G01X136853Y-105417D02*
X143840D01*
X143185Y-103375D01*
X142093Y-102209D01*
X140565Y-101626D01*
X139036Y-101917D01*
X137726Y-102792D01*
X136853Y-104834D01*
X136416Y-106584D01*
Y-108334D01*
X136853Y-110084D01*
X137945Y-111834D01*
X139255Y-113000D01*
X140783Y-113292D01*
X142311Y-112709D01*
X143840Y-110959D01*
G01X154571Y-113292D02*
Y-101626D01*
G01Y-103959D02*
X155663Y-102792D01*
X156755Y-101917D01*
X158283Y-101626D01*
X159374Y-101917D01*
X160685Y-102792D01*
G01X192628Y-101626D02*
Y-113292D01*
G01Y-96959D02*
X192191Y-96667D01*
Y-96084D01*
X192628Y-95792D01*
X193065Y-96084D01*
Y-96667D01*
X192628Y-96959D01*
G01X206853Y-111251D02*
X207945Y-112417D01*
X209473Y-113292D01*
X210783D01*
X212093Y-112709D01*
X212966Y-111834D01*
X213403Y-110668D01*
X213185Y-108917D01*
X212311Y-108042D01*
X208381Y-106292D01*
X207508Y-104250D01*
X207945Y-102792D01*
X208818Y-101917D01*
X210128Y-101626D01*
X211438Y-101917D01*
X212748Y-102792D01*
G01X241634Y-117667D02*
X243163Y-118834D01*
X244473Y-119125D01*
X246220Y-118542D01*
X247530Y-117084D01*
X248185Y-114458D01*
Y-101626D01*
G01Y-96959D02*
X247748Y-96667D01*
Y-96084D01*
X248185Y-95792D01*
X248621Y-96084D01*
Y-96667D01*
X248185Y-96959D01*
G01X258916Y-101626D02*
Y-109792D01*
X259790Y-111834D01*
X261100Y-113000D01*
X262628Y-113292D01*
X264156Y-113000D01*
X265466Y-111834D01*
X266340Y-109792D01*
G01Y-113292D02*
Y-101626D01*
G01X276853Y-111251D02*
X277945Y-112417D01*
X279473Y-113292D01*
X280783D01*
X282093Y-112709D01*
X282966Y-111834D01*
X283403Y-110668D01*
X283185Y-108917D01*
X282311Y-108042D01*
X278381Y-106292D01*
X277508Y-104250D01*
X277945Y-102792D01*
X278818Y-101917D01*
X280128Y-101626D01*
X281438Y-101917D01*
X282748Y-102792D01*
G01X297628Y-95792D02*
Y-113292D01*
G01X294571Y-101626D02*
X300685D01*
G01X331318Y-113292D02*
Y-98417D01*
X331755Y-96959D01*
X332628Y-96084D01*
X333938Y-95792D01*
X335248Y-96375D01*
X335903Y-97834D01*
G01X333283Y-102792D02*
X328916D01*
G01X350128Y-113292D02*
X348818Y-113000D01*
X347508Y-111834D01*
X346634Y-109792D01*
X346198Y-107459D01*
X346634Y-105125D01*
X347508Y-103084D01*
X348818Y-101917D01*
X350128Y-101626D01*
X351438Y-101917D01*
X352748Y-103084D01*
X353621Y-105125D01*
X353840Y-107459D01*
X353621Y-109792D01*
X352748Y-111834D01*
X351438Y-113000D01*
X350128Y-113292D01*
G01X364571D02*
Y-101626D01*
G01Y-103959D02*
X365663Y-102792D01*
X366755Y-101917D01*
X368283Y-101626D01*
X369374Y-101917D01*
X370685Y-102792D01*
G01X398043Y-118542D02*
X399353Y-119125D01*
X401100Y-118542D01*
X402191Y-117376D01*
X403065Y-115917D01*
X404374Y-111251D01*
X407213Y-101626D01*
G01X400226D02*
X404374Y-111251D01*
G01X420128Y-113292D02*
X418818Y-113000D01*
X417508Y-111834D01*
X416634Y-109792D01*
X416198Y-107459D01*
X416634Y-105125D01*
X417508Y-103084D01*
X418818Y-101917D01*
X420128Y-101626D01*
X421438Y-101917D01*
X422748Y-103084D01*
X423621Y-105125D01*
X423840Y-107459D01*
X423621Y-109792D01*
X422748Y-111834D01*
X421438Y-113000D01*
X420128Y-113292D01*
G01X433916Y-101626D02*
Y-109792D01*
X434790Y-111834D01*
X436100Y-113000D01*
X437628Y-113292D01*
X439156Y-113000D01*
X440466Y-111834D01*
X441340Y-109792D01*
G01Y-113292D02*
Y-101626D01*
G01X452071Y-113292D02*
Y-101626D01*
G01Y-103959D02*
X453163Y-102792D01*
X454255Y-101917D01*
X455783Y-101626D01*
X456874Y-101917D01*
X458185Y-102792D01*
G01X487071Y-113292D02*
Y-101626D01*
G01Y-103959D02*
X488163Y-102792D01*
X489255Y-101917D01*
X490783Y-101626D01*
X491874Y-101917D01*
X493185Y-102792D01*
G01X504353Y-105417D02*
X511340D01*
X510685Y-103375D01*
X509593Y-102209D01*
X508065Y-101626D01*
X506536Y-101917D01*
X505226Y-102792D01*
X504353Y-104834D01*
X503916Y-106584D01*
Y-108334D01*
X504353Y-110084D01*
X505445Y-111834D01*
X506755Y-113000D01*
X508283Y-113292D01*
X509811Y-112709D01*
X511340Y-110959D01*
G01X523818Y-113292D02*
Y-98417D01*
X524255Y-96959D01*
X525128Y-96084D01*
X526438Y-95792D01*
X527748Y-96375D01*
X528403Y-97834D01*
G01X525783Y-102792D02*
X521416D01*
G01X539353Y-105417D02*
X546340D01*
X545685Y-103375D01*
X544593Y-102209D01*
X543065Y-101626D01*
X541536Y-101917D01*
X540226Y-102792D01*
X539353Y-104834D01*
X538916Y-106584D01*
Y-108334D01*
X539353Y-110084D01*
X540445Y-111834D01*
X541755Y-113000D01*
X543283Y-113292D01*
X544811Y-112709D01*
X546340Y-110959D01*
G01X557071Y-113292D02*
Y-101626D01*
G01Y-103959D02*
X558163Y-102792D01*
X559255Y-101917D01*
X560783Y-101626D01*
X561874Y-101917D01*
X563185Y-102792D01*
G01X574353Y-105417D02*
X581340D01*
X580685Y-103375D01*
X579593Y-102209D01*
X578065Y-101626D01*
X576536Y-101917D01*
X575226Y-102792D01*
X574353Y-104834D01*
X573916Y-106584D01*
Y-108334D01*
X574353Y-110084D01*
X575445Y-111834D01*
X576755Y-113000D01*
X578283Y-113292D01*
X579811Y-112709D01*
X581340Y-110959D01*
G01X591416Y-113292D02*
Y-101626D01*
G01Y-104542D02*
X592290Y-103084D01*
X593600Y-101917D01*
X595346Y-101626D01*
X596874Y-101917D01*
X598185Y-103084D01*
X598840Y-105125D01*
Y-113292D01*
G01X616121Y-103084D02*
X614593Y-101917D01*
X613283Y-101626D01*
X611536Y-102209D01*
X610226Y-103375D01*
X609353Y-105417D01*
X609134Y-107459D01*
X609353Y-109501D01*
X610226Y-111251D01*
X611536Y-112709D01*
X613283Y-113292D01*
X614811Y-112709D01*
X616121Y-111542D01*
G01X626853Y-105417D02*
X633840D01*
X633185Y-103375D01*
X632093Y-102209D01*
X630565Y-101626D01*
X629036Y-101917D01*
X627726Y-102792D01*
X626853Y-104834D01*
X626416Y-106584D01*
Y-108334D01*
X626853Y-110084D01*
X627945Y-111834D01*
X629255Y-113000D01*
X630783Y-113292D01*
X632311Y-112709D01*
X633840Y-110959D01*
G01X665128Y-95792D02*
Y-113292D01*
G01X662071Y-101626D02*
X668185D01*
G01X682628Y-113292D02*
X681318Y-113000D01*
X680008Y-111834D01*
X679134Y-109792D01*
X678698Y-107459D01*
X679134Y-105125D01*
X680008Y-103084D01*
X681318Y-101917D01*
X682628Y-101626D01*
X683938Y-101917D01*
X685248Y-103084D01*
X686121Y-105125D01*
X686340Y-107459D01*
X686121Y-109792D01*
X685248Y-111834D01*
X683938Y-113000D01*
X682628Y-113292D01*
G01X716318D02*
Y-98417D01*
X716755Y-96959D01*
X717628Y-96084D01*
X718938Y-95792D01*
X720248Y-96375D01*
X720903Y-97834D01*
G01X718283Y-102792D02*
X713916D01*
G01X735128Y-101626D02*
Y-113292D01*
G01Y-96959D02*
X734691Y-96667D01*
Y-96084D01*
X735128Y-95792D01*
X735565Y-96084D01*
Y-96667D01*
X735128Y-96959D01*
G01X748916Y-113292D02*
Y-101626D01*
G01Y-104542D02*
X749790Y-103084D01*
X751100Y-101917D01*
X752846Y-101626D01*
X754374Y-101917D01*
X755685Y-103084D01*
X756340Y-105125D01*
Y-113292D01*
G01X774058Y-95792D02*
Y-113292D01*
G01Y-110668D02*
X773185Y-112126D01*
X771874Y-113000D01*
X770346Y-113292D01*
X768600Y-112709D01*
X767290Y-111251D01*
X766416Y-109501D01*
X766198Y-107459D01*
X766416Y-105417D01*
X767290Y-103667D01*
X768600Y-102209D01*
X770346Y-101626D01*
X771874Y-101917D01*
X772966Y-102501D01*
X774058Y-103667D01*
G01X805128Y-95792D02*
Y-113292D01*
G01X802071Y-101626D02*
X808185D01*
G01X818916Y-113292D02*
Y-95792D01*
G01Y-104250D02*
X820008Y-102792D01*
X821100Y-101917D01*
X822846Y-101626D01*
X824156Y-101917D01*
X825685Y-103084D01*
X826340Y-104834D01*
Y-113292D01*
G01X836853Y-105417D02*
X843840D01*
X843185Y-103375D01*
X842093Y-102209D01*
X840565Y-101626D01*
X839036Y-101917D01*
X837726Y-102792D01*
X836853Y-104834D01*
X836416Y-106584D01*
Y-108334D01*
X836853Y-110084D01*
X837945Y-111834D01*
X839255Y-113000D01*
X840783Y-113292D01*
X842311Y-112709D01*
X843840Y-110959D01*
G01X870543D02*
X872290Y-112417D01*
X874255Y-113292D01*
X876001D01*
X877748Y-112417D01*
X879058Y-110959D01*
X879713Y-108917D01*
X879276Y-106876D01*
X878185Y-105125D01*
X876220Y-103959D01*
X873600Y-103375D01*
X872071Y-102209D01*
X871416Y-100167D01*
X871853Y-98125D01*
X872945Y-96667D01*
X874473Y-95792D01*
X876001D01*
X877530Y-96375D01*
X878840Y-97834D01*
G01X896995Y-113292D02*
X888261D01*
Y-95792D01*
X896995D01*
G01X893501Y-104250D02*
X888261D01*
G01X927628Y-101626D02*
Y-113292D01*
G01Y-96959D02*
X927191Y-96667D01*
Y-96084D01*
X927628Y-95792D01*
X928065Y-96084D01*
Y-96667D01*
X927628Y-96959D01*
G01X938578Y-113292D02*
Y-101626D01*
G01Y-104834D02*
X939233Y-103375D01*
X940325Y-102209D01*
X941853Y-101626D01*
X943381Y-102209D01*
X944473Y-103375D01*
X945128Y-104834D01*
Y-113292D01*
G01Y-104834D02*
X945783Y-103375D01*
X946874Y-102209D01*
X948403Y-101626D01*
X949931Y-102209D01*
X951023Y-103375D01*
X951678Y-105125D01*
Y-113292D01*
G01X958698Y-119125D02*
Y-101626D01*
G01Y-104250D02*
X959790Y-102792D01*
X960881Y-101917D01*
X962628Y-101626D01*
X964156Y-101917D01*
X965685Y-103375D01*
X966340Y-105417D01*
X966558Y-107459D01*
X966340Y-109501D01*
X965685Y-111542D01*
X964374Y-112709D01*
X962628Y-113292D01*
X961100Y-113000D01*
X959571Y-112126D01*
X958698Y-110959D01*
G01X976853Y-105417D02*
X983840D01*
X983185Y-103375D01*
X982093Y-102209D01*
X980565Y-101626D01*
X979036Y-101917D01*
X977726Y-102792D01*
X976853Y-104834D01*
X976416Y-106584D01*
Y-108334D01*
X976853Y-110084D01*
X977945Y-111834D01*
X979255Y-113000D01*
X980783Y-113292D01*
X982311Y-112709D01*
X983840Y-110959D01*
G01X1001558Y-95792D02*
Y-113292D01*
G01Y-110668D02*
X1000685Y-112126D01*
X999374Y-113000D01*
X997846Y-113292D01*
X996100Y-112709D01*
X994790Y-111251D01*
X993916Y-109501D01*
X993698Y-107459D01*
X993916Y-105417D01*
X994790Y-103667D01*
X996100Y-102209D01*
X997846Y-101626D01*
X999374Y-101917D01*
X1000466Y-102501D01*
X1001558Y-103667D01*
G01X1019058Y-113292D02*
Y-101626D01*
G01Y-103667D02*
X1018185Y-102501D01*
X1016874Y-101917D01*
X1015346Y-101626D01*
X1013818Y-102209D01*
X1012508Y-103375D01*
X1011634Y-105125D01*
X1011198Y-107459D01*
X1011634Y-109792D01*
X1012508Y-111542D01*
X1013818Y-112709D01*
X1015346Y-113292D01*
X1016874Y-113000D01*
X1018185Y-112126D01*
X1019058Y-110959D01*
G01X1028916Y-113292D02*
Y-101626D01*
G01Y-104542D02*
X1029790Y-103084D01*
X1031100Y-101917D01*
X1032846Y-101626D01*
X1034374Y-101917D01*
X1035685Y-103084D01*
X1036340Y-105125D01*
Y-113292D01*
G01X1053621Y-103084D02*
X1052093Y-101917D01*
X1050783Y-101626D01*
X1049036Y-102209D01*
X1047726Y-103375D01*
X1046853Y-105417D01*
X1046634Y-107459D01*
X1046853Y-109501D01*
X1047726Y-111251D01*
X1049036Y-112709D01*
X1050783Y-113292D01*
X1052311Y-112709D01*
X1053621Y-111542D01*
G01X1064353Y-105417D02*
X1071340D01*
X1070685Y-103375D01*
X1069593Y-102209D01*
X1068065Y-101626D01*
X1066536Y-101917D01*
X1065226Y-102792D01*
X1064353Y-104834D01*
X1063916Y-106584D01*
Y-108334D01*
X1064353Y-110084D01*
X1065445Y-111834D01*
X1066755Y-113000D01*
X1068283Y-113292D01*
X1069811Y-112709D01*
X1071340Y-110959D01*
G01X1102628Y-95792D02*
Y-113292D01*
G01X1099571Y-101626D02*
X1105685D01*
G01X1117071Y-113292D02*
Y-101626D01*
G01Y-103959D02*
X1118163Y-102792D01*
X1119255Y-101917D01*
X1120783Y-101626D01*
X1121874Y-101917D01*
X1123185Y-102792D01*
G01X1141558Y-113292D02*
Y-101626D01*
G01Y-103667D02*
X1140685Y-102501D01*
X1139374Y-101917D01*
X1137846Y-101626D01*
X1136318Y-102209D01*
X1135008Y-103375D01*
X1134134Y-105125D01*
X1133698Y-107459D01*
X1134134Y-109792D01*
X1135008Y-111542D01*
X1136318Y-112709D01*
X1137846Y-113292D01*
X1139374Y-113000D01*
X1140685Y-112126D01*
X1141558Y-110959D01*
G01X1158621Y-103084D02*
X1157093Y-101917D01*
X1155783Y-101626D01*
X1154036Y-102209D01*
X1152726Y-103375D01*
X1151853Y-105417D01*
X1151634Y-107459D01*
X1151853Y-109501D01*
X1152726Y-111251D01*
X1154036Y-112709D01*
X1155783Y-113292D01*
X1157311Y-112709D01*
X1158621Y-111542D01*
G01X1169353Y-105417D02*
X1176340D01*
X1175685Y-103375D01*
X1174593Y-102209D01*
X1173065Y-101626D01*
X1171536Y-101917D01*
X1170226Y-102792D01*
X1169353Y-104834D01*
X1168916Y-106584D01*
Y-108334D01*
X1169353Y-110084D01*
X1170445Y-111834D01*
X1171755Y-113000D01*
X1173283Y-113292D01*
X1174811Y-112709D01*
X1176340Y-110959D01*
G01X1186853Y-111251D02*
X1187945Y-112417D01*
X1189473Y-113292D01*
X1190783D01*
X1192093Y-112709D01*
X1192966Y-111834D01*
X1193403Y-110668D01*
X1193185Y-108917D01*
X1192311Y-108042D01*
X1188381Y-106292D01*
X1187508Y-104250D01*
X1187945Y-102792D01*
X1188818Y-101917D01*
X1190128Y-101626D01*
X1191438Y-101917D01*
X1192748Y-102792D01*
G01X1225128Y-101626D02*
Y-113292D01*
G01Y-96959D02*
X1224691Y-96667D01*
Y-96084D01*
X1225128Y-95792D01*
X1225565Y-96084D01*
Y-96667D01*
X1225128Y-96959D01*
G01X1238916Y-113292D02*
Y-101626D01*
G01Y-104542D02*
X1239790Y-103084D01*
X1241100Y-101917D01*
X1242846Y-101626D01*
X1244374Y-101917D01*
X1245685Y-103084D01*
X1246340Y-105125D01*
Y-113292D01*
G01X1277628D02*
Y-95792D01*
G01X1299058Y-113292D02*
Y-101626D01*
G01Y-103667D02*
X1298185Y-102501D01*
X1296874Y-101917D01*
X1295346Y-101626D01*
X1293818Y-102209D01*
X1292508Y-103375D01*
X1291634Y-105125D01*
X1291198Y-107459D01*
X1291634Y-109792D01*
X1292508Y-111542D01*
X1293818Y-112709D01*
X1295346Y-113292D01*
X1296874Y-113000D01*
X1298185Y-112126D01*
X1299058Y-110959D01*
G01X1308043Y-118542D02*
X1309353Y-119125D01*
X1311100Y-118542D01*
X1312191Y-117376D01*
X1313065Y-115917D01*
X1314374Y-111251D01*
X1317213Y-101626D01*
G01X1310226D02*
X1314374Y-111251D01*
G01X1326853Y-105417D02*
X1333840D01*
X1333185Y-103375D01*
X1332093Y-102209D01*
X1330565Y-101626D01*
X1329036Y-101917D01*
X1327726Y-102792D01*
X1326853Y-104834D01*
X1326416Y-106584D01*
Y-108334D01*
X1326853Y-110084D01*
X1327945Y-111834D01*
X1329255Y-113000D01*
X1330783Y-113292D01*
X1332311Y-112709D01*
X1333840Y-110959D01*
G01X1344571Y-113292D02*
Y-101626D01*
G01Y-103959D02*
X1345663Y-102792D01*
X1346755Y-101917D01*
X1348283Y-101626D01*
X1349374Y-101917D01*
X1350685Y-102792D01*
G01X1378261Y-95792D02*
Y-113292D01*
X1386995D01*
G01X1400128D02*
Y-95792D01*
X1397508Y-99292D01*
G01Y-113292D02*
X1402748D01*
G01X1417628Y-113875D02*
X1417191Y-113584D01*
Y-113000D01*
X1417628Y-112709D01*
X1418065Y-113000D01*
Y-113584D01*
X1417628Y-113875D01*
G01X2083125Y539822D02*
X2084434Y538364D01*
X2085963Y537490D01*
X2087928Y537198D01*
X2089893Y537781D01*
X2091421Y538948D01*
X2092513Y540989D01*
X2092731Y543323D01*
X2092295Y545656D01*
X2091203Y547115D01*
X2089674Y548281D01*
X2088146Y548573D01*
X2086618Y548281D01*
X2084653Y547115D01*
X2085308Y554698D01*
X2091203D01*
G01X2105428D02*
X2103681Y554115D01*
X2102371Y552656D01*
X2101498Y550907D01*
X2100843Y548573D01*
X2100625Y545948D01*
X2100843Y543323D01*
X2101498Y540989D01*
X2102371Y539239D01*
X2103681Y537781D01*
X2105428Y537198D01*
X2107174Y537781D01*
X2108485Y539239D01*
X2109358Y540989D01*
X2110013Y543323D01*
X2110231Y545948D01*
X2110013Y548573D01*
X2109358Y550907D01*
X2108485Y552656D01*
X2107174Y554115D01*
X2105428Y554698D01*
G01X2122928Y536615D02*
X2122491Y536906D01*
Y537490D01*
X2122928Y537781D01*
X2123365Y537490D01*
Y536906D01*
X2122928Y536615D01*
G01X2140428Y554698D02*
X2138681Y554115D01*
X2137371Y552656D01*
X2136498Y550907D01*
X2135843Y548573D01*
X2135625Y545948D01*
X2135843Y543323D01*
X2136498Y540989D01*
X2137371Y539239D01*
X2138681Y537781D01*
X2140428Y537198D01*
X2142174Y537781D01*
X2143485Y539239D01*
X2144358Y540989D01*
X2145013Y543323D01*
X2145231Y545948D01*
X2145013Y548573D01*
X2144358Y550907D01*
X2143485Y552656D01*
X2142174Y554115D01*
X2140428Y554698D01*
G01X2090548Y571848D02*
Y589348D01*
X2082469Y576806D01*
X2093387D01*
G01X2105428Y589348D02*
X2103681Y588765D01*
X2102371Y587306D01*
X2101498Y585557D01*
X2100843Y583223D01*
X2100625Y580598D01*
X2100843Y577973D01*
X2101498Y575639D01*
X2102371Y573889D01*
X2103681Y572431D01*
X2105428Y571848D01*
X2107174Y572431D01*
X2108485Y573889D01*
X2109358Y575639D01*
X2110013Y577973D01*
X2110231Y580598D01*
X2110013Y583223D01*
X2109358Y585557D01*
X2108485Y587306D01*
X2107174Y588765D01*
X2105428Y589348D01*
G01X2122928Y571265D02*
X2122491Y571556D01*
Y572140D01*
X2122928Y572431D01*
X2123365Y572140D01*
Y571556D01*
X2122928Y571265D01*
G01X2140428Y589348D02*
X2138681Y588765D01*
X2137371Y587306D01*
X2136498Y585557D01*
X2135843Y583223D01*
X2135625Y580598D01*
X2135843Y577973D01*
X2136498Y575639D01*
X2137371Y573889D01*
X2138681Y572431D01*
X2140428Y571848D01*
X2142174Y572431D01*
X2143485Y573889D01*
X2144358Y575639D01*
X2145013Y577973D01*
X2145231Y580598D01*
X2145013Y583223D01*
X2144358Y585557D01*
X2143485Y587306D01*
X2142174Y588765D01*
X2140428Y589348D01*
G01X2050308Y623998D02*
X2055548D01*
G01X2052928D02*
Y606498D01*
G01X2050308D02*
X2055548D01*
G01X2064751D02*
Y623998D01*
X2070428Y609415D01*
X2076105Y623998D01*
Y606498D01*
G01X2083561D02*
Y623998D01*
X2088801D01*
X2090548Y623123D01*
X2091858Y621081D01*
X2092295Y618748D01*
X2091858Y616415D01*
X2090766Y614665D01*
X2088801Y613789D01*
X2083561D01*
G01X2104336Y600665D02*
X2102153Y603581D01*
X2101061Y606498D01*
Y618164D01*
X2102153Y621081D01*
X2104336Y623998D01*
G01X2122928Y606498D02*
X2121181Y606790D01*
X2119653Y607956D01*
X2118343Y609706D01*
X2117469Y611748D01*
X2117033Y614081D01*
Y616415D01*
X2117469Y618748D01*
X2118343Y620790D01*
X2119653Y622539D01*
X2121181Y623706D01*
X2122928Y623998D01*
X2124674Y623706D01*
X2126203Y622539D01*
X2127513Y620790D01*
X2128387Y618748D01*
X2128823Y616415D01*
Y614081D01*
X2128387Y611748D01*
X2127513Y609706D01*
X2126203Y607956D01*
X2124674Y606790D01*
X2122928Y606498D01*
G01X2136716D02*
Y623998D01*
G01Y615540D02*
X2137808Y616998D01*
X2138900Y617873D01*
X2140646Y618164D01*
X2141956Y617873D01*
X2143485Y616706D01*
X2144140Y614956D01*
Y606498D01*
G01X2151378D02*
Y618164D01*
G01Y614956D02*
X2152033Y616415D01*
X2153125Y617581D01*
X2154653Y618164D01*
X2156181Y617581D01*
X2157273Y616415D01*
X2157928Y614956D01*
Y606498D01*
G01Y614956D02*
X2158583Y616415D01*
X2159674Y617581D01*
X2161203Y618164D01*
X2162731Y617581D01*
X2163823Y616415D01*
X2164478Y614665D01*
Y606498D01*
G01X2176520Y600665D02*
X2178703Y603581D01*
X2179795Y606498D01*
Y618164D01*
X2178703Y621081D01*
X2176520Y623998D01*
G01X2028643Y643481D02*
X2030390Y642023D01*
X2032355Y641148D01*
X2034101D01*
X2035848Y642023D01*
X2037158Y643481D01*
X2037813Y645523D01*
X2037376Y647564D01*
X2036285Y649315D01*
X2034320Y650481D01*
X2031700Y651065D01*
X2030171Y652231D01*
X2029516Y654273D01*
X2029953Y656315D01*
X2031045Y657773D01*
X2032573Y658648D01*
X2034101D01*
X2035630Y658065D01*
X2036940Y656606D01*
G01X2055095Y641148D02*
X2046361D01*
Y658648D01*
X2055095D01*
G01X2051601Y650190D02*
X2046361D01*
G01X2083108Y658648D02*
X2088348D01*
G01X2085728D02*
Y641148D01*
G01X2083108D02*
X2088348D01*
G01X2097551D02*
Y658648D01*
X2103228Y644065D01*
X2108905Y658648D01*
Y641148D01*
G01X2116361D02*
Y658648D01*
X2121601D01*
X2123348Y657773D01*
X2124658Y655731D01*
X2125095Y653398D01*
X2124658Y651065D01*
X2123566Y649315D01*
X2121601Y648439D01*
X2116361D01*
G01X2142595Y641148D02*
X2133861D01*
Y658648D01*
X2142595D01*
G01X2139101Y650190D02*
X2133861D01*
G01X2150925Y641148D02*
Y658648D01*
X2155291D01*
X2157038Y657773D01*
X2158348Y656606D01*
X2159440Y654857D01*
X2160313Y652814D01*
X2160531Y649898D01*
X2160313Y646981D01*
X2159440Y644939D01*
X2158348Y643189D01*
X2157038Y642023D01*
X2155291Y641148D01*
X2150925D01*
G01X2167769D02*
X2173228Y658648D01*
X2178687Y641148D01*
G01X2176721Y647273D02*
X2169734D01*
G01X2185706Y641148D02*
Y658648D01*
X2195750Y641148D01*
Y658648D01*
G01X2213031Y657189D02*
X2211721Y658065D01*
X2210193Y658648D01*
X2208446D01*
X2206481Y657773D01*
X2204953Y656315D01*
X2203861Y654564D01*
X2202988Y651648D01*
X2202769Y649023D01*
X2203206Y646398D01*
X2203861Y644648D01*
X2205171Y642898D01*
X2206700Y641731D01*
X2208228Y641148D01*
X2209756D01*
X2211285Y641731D01*
X2212595Y642606D01*
X2213687Y643772D01*
G01X2230095Y641148D02*
X2221361D01*
Y658648D01*
X2230095D01*
G01X2226601Y650190D02*
X2221361D01*
G01X2260728Y658648D02*
Y641148D01*
G01X2255706Y658648D02*
X2265750D01*
G01X2272769Y641148D02*
X2278228Y658648D01*
X2283687Y641148D01*
G01X2281721Y647273D02*
X2274734D01*
G01X2297474Y650481D02*
X2298348Y651356D01*
X2299003Y652814D01*
X2299440Y654857D01*
X2299003Y656606D01*
X2298130Y657773D01*
X2296601Y658648D01*
X2290706D01*
Y641148D01*
X2297911D01*
X2299440Y642314D01*
X2300313Y644065D01*
X2300750Y646106D01*
X2300313Y648148D01*
X2299003Y649898D01*
X2297474Y650481D01*
X2290706D01*
G01X2308861Y658648D02*
Y641148D01*
X2317595D01*
G01X2335095D02*
X2326361D01*
Y658648D01*
X2335095D01*
G01X2331601Y650190D02*
X2326361D01*
G01X2348228Y640565D02*
X2347791Y640856D01*
Y641440D01*
X2348228Y641731D01*
X2348665Y641440D01*
Y640856D01*
X2348228Y640565D01*
G01Y648439D02*
X2347791Y648731D01*
Y649315D01*
X2348228Y649606D01*
X2348665Y649315D01*
Y648731D01*
X2348228Y648439D01*
G01X2378861Y658648D02*
Y641148D01*
X2387595D01*
G01X2400728D02*
Y658648D01*
X2398108Y655148D01*
G01Y641148D02*
X2403348D01*
G01X2221378Y623998D02*
X2224434Y606498D01*
X2227928Y623998D01*
X2231421Y606498D01*
X2234478Y623998D01*
G01X2242808D02*
X2248048D01*
G01X2245428D02*
Y606498D01*
G01X2242808D02*
X2248048D01*
G01X2258125D02*
Y623998D01*
X2262491D01*
X2264238Y623123D01*
X2265548Y621956D01*
X2266640Y620207D01*
X2267513Y618164D01*
X2267731Y615248D01*
X2267513Y612331D01*
X2266640Y610289D01*
X2265548Y608539D01*
X2264238Y607373D01*
X2262491Y606498D01*
X2258125D01*
G01X2280428Y623998D02*
Y606498D01*
G01X2275406Y623998D02*
X2285450D01*
G01X2293343Y606498D02*
Y623998D01*
G01X2302513D02*
Y606498D01*
G01Y615248D02*
X2293343D01*
G01X2314336Y600665D02*
X2312153Y603581D01*
X2311061Y606498D01*
Y618164D01*
X2312153Y621081D01*
X2314336Y623998D01*
G01X2326378Y606498D02*
Y618164D01*
G01Y614956D02*
X2327033Y616415D01*
X2328125Y617581D01*
X2329653Y618164D01*
X2331181Y617581D01*
X2332273Y616415D01*
X2332928Y614956D01*
Y606498D01*
G01Y614956D02*
X2333583Y616415D01*
X2334674Y617581D01*
X2336203Y618164D01*
X2337731Y617581D01*
X2338823Y616415D01*
X2339478Y614665D01*
Y606498D01*
G01X2350428Y618164D02*
Y606498D01*
G01Y622831D02*
X2349991Y623123D01*
Y623706D01*
X2350428Y623998D01*
X2350865Y623706D01*
Y623123D01*
X2350428Y622831D01*
G01X2367928Y606498D02*
Y623998D01*
G01X2382153Y608539D02*
X2383245Y607373D01*
X2384773Y606498D01*
X2386083D01*
X2387393Y607081D01*
X2388266Y607956D01*
X2388703Y609122D01*
X2388485Y610873D01*
X2387611Y611748D01*
X2383681Y613498D01*
X2382808Y615540D01*
X2383245Y616998D01*
X2384118Y617873D01*
X2385428Y618164D01*
X2386738Y617873D01*
X2388048Y616998D01*
G01X2404020Y600665D02*
X2406203Y603581D01*
X2407295Y606498D01*
Y618164D01*
X2406203Y621081D01*
X2404020Y623998D01*
G01X2291798Y537198D02*
Y554698D01*
X2283719Y542156D01*
X2294637D01*
G01X2306678Y536615D02*
X2306241Y536906D01*
Y537490D01*
X2306678Y537781D01*
X2307115Y537490D01*
Y536906D01*
X2306678Y536615D01*
G01X2320030Y551781D02*
X2321340Y553531D01*
X2322868Y554406D01*
X2324615Y554698D01*
X2326798Y554115D01*
X2328326Y552656D01*
X2328763Y550907D01*
X2328545Y549156D01*
X2327671Y547698D01*
X2323305Y544781D01*
X2321340Y542740D01*
X2320030Y539822D01*
X2319593Y537198D01*
X2328763D01*
G01X2336875Y539822D02*
X2338184Y538364D01*
X2339713Y537490D01*
X2341678Y537198D01*
X2343643Y537781D01*
X2345171Y538948D01*
X2346263Y540989D01*
X2346481Y543323D01*
X2346045Y545656D01*
X2344953Y547115D01*
X2343424Y548281D01*
X2341896Y548573D01*
X2340368Y548281D01*
X2338403Y547115D01*
X2339058Y554698D01*
X2344953D01*
G01X2293780Y579139D02*
X2295308Y581181D01*
X2296618Y582348D01*
X2298365Y582931D01*
X2299893Y582348D01*
X2300985Y581181D01*
X2301858Y579431D01*
X2302076Y577390D01*
X2301858Y575639D01*
X2300985Y573889D01*
X2299674Y572431D01*
X2298146Y571848D01*
X2296400Y572431D01*
X2294871Y574181D01*
X2293998Y576806D01*
X2293780Y579723D01*
X2294216Y583514D01*
X2294871Y585557D01*
X2295963Y587598D01*
X2297491Y589056D01*
X2299020Y589348D01*
X2300548Y588765D01*
X2301640Y587306D01*
G01X2315428Y571265D02*
X2314991Y571556D01*
Y572140D01*
X2315428Y572431D01*
X2315865Y572140D01*
Y571556D01*
X2315428Y571265D01*
G01X2328125Y574472D02*
X2329434Y573014D01*
X2330963Y572140D01*
X2332928Y571848D01*
X2334893Y572431D01*
X2336421Y573598D01*
X2337513Y575639D01*
X2337731Y577973D01*
X2337295Y580306D01*
X2336203Y581765D01*
X2334674Y582931D01*
X2333146Y583223D01*
X2331618Y582931D01*
X2329653Y581765D01*
X2330308Y589348D01*
X2336203D01*
G01X2455428Y623998D02*
Y606498D01*
G01X2450406Y623998D02*
X2460450D01*
G01X2472928Y606498D02*
Y614373D01*
X2468561Y623998D01*
G01X2477295D02*
X2472928Y614373D01*
G01X2486061Y606498D02*
Y623998D01*
X2491301D01*
X2493048Y623123D01*
X2494358Y621081D01*
X2494795Y618748D01*
X2494358Y616415D01*
X2493266Y614665D01*
X2491301Y613789D01*
X2486061D01*
G01X2512295Y606498D02*
X2503561D01*
Y623998D01*
X2512295D01*
G01X2508801Y615540D02*
X2503561D01*
G01X2468343Y539531D02*
X2470090Y538073D01*
X2472055Y537198D01*
X2473801D01*
X2475548Y538073D01*
X2476858Y539531D01*
X2477513Y541573D01*
X2477076Y543614D01*
X2475985Y545365D01*
X2474020Y546531D01*
X2471400Y547115D01*
X2469871Y548281D01*
X2469216Y550323D01*
X2469653Y552365D01*
X2470745Y553823D01*
X2472273Y554698D01*
X2473801D01*
X2475330Y554115D01*
X2476640Y552656D01*
G01X2494795Y537198D02*
X2486061D01*
Y554698D01*
X2494795D01*
G01X2491301Y546240D02*
X2486061D01*
G01X2468343Y574181D02*
X2470090Y572723D01*
X2472055Y571848D01*
X2473801D01*
X2475548Y572723D01*
X2476858Y574181D01*
X2477513Y576223D01*
X2477076Y578264D01*
X2475985Y580015D01*
X2474020Y581181D01*
X2471400Y581765D01*
X2469871Y582931D01*
X2469216Y584973D01*
X2469653Y587015D01*
X2470745Y588473D01*
X2472273Y589348D01*
X2473801D01*
X2475330Y588765D01*
X2476640Y587306D01*
G01X2494795Y571848D02*
X2486061D01*
Y589348D01*
X2494795D01*
G01X2491301Y580890D02*
X2486061D01*
G01X2556061Y606498D02*
Y623998D01*
X2561520D01*
X2563266Y623123D01*
X2564358Y621956D01*
X2564795Y619623D01*
X2564358Y617289D01*
X2563048Y615831D01*
X2561520Y614956D01*
X2556061D01*
G01X2561520D02*
X2564795Y606498D01*
G01X2574653Y614373D02*
X2581640D01*
X2580985Y616415D01*
X2579893Y617581D01*
X2578365Y618164D01*
X2576836Y617873D01*
X2575526Y616998D01*
X2574653Y614956D01*
X2574216Y613206D01*
Y611456D01*
X2574653Y609706D01*
X2575745Y607956D01*
X2577055Y606790D01*
X2578583Y606498D01*
X2580111Y607081D01*
X2581640Y608831D01*
G01X2594118Y606498D02*
Y621373D01*
X2594555Y622831D01*
X2595428Y623706D01*
X2596738Y623998D01*
X2598048Y623415D01*
X2598703Y621956D01*
G01X2596083Y616998D02*
X2591716D01*
G01X2612928Y605915D02*
X2612491Y606206D01*
Y606790D01*
X2612928Y607081D01*
X2613365Y606790D01*
Y606206D01*
X2612928Y605915D01*
G01X2643561Y606498D02*
Y623998D01*
X2648801D01*
X2650548Y623123D01*
X2651858Y621081D01*
X2652295Y618748D01*
X2651858Y616415D01*
X2650766Y614665D01*
X2648801Y613789D01*
X2643561D01*
G01X2665428Y606498D02*
Y623998D01*
G01X2686858Y606498D02*
Y618164D01*
G01Y616123D02*
X2685985Y617289D01*
X2684674Y617873D01*
X2683146Y618164D01*
X2681618Y617581D01*
X2680308Y616415D01*
X2679434Y614665D01*
X2678998Y612331D01*
X2679434Y609998D01*
X2680308Y608248D01*
X2681618Y607081D01*
X2683146Y606498D01*
X2684674Y606790D01*
X2685985Y607664D01*
X2686858Y608831D01*
G01X2696716Y606498D02*
Y618164D01*
G01Y615248D02*
X2697590Y616706D01*
X2698900Y617873D01*
X2700646Y618164D01*
X2702174Y617873D01*
X2703485Y616706D01*
X2704140Y614665D01*
Y606498D01*
G01X2714653Y614373D02*
X2721640D01*
X2720985Y616415D01*
X2719893Y617581D01*
X2718365Y618164D01*
X2716836Y617873D01*
X2715526Y616998D01*
X2714653Y614956D01*
X2714216Y613206D01*
Y611456D01*
X2714653Y609706D01*
X2715745Y607956D01*
X2717055Y606790D01*
X2718583Y606498D01*
X2720111Y607081D01*
X2721640Y608831D01*
G01X2626061Y554698D02*
Y537198D01*
X2634795D01*
G01X2643780Y551781D02*
X2645090Y553531D01*
X2646618Y554406D01*
X2648365Y554698D01*
X2650548Y554115D01*
X2652076Y552656D01*
X2652513Y550907D01*
X2652295Y549156D01*
X2651421Y547698D01*
X2647055Y544781D01*
X2645090Y542740D01*
X2643780Y539822D01*
X2643343Y537198D01*
X2652513D01*
G01X2626061Y589348D02*
Y571848D01*
X2634795D01*
G01X2643780Y586431D02*
X2645090Y588181D01*
X2646618Y589056D01*
X2648365Y589348D01*
X2650548Y588765D01*
X2652076Y587306D01*
X2652513Y585557D01*
X2652295Y583806D01*
X2651421Y582348D01*
X2647055Y579431D01*
X2645090Y577390D01*
X2643780Y574472D01*
X2643343Y571848D01*
X2652513D01*
G01X2835728Y548864D02*
Y537198D01*
G01Y553531D02*
X2835291Y553823D01*
Y554406D01*
X2835728Y554698D01*
X2836165Y554406D01*
Y553823D01*
X2835728Y553531D01*
G01X2849516Y537198D02*
Y548864D01*
G01Y545948D02*
X2850390Y547406D01*
X2851700Y548573D01*
X2853446Y548864D01*
X2854974Y548573D01*
X2856285Y547406D01*
X2856940Y545365D01*
Y537198D01*
G01X2867453Y539239D02*
X2868545Y538073D01*
X2870073Y537198D01*
X2871383D01*
X2872693Y537781D01*
X2873566Y538656D01*
X2874003Y539822D01*
X2873785Y541573D01*
X2872911Y542448D01*
X2868981Y544198D01*
X2868108Y546240D01*
X2868545Y547698D01*
X2869418Y548573D01*
X2870728Y548864D01*
X2872038Y548573D01*
X2873348Y547698D01*
G01X2888228Y548864D02*
Y537198D01*
G01Y553531D02*
X2887791Y553823D01*
Y554406D01*
X2888228Y554698D01*
X2888665Y554406D01*
Y553823D01*
X2888228Y553531D01*
G01X2909658Y554698D02*
Y537198D01*
G01Y539822D02*
X2908785Y538364D01*
X2907474Y537490D01*
X2905946Y537198D01*
X2904200Y537781D01*
X2902890Y539239D01*
X2902016Y540989D01*
X2901798Y543031D01*
X2902016Y545073D01*
X2902890Y546823D01*
X2904200Y548281D01*
X2905946Y548864D01*
X2907474Y548573D01*
X2908566Y547989D01*
X2909658Y546823D01*
G01X2919953Y545073D02*
X2926940D01*
X2926285Y547115D01*
X2925193Y548281D01*
X2923665Y548864D01*
X2922136Y548573D01*
X2920826Y547698D01*
X2919953Y545656D01*
X2919516Y543906D01*
Y542156D01*
X2919953Y540406D01*
X2921045Y538656D01*
X2922355Y537490D01*
X2923883Y537198D01*
X2925411Y537781D01*
X2926940Y539531D01*
G01X2954298Y537198D02*
Y554698D01*
G01Y545948D02*
X2955390Y547698D01*
X2956700Y548573D01*
X2958010Y548864D01*
X2959974Y548281D01*
X2961285Y547115D01*
X2962158Y545073D01*
Y542740D01*
X2961721Y540406D01*
X2960848Y538656D01*
X2959320Y537490D01*
X2958010Y537198D01*
X2956700Y537490D01*
X2955390Y538364D01*
X2954298Y539822D01*
G01X2975728Y537198D02*
X2974418Y537490D01*
X2973108Y538656D01*
X2972234Y540698D01*
X2971798Y543031D01*
X2972234Y545365D01*
X2973108Y547406D01*
X2974418Y548573D01*
X2975728Y548864D01*
X2977038Y548573D01*
X2978348Y547406D01*
X2979221Y545365D01*
X2979440Y543031D01*
X2979221Y540698D01*
X2978348Y538656D01*
X2977038Y537490D01*
X2975728Y537198D01*
G01X2997158D02*
Y548864D01*
G01Y546823D02*
X2996285Y547989D01*
X2994974Y548573D01*
X2993446Y548864D01*
X2991918Y548281D01*
X2990608Y547115D01*
X2989734Y545365D01*
X2989298Y543031D01*
X2989734Y540698D01*
X2990608Y538948D01*
X2991918Y537781D01*
X2993446Y537198D01*
X2994974Y537490D01*
X2996285Y538364D01*
X2997158Y539531D01*
G01X3007671Y537198D02*
Y548864D01*
G01Y546531D02*
X3008763Y547698D01*
X3009855Y548573D01*
X3011383Y548864D01*
X3012474Y548573D01*
X3013785Y547698D01*
G01X3032158Y554698D02*
Y537198D01*
G01Y539822D02*
X3031285Y538364D01*
X3029974Y537490D01*
X3028446Y537198D01*
X3026700Y537781D01*
X3025390Y539239D01*
X3024516Y540989D01*
X3024298Y543031D01*
X3024516Y545073D01*
X3025390Y546823D01*
X3026700Y548281D01*
X3028446Y548864D01*
X3029974Y548573D01*
X3031066Y547989D01*
X3032158Y546823D01*
G01X3063228Y537198D02*
X3061918Y537490D01*
X3060608Y538656D01*
X3059734Y540698D01*
X3059298Y543031D01*
X3059734Y545365D01*
X3060608Y547406D01*
X3061918Y548573D01*
X3063228Y548864D01*
X3064538Y548573D01*
X3065848Y547406D01*
X3066721Y545365D01*
X3066940Y543031D01*
X3066721Y540698D01*
X3065848Y538656D01*
X3064538Y537490D01*
X3063228Y537198D01*
G01X3077016Y548864D02*
Y540698D01*
X3077890Y538656D01*
X3079200Y537490D01*
X3080728Y537198D01*
X3082256Y537490D01*
X3083566Y538656D01*
X3084440Y540698D01*
G01Y537198D02*
Y548864D01*
G01X3098228Y554698D02*
Y537198D01*
G01X3095171Y548864D02*
X3101285D01*
G01X3115728Y537198D02*
Y554698D01*
G01X3133228Y548864D02*
Y537198D01*
G01Y553531D02*
X3132791Y553823D01*
Y554406D01*
X3133228Y554698D01*
X3133665Y554406D01*
Y553823D01*
X3133228Y553531D01*
G01X3147016Y537198D02*
Y548864D01*
G01Y545948D02*
X3147890Y547406D01*
X3149200Y548573D01*
X3150946Y548864D01*
X3152474Y548573D01*
X3153785Y547406D01*
X3154440Y545365D01*
Y537198D01*
G01X3164953Y545073D02*
X3171940D01*
X3171285Y547115D01*
X3170193Y548281D01*
X3168665Y548864D01*
X3167136Y548573D01*
X3165826Y547698D01*
X3164953Y545656D01*
X3164516Y543906D01*
Y542156D01*
X3164953Y540406D01*
X3166045Y538656D01*
X3167355Y537490D01*
X3168883Y537198D01*
X3170411Y537781D01*
X3171940Y539531D01*
G01X3185728Y536615D02*
X3185291Y536906D01*
Y537490D01*
X3185728Y537781D01*
X3186165Y537490D01*
Y536906D01*
X3185728Y536615D01*
G01X2835728Y583514D02*
Y571848D01*
G01Y588181D02*
X2835291Y588473D01*
Y589056D01*
X2835728Y589348D01*
X2836165Y589056D01*
Y588473D01*
X2835728Y588181D01*
G01X2849953Y573889D02*
X2851045Y572723D01*
X2852573Y571848D01*
X2853883D01*
X2855193Y572431D01*
X2856066Y573306D01*
X2856503Y574472D01*
X2856285Y576223D01*
X2855411Y577098D01*
X2851481Y578848D01*
X2850608Y580890D01*
X2851045Y582348D01*
X2851918Y583223D01*
X2853228Y583514D01*
X2854538Y583223D01*
X2855848Y582348D01*
G01X2883206Y571848D02*
Y589348D01*
X2893250Y571848D01*
Y589348D01*
G01X2905728Y571848D02*
X2903981Y572140D01*
X2902453Y573306D01*
X2901143Y575056D01*
X2900269Y577098D01*
X2899833Y579431D01*
Y581765D01*
X2900269Y584098D01*
X2901143Y586140D01*
X2902453Y587889D01*
X2903981Y589056D01*
X2905728Y589348D01*
X2907474Y589056D01*
X2909003Y587889D01*
X2910313Y586140D01*
X2911187Y584098D01*
X2911623Y581765D01*
Y579431D01*
X2911187Y577098D01*
X2910313Y575056D01*
X2909003Y573306D01*
X2907474Y572140D01*
X2905728Y571848D01*
G01X2923228Y589348D02*
Y571848D01*
G01X2918206Y589348D02*
X2928250D01*
G01X2954516Y583514D02*
Y575348D01*
X2955390Y573306D01*
X2956700Y572140D01*
X2958228Y571848D01*
X2959756Y572140D01*
X2961066Y573306D01*
X2961940Y575348D01*
G01Y571848D02*
Y583514D01*
G01X2972453Y573889D02*
X2973545Y572723D01*
X2975073Y571848D01*
X2976383D01*
X2977693Y572431D01*
X2978566Y573306D01*
X2979003Y574472D01*
X2978785Y576223D01*
X2977911Y577098D01*
X2973981Y578848D01*
X2973108Y580890D01*
X2973545Y582348D01*
X2974418Y583223D01*
X2975728Y583514D01*
X2977038Y583223D01*
X2978348Y582348D01*
G01X2989953Y579723D02*
X2996940D01*
X2996285Y581765D01*
X2995193Y582931D01*
X2993665Y583514D01*
X2992136Y583223D01*
X2990826Y582348D01*
X2989953Y580306D01*
X2989516Y578556D01*
Y576806D01*
X2989953Y575056D01*
X2991045Y573306D01*
X2992355Y572140D01*
X2993883Y571848D01*
X2995411Y572431D01*
X2996940Y574181D01*
G01X3014658Y589348D02*
Y571848D01*
G01Y574472D02*
X3013785Y573014D01*
X3012474Y572140D01*
X3010946Y571848D01*
X3009200Y572431D01*
X3007890Y573889D01*
X3007016Y575639D01*
X3006798Y577681D01*
X3007016Y579723D01*
X3007890Y581473D01*
X3009200Y582931D01*
X3010946Y583514D01*
X3012474Y583223D01*
X3013566Y582639D01*
X3014658Y581473D01*
G01X3045728Y583514D02*
Y571848D01*
G01Y588181D02*
X3045291Y588473D01*
Y589056D01*
X3045728Y589348D01*
X3046165Y589056D01*
Y588473D01*
X3045728Y588181D01*
G01X3059516Y571848D02*
Y583514D01*
G01Y580598D02*
X3060390Y582056D01*
X3061700Y583223D01*
X3063446Y583514D01*
X3064974Y583223D01*
X3066285Y582056D01*
X3066940Y580015D01*
Y571848D01*
G01X3098228Y589348D02*
Y571848D01*
G01X3095171Y583514D02*
X3101285D01*
G01X3112016Y571848D02*
Y589348D01*
G01Y580890D02*
X3113108Y582348D01*
X3114200Y583223D01*
X3115946Y583514D01*
X3117256Y583223D01*
X3118785Y582056D01*
X3119440Y580306D01*
Y571848D01*
G01X3133228Y583514D02*
Y571848D01*
G01Y588181D02*
X3132791Y588473D01*
Y589056D01*
X3133228Y589348D01*
X3133665Y589056D01*
Y588473D01*
X3133228Y588181D01*
G01X3147453Y573889D02*
X3148545Y572723D01*
X3150073Y571848D01*
X3151383D01*
X3152693Y572431D01*
X3153566Y573306D01*
X3154003Y574472D01*
X3153785Y576223D01*
X3152911Y577098D01*
X3148981Y578848D01*
X3148108Y580890D01*
X3148545Y582348D01*
X3149418Y583223D01*
X3150728Y583514D01*
X3152038Y583223D01*
X3153348Y582348D01*
G01X3185728Y571848D02*
Y589348D01*
G01X3207158Y571848D02*
Y583514D01*
G01Y581473D02*
X3206285Y582639D01*
X3204974Y583223D01*
X3203446Y583514D01*
X3201918Y582931D01*
X3200608Y581765D01*
X3199734Y580015D01*
X3199298Y577681D01*
X3199734Y575348D01*
X3200608Y573598D01*
X3201918Y572431D01*
X3203446Y571848D01*
X3204974Y572140D01*
X3206285Y573014D01*
X3207158Y574181D01*
G01X3216143Y566598D02*
X3217453Y566015D01*
X3219200Y566598D01*
X3220291Y567764D01*
X3221165Y569223D01*
X3222474Y573889D01*
X3225313Y583514D01*
G01X3218326D02*
X3222474Y573889D01*
G01X3234953Y579723D02*
X3241940D01*
X3241285Y581765D01*
X3240193Y582931D01*
X3238665Y583514D01*
X3237136Y583223D01*
X3235826Y582348D01*
X3234953Y580306D01*
X3234516Y578556D01*
Y576806D01*
X3234953Y575056D01*
X3236045Y573306D01*
X3237355Y572140D01*
X3238883Y571848D01*
X3240411Y572431D01*
X3241940Y574181D01*
G01X3252671Y571848D02*
Y583514D01*
G01Y581181D02*
X3253763Y582348D01*
X3254855Y583223D01*
X3256383Y583514D01*
X3257474Y583223D01*
X3258785Y582348D01*
G01X2760925Y605915D02*
X2770531Y618748D01*
G01X2765728Y621081D02*
Y603581D01*
G01X2770531Y605915D02*
X2760925Y618748D01*
G01X2759178Y612331D02*
X2772278D01*
G01X2797890D02*
X2803566D01*
G01X2830925Y606498D02*
Y623998D01*
X2835291D01*
X2837038Y623123D01*
X2838348Y621956D01*
X2839440Y620207D01*
X2840313Y618164D01*
X2840531Y615248D01*
X2840313Y612331D01*
X2839440Y610289D01*
X2838348Y608539D01*
X2837038Y607373D01*
X2835291Y606498D01*
X2830925D01*
G01X2849953Y614373D02*
X2856940D01*
X2856285Y616415D01*
X2855193Y617581D01*
X2853665Y618164D01*
X2852136Y617873D01*
X2850826Y616998D01*
X2849953Y614956D01*
X2849516Y613206D01*
Y611456D01*
X2849953Y609706D01*
X2851045Y607956D01*
X2852355Y606790D01*
X2853883Y606498D01*
X2855411Y607081D01*
X2856940Y608831D01*
G01X2867016Y606498D02*
Y618164D01*
G01Y615248D02*
X2867890Y616706D01*
X2869200Y617873D01*
X2870946Y618164D01*
X2872474Y617873D01*
X2873785Y616706D01*
X2874440Y614665D01*
Y606498D01*
G01X2888228D02*
X2886918Y606790D01*
X2885608Y607956D01*
X2884734Y609998D01*
X2884298Y612331D01*
X2884734Y614665D01*
X2885608Y616706D01*
X2886918Y617873D01*
X2888228Y618164D01*
X2889538Y617873D01*
X2890848Y616706D01*
X2891721Y614665D01*
X2891940Y612331D01*
X2891721Y609998D01*
X2890848Y607956D01*
X2889538Y606790D01*
X2888228Y606498D01*
G01X2905728Y623998D02*
Y606498D01*
G01X2902671Y618164D02*
X2908785D01*
G01X2919953Y614373D02*
X2926940D01*
X2926285Y616415D01*
X2925193Y617581D01*
X2923665Y618164D01*
X2922136Y617873D01*
X2920826Y616998D01*
X2919953Y614956D01*
X2919516Y613206D01*
Y611456D01*
X2919953Y609706D01*
X2921045Y607956D01*
X2922355Y606790D01*
X2923883Y606498D01*
X2925411Y607081D01*
X2926940Y608831D01*
G01X2937453Y608539D02*
X2938545Y607373D01*
X2940073Y606498D01*
X2941383D01*
X2942693Y607081D01*
X2943566Y607956D01*
X2944003Y609122D01*
X2943785Y610873D01*
X2942911Y611748D01*
X2938981Y613498D01*
X2938108Y615540D01*
X2938545Y616998D01*
X2939418Y617873D01*
X2940728Y618164D01*
X2942038Y617873D01*
X2943348Y616998D01*
G01X2975728Y623998D02*
Y606498D01*
G01X2972671Y618164D02*
X2978785D01*
G01X2989516Y606498D02*
Y623998D01*
G01Y615540D02*
X2990608Y616998D01*
X2991700Y617873D01*
X2993446Y618164D01*
X2994756Y617873D01*
X2996285Y616706D01*
X2996940Y614956D01*
Y606498D01*
G01X3014658D02*
Y618164D01*
G01Y616123D02*
X3013785Y617289D01*
X3012474Y617873D01*
X3010946Y618164D01*
X3009418Y617581D01*
X3008108Y616415D01*
X3007234Y614665D01*
X3006798Y612331D01*
X3007234Y609998D01*
X3008108Y608248D01*
X3009418Y607081D01*
X3010946Y606498D01*
X3012474Y606790D01*
X3013785Y607664D01*
X3014658Y608831D01*
G01X3028228Y623998D02*
Y606498D01*
G01X3025171Y618164D02*
X3031285D01*
G01X3056678Y623998D02*
X3059734Y606498D01*
X3063228Y623998D01*
X3066721Y606498D01*
X3069778Y623998D01*
G01X3078108D02*
X3083348D01*
G01X3080728D02*
Y606498D01*
G01X3078108D02*
X3083348D01*
G01X3093425D02*
Y623998D01*
X3097791D01*
X3099538Y623123D01*
X3100848Y621956D01*
X3101940Y620207D01*
X3102813Y618164D01*
X3103031Y615248D01*
X3102813Y612331D01*
X3101940Y610289D01*
X3100848Y608539D01*
X3099538Y607373D01*
X3097791Y606498D01*
X3093425D01*
G01X3115728Y623998D02*
Y606498D01*
G01X3110706Y623998D02*
X3120750D01*
G01X3128643Y606498D02*
Y623998D01*
G01X3137813D02*
Y606498D01*
G01Y615248D02*
X3128643D01*
G01X-7874Y-31496D02*
X-19685D01*
G01X-7874D02*
X-19685D01*
G01D02*
G03X-23622Y-35433I0J-3937D01*
G01D02*
Y-59055D01*
G01Y-35433D02*
Y-59055D01*
G01X-19685Y-31496D02*
G03X-23622Y-35433I0J-3937D01*
G01Y-59055D02*
G03X-19685Y-62992I3937J0D01*
G01D02*
X1972441D01*
G01X-19685D02*
X1972441D01*
G01X-23622Y-59055D02*
G03X-19685Y-62992I3937J0D01*
G01Y-23622D02*
X1972441D01*
G01X-19685D02*
X1972441D01*
G01X-19685D02*
X1972441D01*
G01X-19685D02*
X1972441D01*
G01X-23622Y622441D02*
Y-19685D01*
G01Y622441D02*
Y-19685D01*
G01Y622441D02*
Y-19685D01*
G01Y622441D02*
Y-19685D01*
G01D02*
G03X-19685Y-23622I3937J0D01*
G01X-23622Y-19685D02*
G03X-19685Y-23622I3937J0D01*
G01X-23622Y-19685D02*
G03X-19685Y-23622I3937J0D01*
G01X-23622Y-19685D02*
G03X-19685Y-23622I3937J0D01*
G01X1972441Y626378D02*
X-19685D01*
G01X1972441D02*
X-19685D01*
G01X1972441D02*
X-19685D01*
G01X1972441D02*
X-19685D01*
G01D02*
G03X-23622Y622441I0J-3937D01*
G01X-19685Y626378D02*
G03X-23622Y622441I0J-3937D01*
G01X-19685Y626378D02*
G03X-23622Y622441I0J-3937D01*
G01X-19685Y626378D02*
G03X-23622Y622441I0J-3937D01*
G01X-19685Y634252D02*
X-7874D01*
G01X-19685D02*
X-7874D01*
G01X-23622Y661811D02*
Y638189D01*
G01Y661811D02*
Y638189D01*
G01D02*
G03X-19685Y634252I3937J0D01*
G01X-23622Y638189D02*
G03X-19685Y634252I3937J0D01*
G01X1972441Y665748D02*
X-19685D01*
G01X1972441D02*
X-19685D01*
G01D02*
G03X-23622Y661811I0J-3937D01*
G01X-19685Y665748D02*
G03X-23622Y661811I0J-3937D01*
G01X-7874Y-31496D02*
G03Y-23622I0J3937D01*
G01Y-31496D02*
G03Y-23622I0J3937D01*
G01X22835D02*
G03Y-31496I0J-3937D01*
G01X137795D02*
X22835D01*
G01X137795D02*
X22835D01*
G01Y-23622D02*
G03Y-31496I0J-3937D01*
G01X0Y616535D02*
G03Y604724I0J-5905D01*
G01Y616535D02*
G03Y604724I0J-5905D01*
G01Y616535D02*
X2646D01*
G01X2644D02*
X0D01*
G01Y604724D02*
X2644D01*
G01X2646D02*
X0D01*
G01X2646D02*
X0D01*
G01D02*
X2644D01*
G01Y616535D02*
X0D01*
G01D02*
X2646D01*
G01X0D02*
G03Y604724I0J-5905D01*
G01Y616535D02*
G03Y604724I0J-5905D01*
G01X2646Y616535D02*
G03X7595Y618285I0J7874D01*
G01X2644Y616535D02*
G03X7593Y618285I0J7874D01*
G01X2644Y616535D02*
G03X7593Y618285I0J7874D01*
G01X7595Y602975D02*
G03X2646Y604724I-4948J-6125D01*
G01X7593Y602975D02*
G03X2644Y604724I-4948J-6125D01*
G01X7593Y602975D02*
G03X2644Y604724I-4948J-6125D01*
G01X7593Y602975D02*
G03X2644Y604724I-4948J-6125D01*
G01X7593Y602975D02*
G03X2644Y604724I-4948J-6125D01*
G01X7595Y602975D02*
G03X2646Y604724I-4948J-6125D01*
G01X2644Y616535D02*
G03X7593Y618285I0J7874D01*
G01X2644Y616535D02*
G03X7593Y618285I0J7874D01*
G01X2646Y616535D02*
G03X7595Y618285I0J7874D01*
G01Y602975D02*
G03Y618285I6186J7655D01*
G01X7593Y602975D02*
G03Y618285I6187J7655D01*
G01Y602975D02*
G03Y618285I6187J7655D01*
G01Y602975D02*
G03Y618285I6187J7655D01*
G01Y602975D02*
G03Y618285I6187J7655D01*
G01X7595Y602975D02*
G03Y618285I6186J7655D01*
G01X-7874Y626378D02*
G03Y634252I0J3937D01*
G01Y626378D02*
G03Y634252I0J3937D01*
G01X22835D02*
G03Y626378I0J-3937D01*
G01Y634252D02*
X137795D01*
G01X22835D02*
X137795D01*
G01X22835D02*
G03Y626378I0J-3937D01*
G01X168504Y-23622D02*
G03Y-31496I0J-3937D01*
G01X137795D02*
G03Y-23622I0J3937D01*
G01X341732Y-31496D02*
X168504D01*
G01X341732D02*
X168504D01*
G01X137795D02*
G03Y-23622I0J3937D01*
G01X168504D02*
G03Y-31496I0J-3937D01*
G01Y634252D02*
G03Y626378I0J-3937D01*
G01X137795D02*
G03Y634252I0J3937D01*
G01X168504D02*
X341732D01*
G01X168504D02*
X341732D01*
G01X137795Y626378D02*
G03Y634252I0J3937D01*
G01X168504D02*
G03Y626378I0J-3937D01*
G01X341732Y-31496D02*
G03Y-23622I0J3937D01*
G01Y-31496D02*
G03Y-23622I0J3937D01*
G01Y626378D02*
G03Y634252I0J3937D01*
G01Y626378D02*
G03Y634252I0J3937D01*
G01X372441Y-23622D02*
G03Y-31496I0J-3937D01*
G01X529921D02*
X372441D01*
G01X529921D02*
X372441D01*
G01Y-23622D02*
G03Y-31496I0J-3937D01*
G01Y634252D02*
G03Y626378I0J-3937D01*
G01Y634252D02*
X529921D01*
G01X372441D02*
X529921D01*
G01X372441D02*
G03Y626378I0J-3937D01*
G01X529921Y-31496D02*
G03Y-23622I0J3937D01*
G01Y-31496D02*
G03Y-23622I0J3937D01*
G01Y626378D02*
G03Y634252I0J3937D01*
G01Y626378D02*
G03Y634252I0J3937D01*
G01X560630Y-23622D02*
G03Y-31496I0J-3937D01*
G01X788976D02*
X560630D01*
G01X788976D02*
X560630D01*
G01Y-23622D02*
G03Y-31496I0J-3937D01*
G01Y634252D02*
G03Y626378I0J-3937D01*
G01Y634252D02*
X788976D01*
G01X560630D02*
X788976D01*
G01X560630D02*
G03Y626378I0J-3937D01*
G01X684760Y-15529D02*
G03Y-219I6187J7655D01*
G01X684759Y-15529D02*
G03X679809Y-13780I-4948J-6125D01*
G01X679811Y-1969D02*
G03X684760Y-219I0J7874D01*
G01X677165Y-1969D02*
X679811D01*
G01X677165D02*
G03Y-13780I0J-5906D01*
G01D02*
X679809D01*
G01X684760Y602975D02*
G03Y618285I6187J7655D01*
G01X684759Y602975D02*
G03Y618285I6186J7655D01*
G01Y602975D02*
G03Y618285I6186J7655D01*
G01Y602975D02*
G03Y618285I6186J7655D01*
G01Y602975D02*
G03Y618285I6186J7655D01*
G01X684760Y602975D02*
G03Y618285I6187J7655D01*
G01X679811Y616535D02*
G03X684760Y618285I0J7874D01*
G01X679809Y616535D02*
G03X684759Y618285I0J7874D01*
G01X679809Y616535D02*
G03X684759Y618285I0J7874D01*
G01X684760Y602975D02*
G03X679811Y604724I-4948J-6125D01*
G01X684759Y602975D02*
G03X679809Y604724I-4948J-6125D01*
G01X684759Y602975D02*
G03X679809Y604724I-4948J-6125D01*
G01X684759Y602975D02*
G03X679809Y604724I-4948J-6125D01*
G01X684759Y602975D02*
G03X679809Y604724I-4948J-6125D01*
G01X684760Y602975D02*
G03X679811Y604724I-4948J-6125D01*
G01X679809Y616535D02*
G03X684759Y618285I0J7874D01*
G01X679809Y616535D02*
G03X684759Y618285I0J7874D01*
G01X679811Y616535D02*
G03X684760Y618285I0J7874D01*
G01X677165Y616535D02*
X679811D01*
G01X677165D02*
G03Y604724I0J-5905D01*
G01D02*
X679809D01*
G01X788976Y-31496D02*
G03Y-23622I0J3937D01*
G01Y-31496D02*
G03Y-23622I0J3937D01*
G01X819685D02*
G03Y-31496I0J-3937D01*
G01X975591D02*
X819685D01*
G01X975591D02*
X819685D01*
G01Y-23622D02*
G03Y-31496I0J-3937D01*
G01X788976Y626378D02*
G03Y634252I0J3937D01*
G01Y626378D02*
G03Y634252I0J3937D01*
G01X819685D02*
G03Y626378I0J-3937D01*
G01Y634252D02*
X975591D01*
G01X819685D02*
X975591D01*
G01X819685D02*
G03Y626378I0J-3937D01*
G01X975591Y-31496D02*
G03Y-23622I0J3937D01*
G01Y-31496D02*
G03Y-23622I0J3937D01*
G01X1006299D02*
G03Y-31496I0J-3937D01*
G01X1162205D02*
X1006299D01*
G01X1162205D02*
X1006299D01*
G01Y-23622D02*
G03Y-31496I0J-3937D01*
G01Y634252D02*
X1162205D01*
G01X1006299D02*
X1162205D01*
G01X975591Y626378D02*
G03Y634252I0J3937D01*
G01Y626378D02*
G03Y634252I0J3937D01*
G01X1006299D02*
G03Y626378I0J-3937D01*
G01Y634252D02*
G03Y626378I0J-3937D01*
G01X1162205Y-31496D02*
G03Y-23622I0J3937D01*
G01Y-31496D02*
G03Y-23622I0J3937D01*
G01X1192913D02*
G03Y-31496I0J-3937D01*
G01X1398425D02*
X1192913D01*
G01X1398425D02*
X1192913D01*
G01Y-23622D02*
G03Y-31496I0J-3937D01*
G01Y634252D02*
X1394488D01*
G01X1192913D02*
X1394488D01*
G01X1162205Y626378D02*
G03Y634252I0J3937D01*
G01Y626378D02*
G03Y634252I0J3937D01*
G01X1192913D02*
G03Y626378I0J-3937D01*
G01Y634252D02*
G03Y626378I0J-3937D01*
G01X1398425Y-31496D02*
G03Y-23622I0J3937D01*
G01Y-31496D02*
G03Y-23622I0J3937D01*
G01X1405512Y-1968D02*
G03Y-13779I0J-5906D01*
G01Y-1968D02*
G03Y-13779I0J-5906D01*
G01Y-1968D02*
G03Y-13779I0J-5906D01*
G01Y-1968D02*
G03Y-13779I0J-5906D01*
G01X1394488Y626378D02*
G03Y634252I0J3937D01*
G01Y626378D02*
G03Y634252I0J3937D01*
G01X1405512Y616535D02*
G03Y604724I0J-5905D01*
G01Y616535D02*
G03Y604724I0J-5905D01*
G01Y616535D02*
G03Y604724I0J-5905D01*
G01Y616535D02*
G03Y604724I0J-5905D01*
G01X1429134Y-23622D02*
G03Y-31496I0J-3937D01*
G01X1851181D02*
X1429134D01*
G01X1851181D02*
X1429134D01*
G01Y-23622D02*
G03Y-31496I0J-3937D01*
G01X1413107Y-15529D02*
G03Y-218I6186J7655D01*
G01X1413105Y-15529D02*
G03Y-218I6186J7655D01*
G01Y-15529D02*
G03Y-218I6186J7655D01*
G01Y-15529D02*
G03Y-218I6186J7655D01*
G01Y-15529D02*
G03Y-218I6186J7655D01*
G01X1413107Y-15529D02*
G03Y-218I6186J7655D01*
G01X1408157Y-1968D02*
G03X1413107Y-218I1J7874D01*
G01X1408156Y-1968D02*
G03X1413105Y-218I0J7874D01*
G01X1408156Y-1968D02*
G03X1413105Y-218I0J7874D01*
G01X1408156Y-1968D02*
G03X1413105Y-218I0J7874D01*
G01X1408156Y-1968D02*
G03X1413105Y-218I0J7874D01*
G01X1408157Y-1968D02*
G03X1413107Y-218I1J7874D01*
G01Y-15529D02*
G03X1408157Y-13779I-4949J-6124D01*
G01X1413105Y-15529D02*
G03X1408156Y-13779I-4949J-6124D01*
G01X1413105Y-15529D02*
G03X1408156Y-13779I-4949J-6124D01*
G01X1413105Y-15529D02*
G03X1408156Y-13779I-4949J-6124D01*
G01X1413105Y-15529D02*
G03X1408156Y-13779I-4949J-6124D01*
G01X1413107Y-15529D02*
G03X1408157Y-13779I-4949J-6124D01*
G01X1405512D02*
X1408156D01*
G01X1408157D02*
X1405512D01*
G01X1408157D02*
X1405512D01*
G01D02*
X1408156D01*
G01X1405512Y-1968D02*
X1408157D01*
G01X1408156D02*
X1405512D01*
G01X1408156D02*
X1405512D01*
G01D02*
X1408157D01*
G01X1425197Y634252D02*
X1851181D01*
G01X1425197D02*
X1851181D01*
G01X1425197D02*
G03Y626378I0J-3937D01*
G01Y634252D02*
G03Y626378I0J-3937D01*
G01X1408157Y616535D02*
G03X1413107Y618285I1J7874D01*
G01X1408156Y616535D02*
G03X1413105Y618285I0J7874D01*
G01X1408156Y616535D02*
G03X1413105Y618285I0J7874D01*
G01X1413107Y602975D02*
G03Y618285I6186J7655D01*
G01X1413105Y602975D02*
G03Y618285I6187J7655D01*
G01Y602975D02*
G03Y618285I6187J7655D01*
G01X1413107Y602975D02*
G03X1408157Y604724I-4948J-6125D01*
G01X1413105Y602975D02*
G03X1408156Y604724I-4948J-6125D01*
G01X1413105Y602975D02*
G03X1408156Y604724I-4948J-6125D01*
G01X1413105Y602975D02*
G03X1408156Y604724I-4948J-6125D01*
G01X1413105Y602975D02*
G03X1408156Y604724I-4948J-6125D01*
G01X1413107Y602975D02*
G03X1408157Y604724I-4948J-6125D01*
G01X1413105Y602975D02*
G03Y618285I6187J7655D01*
G01Y602975D02*
G03Y618285I6187J7655D01*
G01X1413107Y602975D02*
G03Y618285I6186J7655D01*
G01X1408156Y616535D02*
G03X1413105Y618285I0J7874D01*
G01X1408156Y616535D02*
G03X1413105Y618285I0J7874D01*
G01X1408157Y616535D02*
G03X1413107Y618285I1J7874D01*
G01X1405512Y616535D02*
X1408157D01*
G01X1408156D02*
X1405512D01*
G01Y604724D02*
X1408156D01*
G01X1408157D02*
X1405512D01*
G01X1408157D02*
X1405512D01*
G01D02*
X1408156D01*
G01Y616535D02*
X1405512D01*
G01D02*
X1408157D01*
G01X1685866Y267244D02*
X1883780D01*
G01X1685866D02*
X1883780D01*
G01X1685866D02*
X1883780D01*
G01X1685866D02*
X1883780D01*
G01X1681929Y271181D02*
G03X1685866Y267244I3937J0D01*
G01X1681929Y271181D02*
G03X1685866Y267244I3937J0D01*
G01X1681929Y271181D02*
G03X1685866Y267244I3937J0D01*
G01X1681929Y271181D02*
G03X1685866Y267244I3937J0D01*
G01X1681929Y428661D02*
Y271181D01*
G01Y428661D02*
Y271181D01*
G01Y428661D02*
Y271181D01*
G01Y428661D02*
Y271181D01*
G01X1685866Y432598D02*
G03X1681929Y428661I0J-3937D01*
G01X1685866Y432598D02*
G03X1681929Y428661I0J-3937D01*
G01X1972441Y432598D02*
X1685866D01*
G01X1972441D02*
X1685866D01*
G01X1972441D02*
X1685866D01*
G01X1972441D02*
X1685866D01*
G01D02*
G03X1681929Y428661I0J-3937D01*
G01X1685866Y432598D02*
G03X1681929Y428661I0J-3937D01*
G01X1851181Y-31496D02*
G03Y-23622I0J3937D01*
G01Y-31496D02*
G03Y-23622I0J3937D01*
G01X1881890D02*
G03Y-31496I0J-3937D01*
G01X1972441D02*
X1881890D01*
G01X1972441D02*
X1881890D01*
G01Y-23622D02*
G03Y-31496I0J-3937D01*
G01X1861926Y-15529D02*
G03X1856976Y-13780I-4948J-6125D01*
G01X1861924Y-15529D02*
G03X1856975Y-13780I-4948J-6125D01*
G01X1861924Y-15529D02*
G03X1856975Y-13780I-4948J-6125D01*
G01X1861924Y-15529D02*
G03X1856975Y-13780I-4948J-6125D01*
G01X1861924Y-15529D02*
G03X1856975Y-13780I-4948J-6125D01*
G01X1861926Y-15529D02*
G03X1856976Y-13780I-4948J-6125D01*
G01Y-1969D02*
G03X1861926Y-219I0J7874D01*
G01X1856975Y-1969D02*
G03X1861924Y-219I0J7874D01*
G01X1856975Y-1969D02*
G03X1861924Y-219I0J7874D01*
G01X1861926Y-15529D02*
G03Y-219I6186J7655D01*
G01X1861924Y-15529D02*
G03Y-219I6186J7655D01*
G01Y-15529D02*
G03Y-219I6186J7655D01*
G01Y-15529D02*
G03Y-219I6186J7655D01*
G01Y-15529D02*
G03Y-219I6186J7655D01*
G01X1861926Y-15529D02*
G03Y-219I6186J7655D01*
G01X1856975Y-1969D02*
G03X1861924Y-219I0J7874D01*
G01X1856975Y-1969D02*
G03X1861924Y-219I0J7874D01*
G01X1856976Y-1969D02*
G03X1861926Y-219I0J7874D01*
G01X1854331Y-1969D02*
G03Y-13780I0J-5906D01*
G01Y-1969D02*
G03Y-13780I0J-5906D01*
G01D02*
X1856975D01*
G01X1856976D02*
X1854331D01*
G01X1856976D02*
X1854331D01*
G01D02*
X1856975D01*
G01X1854331Y-1969D02*
G03Y-13780I0J-5906D01*
G01Y-1969D02*
G03Y-13780I0J-5906D01*
G01Y-1969D02*
X1856976D01*
G01X1856975D02*
X1854331D01*
G01X1856975D02*
X1854331D01*
G01D02*
X1856976D01*
G01X1891654Y246772D02*
X1972441D01*
G01X1891654D02*
X1972441D01*
G01X1891654D02*
X1972441D01*
G01X1891654D02*
X1972441D01*
G01X1887717Y250709D02*
G03X1891654Y246772I3937J0D01*
G01X1887717Y250709D02*
G03X1891654Y246772I3937J0D01*
G01X1887717Y263307D02*
Y250709D01*
G01Y263307D02*
Y250709D01*
G01Y263307D02*
Y250709D01*
G01Y263307D02*
Y250709D01*
G01D02*
G03X1891654Y246772I3937J0D01*
G01X1887717Y250709D02*
G03X1891654Y246772I3937J0D01*
G01X1887717Y263307D02*
G03X1883780Y267244I-3937J0D01*
G01X1887717Y263307D02*
G03X1883780Y267244I-3937J0D01*
G01X1887717Y263307D02*
G03X1883780Y267244I-3937J0D01*
G01X1887717Y263307D02*
G03X1883780Y267244I-3937J0D01*
G01X1881890Y634252D02*
G03Y626378I0J-3937D01*
G01Y634252D02*
X1972441D01*
G01X1881890D02*
X1972441D01*
G01X1881890D02*
G03Y626378I0J-3937D01*
G01X1851181D02*
G03Y634252I0J3937D01*
G01Y626378D02*
G03Y634252I0J3937D01*
G01X1856976Y616535D02*
G03X1861926Y618285I0J7874D01*
G01X1856975Y616535D02*
G03X1861924Y618285I0J7874D01*
G01X1856975Y616535D02*
G03X1861924Y618285I0J7874D01*
G01X1861926Y602975D02*
G03Y618285I6186J7655D01*
G01X1861924Y602975D02*
G03Y618285I6186J7655D01*
G01Y602975D02*
G03Y618285I6186J7655D01*
G01Y602975D02*
G03Y618285I6186J7655D01*
G01Y602975D02*
G03Y618285I6186J7655D01*
G01X1861926Y602975D02*
G03Y618285I6186J7655D01*
G01X1856975Y616535D02*
G03X1861924Y618285I0J7874D01*
G01X1856975Y616535D02*
G03X1861924Y618285I0J7874D01*
G01X1856976Y616535D02*
G03X1861926Y618285I0J7874D01*
G01Y602975D02*
G03X1856976Y604724I-4948J-6125D01*
G01X1861924Y602975D02*
G03X1856975Y604724I-4948J-6125D01*
G01X1861924Y602975D02*
G03X1856975Y604724I-4948J-6125D01*
G01X1861924Y602975D02*
G03X1856975Y604724I-4948J-6125D01*
G01X1861924Y602975D02*
G03X1856975Y604724I-4948J-6125D01*
G01X1861926Y602975D02*
G03X1856976Y604724I-4948J-6125D01*
G01X1854331Y616535D02*
G03Y604724I0J-5905D01*
G01Y616535D02*
G03Y604724I0J-5905D01*
G01D02*
X1856975D01*
G01X1856976D02*
X1854331D01*
G01X1856976D02*
X1854331D01*
G01D02*
X1856975D01*
G01X1854331Y616535D02*
G03Y604724I0J-5905D01*
G01Y616535D02*
G03Y604724I0J-5905D01*
G01Y616535D02*
X1856976D01*
G01X1856975D02*
X1854331D01*
G01X1856975D02*
X1854331D01*
G01D02*
X1856976D01*
G01X1972441Y-11811D02*
X1906890D01*
G01X1904921Y-9843D02*
G03X1906890Y-11811I1969J1D01*
G01X1904921Y53150D02*
Y-9843D01*
G01X1972441Y-11811D02*
X1906890D01*
G01X1904921Y-9843D02*
G03X1906890Y-11811I1969J1D01*
G01X1904921Y53150D02*
Y-9843D01*
G01X1923071Y53150D02*
Y-9843D01*
G01X1940787Y-3937D02*
X1972441D01*
G01X1940787D02*
G03X1938819Y-5906I0J-1968D01*
G01Y-9843D02*
Y-5906D01*
G01Y-9843D02*
G03X1940787Y-11811I1968J0D01*
G01X1921102D02*
G03X1923071Y-9843I0J1969D01*
G01X1906890Y55118D02*
G03X1904921Y53150I0J-1969D01*
G01X1972441Y55118D02*
X1906890D01*
G01X1972441D02*
X1906890D01*
G01X1972441D02*
X1906890D01*
G01X1972441D02*
X1906890D01*
G01D02*
G03X1904921Y53150I0J-1969D01*
G01X1923071D02*
G03X1921102Y55118I-1969J-1D01*
G01X1940787D02*
G03X1938819Y53150I0J-1968D01*
G01Y49213D02*
Y53150D01*
G01Y49213D02*
G03X1940787Y47244I1968J-1D01*
G01X1972441D02*
X1940787D01*
G01X1976378Y-35433D02*
G03X1972441Y-31496I-3937J0D01*
G01X1976378Y-59055D02*
Y-35433D01*
G01Y-59055D02*
Y-35433D01*
G01D02*
G03X1972441Y-31496I-3937J0D01*
G01Y-62992D02*
G03X1976378Y-59055I0J3937D01*
G01X1972441Y-62992D02*
G03X1976378Y-59055I0J3937D01*
G01X1972441Y-23622D02*
G03X1976378Y-19685I0J3937D01*
G01X1972441Y-23622D02*
G03X1976378Y-19685I0J3937D01*
G01X1972441Y-23622D02*
G03X1976378Y-19685I0J3937D01*
G01X1972441Y-23622D02*
G03X1976378Y-19685I0J3937D01*
G01D02*
Y-15748D01*
G01Y-19685D02*
Y-15748D01*
G01Y-19685D02*
Y-15748D01*
G01Y-19685D02*
Y-15748D01*
G01D02*
G03X1972441Y-11811I-3937J0D01*
G01X1976378Y-15748D02*
G03X1972441Y-11811I-3937J0D01*
G01X1976378Y-15748D02*
G03X1972441Y-11811I-3937J0D01*
G01X1976378Y-15748D02*
G03X1972441Y-11811I-3937J0D01*
G01X1976378Y0D02*
Y43307D01*
G01X1972441Y-3937D02*
G03X1976378Y0I0J3937D01*
G01X1972441Y55118D02*
G03X1976378Y59055I0J3937D01*
G01X1972441Y55118D02*
G03X1976378Y59055I0J3937D01*
G01X1972441Y55118D02*
G03X1976378Y59055I0J3937D01*
G01X1972441Y55118D02*
G03X1976378Y59055I0J3937D01*
G01D02*
Y242835D01*
G01Y59055D02*
Y242835D01*
G01Y59055D02*
Y242835D01*
G01Y59055D02*
Y242835D01*
G01Y43307D02*
G03X1972441Y47244I-3937J0D01*
G01X1976378Y242835D02*
G03X1972441Y246772I-3937J0D01*
G01X1976378Y242835D02*
G03X1972441Y246772I-3937J0D01*
G01X1976378Y242835D02*
G03X1972441Y246772I-3937J0D01*
G01X1976378Y242835D02*
G03X1972441Y246772I-3937J0D01*
G01Y432598D02*
G03X1976378Y436535I0J3937D01*
G01X1972441Y432598D02*
G03X1976378Y436535I0J3937D01*
G01X1972441Y432598D02*
G03X1976378Y436535I0J3937D01*
G01X1972441Y432598D02*
G03X1976378Y436535I0J3937D01*
G01D02*
Y622441D01*
G01Y436535D02*
Y622441D01*
G01Y436535D02*
Y622441D01*
G01Y436535D02*
Y622441D01*
G01D02*
G03X1972441Y626378I-3937J0D01*
G01X1976378Y622441D02*
G03X1972441Y626378I-3937J0D01*
G01X1976378Y622441D02*
G03X1972441Y626378I-3937J0D01*
G01X1976378Y622441D02*
G03X1972441Y626378I-3937J0D01*
G01Y634252D02*
G03X1976378Y638189I0J3937D01*
G01X1972441Y634252D02*
G03X1976378Y638189I0J3937D01*
G01D02*
Y661811D01*
G01Y638189D02*
Y661811D01*
G01D02*
G03X1972441Y665748I-3937J0D01*
G01X1976378Y661811D02*
G03X1972441Y665748I-3937J0D01*
G54D12*
G01X1547975Y459540D02*
X1549925Y460446D01*
G01X1565192Y446771D02*
X1565525Y446926D01*
G01X1564844Y446610D02*
X1565192Y446771D01*
G01X1563575Y446020D02*
X1564844Y446610D01*
G01X1538212Y467200D02*
X1538225Y467206D01*
G01X1536275Y466300D02*
X1538212Y467200D01*
G54D13*
G01X45500Y-47250D02*
X40500Y-42250D01*
G01X144250Y-47250D02*
X45500D01*
G01X145585Y-45915D02*
X144250Y-47250D01*
G01X443071Y-45915D02*
X145585D01*
G01X146290Y-42265D02*
X443071D01*
G01X160431Y-14877D02*
Y-9901D01*
G01X147045Y-14877D02*
Y-9901D01*
G01X150392Y-3699D02*
X150391Y-3700D01*
G01X150392Y-2500D02*
Y-3699D01*
G01X150912Y-1980D02*
X150392Y-2500D01*
G01X150912Y-1120D02*
Y-1980D01*
G01X150392Y-600D02*
X150912Y-1120D01*
G01X150392Y3233D02*
Y-600D01*
G01X130313Y-14877D02*
Y-9901D01*
G01X160431Y22923D02*
Y27899D01*
G01X167124Y22923D02*
Y27899D01*
G01X153738Y22923D02*
Y27899D01*
G01X123620Y22923D02*
Y27899D01*
G01X133659Y3233D02*
X132959Y-4100D01*
G01X163777Y-2008D02*
X163391Y-4100D01*
G01X163777Y3233D02*
Y-2008D01*
G01X130313Y22923D02*
Y27899D01*
G01X123620Y-14877D02*
Y-9901D01*
G01X153738Y-14877D02*
Y-9901D01*
G01X167124Y-14877D02*
Y-9901D01*
G01X126966Y-2008D02*
X126580Y-4100D01*
G01X126966Y3233D02*
Y-2008D01*
G01X157084Y-2608D02*
Y-3700D01*
G01X157602Y-2090D02*
X157084Y-2608D01*
G01X157602Y-1210D02*
Y-2090D01*
G01X157084Y-692D02*
X157602Y-1210D01*
G01X157084Y3233D02*
Y-692D01*
G01X147045Y22923D02*
Y27899D01*
G01X123620Y65699D02*
Y60723D01*
G01X150392Y34101D02*
X150391Y34100D01*
G01X150392Y35300D02*
Y34101D01*
G01X150912Y35820D02*
X150392Y35300D01*
G01X150912Y36680D02*
Y35820D01*
G01X150392Y37200D02*
X150912Y36680D01*
G01X150392Y41033D02*
Y37200D01*
G01X165584Y94297D02*
Y101984D01*
G01X167124Y92757D02*
X165584Y94297D01*
G01X160431Y60723D02*
Y65699D01*
G01X162892Y93800D02*
Y102992D01*
G01X161632Y90720D02*
X162892Y93800D01*
G01X161632Y89559D02*
Y90720D01*
G01X163477Y87714D02*
X161632Y89559D01*
G01X126966Y73592D02*
X126580Y71500D01*
G01X126966Y78833D02*
Y73592D01*
G01X126728Y34500D02*
X126580Y33700D01*
G01X126966Y35792D02*
X126728Y34500D01*
G01X126966Y41033D02*
Y35792D01*
G01X133341Y75500D02*
X132959Y71500D01*
G01X133659Y78833D02*
X133341Y75500D01*
G01X157084Y72992D02*
Y71900D01*
G01X157602Y73510D02*
X157084Y72992D01*
G01X157602Y74390D02*
Y73510D01*
G01X157084Y74908D02*
X157602Y74390D01*
G01X157084Y78833D02*
Y74908D01*
G01Y35192D02*
Y34100D01*
G01X157602Y35710D02*
X157084Y35192D01*
G01X157602Y36590D02*
Y35710D01*
G01X157084Y37108D02*
X157602Y36590D01*
G01X157084Y41033D02*
Y37108D01*
G01X147045Y60723D02*
Y65699D01*
G01X133035Y34500D02*
X132959Y33700D01*
G01X133659Y41033D02*
X133035Y34500D01*
G01X130313Y60723D02*
Y65699D01*
G01X163777Y73592D02*
X163391Y71500D01*
G01X163777Y78833D02*
Y73592D01*
G01X160192Y92996D02*
Y103892D01*
G01X160431Y92757D02*
X160192Y92996D01*
G01X153738Y60723D02*
Y65699D01*
G01X150392Y71901D02*
X150391Y71900D01*
G01X150392Y73100D02*
Y71901D01*
G01X150912Y73620D02*
X150392Y73100D01*
G01X150912Y74480D02*
Y73620D01*
G01X150392Y75000D02*
X150912Y74480D01*
G01X150392Y78833D02*
Y75000D01*
G01X163539Y34500D02*
X163391Y33700D01*
G01X163777Y35792D02*
X163539Y34500D01*
G01X163777Y41033D02*
Y35792D01*
G01X167124Y60723D02*
Y65699D01*
G01X168307Y94233D02*
Y101008D01*
G01X168966Y93574D02*
X168307Y94233D01*
G01X168966Y92074D02*
Y93574D01*
G01X167766Y90874D02*
X168966Y92074D01*
G01X167766Y89718D02*
Y90874D01*
G01X169770Y87714D02*
X167766Y89718D01*
G01X165584Y101984D02*
X182420Y118820D01*
G01X162892Y102992D02*
X180519Y120619D01*
G01X160192Y103892D02*
X178000Y121700D01*
G01X168307Y101008D02*
X183603Y116301D01*
G01X164992Y449629D02*
Y497800D01*
G01X257312Y357309D02*
X164992Y449629D01*
G01X167692Y450687D02*
Y498999D01*
G01X257879Y360500D02*
X167692Y450687D01*
G01X160431Y513287D02*
Y518157D01*
G01X162266Y511452D02*
X160431Y513287D01*
G01X162266Y500526D02*
Y511452D01*
G01X164992Y497800D02*
X162266Y500526D01*
G01X160431Y523900D02*
Y528899D01*
G01X164915Y511676D02*
X163477Y513114D01*
G01X164915Y501776D02*
Y511676D01*
G01X167692Y498999D02*
X164915Y501776D01*
G01X130313Y523900D02*
Y528899D01*
G01X153738Y523900D02*
Y528899D01*
G01X147045Y523900D02*
Y528899D01*
G01X123620Y523900D02*
Y528899D01*
G01X167124Y523900D02*
Y528899D01*
G01Y512594D02*
Y518157D01*
G01X169046Y510672D02*
X167124Y512594D01*
G01X169046Y508854D02*
Y510672D01*
G01X167492Y507300D02*
X169046Y508854D01*
G01X167492Y503500D02*
Y507300D01*
G01X170392Y500600D02*
X167492Y503500D01*
G01X126966Y574592D02*
X126580Y572500D01*
G01X126966Y579810D02*
Y574592D01*
G01X157084Y536192D02*
Y535100D01*
G01X157602Y536710D02*
X157084Y536192D01*
G01X157602Y537590D02*
Y536710D01*
G01X157084Y538108D02*
X157602Y537590D01*
G01X157084Y542010D02*
Y538108D01*
G01X163777Y536792D02*
X163391Y534700D01*
G01X163777Y542010D02*
Y536792D01*
G01X167124Y561700D02*
Y566699D01*
G01X150392Y572901D02*
X150391Y572900D01*
G01X150392Y574100D02*
Y572901D01*
G01X150912Y574620D02*
X150392Y574100D01*
G01X150912Y575480D02*
Y574620D01*
G01X150392Y576000D02*
X150912Y575480D01*
G01X150392Y579810D02*
Y576000D01*
G01X133659Y542033D02*
X132959Y534700D01*
G01X133659Y542010D02*
Y542033D01*
G01X130313Y561700D02*
Y566699D01*
G01X126966Y536792D02*
X126580Y534700D01*
G01X126966Y542010D02*
Y536792D01*
G01X163777Y574592D02*
X163391Y572500D01*
G01X163777Y579810D02*
Y574592D01*
G01X160431Y561700D02*
Y566699D01*
G01X133659Y579833D02*
X132959Y572500D01*
G01X133659Y579810D02*
Y579833D01*
G01X157084Y573992D02*
Y572900D01*
G01X157602Y574510D02*
X157084Y573992D01*
G01X157602Y575390D02*
Y574510D01*
G01X157084Y575908D02*
X157602Y575390D01*
G01X157084Y579810D02*
Y575908D01*
G01X153738Y561700D02*
Y566699D01*
G01X147045Y561700D02*
Y566699D01*
G01X123620Y561700D02*
Y566699D01*
G01X150392Y535101D02*
X150391Y535100D01*
G01X150392Y536300D02*
Y535101D01*
G01X150912Y536820D02*
X150392Y536300D01*
G01X150912Y537680D02*
Y536820D01*
G01X150392Y538200D02*
X150912Y537680D01*
G01X150392Y542010D02*
Y538200D01*
G01X167124Y599500D02*
Y604499D01*
G01X130313Y599500D02*
Y604499D01*
G01X163777Y612392D02*
X163391Y610300D01*
G01X163777Y617610D02*
Y612392D01*
G01X153738Y599500D02*
Y604499D01*
G01X126966Y612392D02*
X126580Y610300D01*
G01X126966Y617610D02*
Y612392D01*
G01X157084Y611792D02*
Y610700D01*
G01X157602Y612310D02*
X157084Y611792D01*
G01X157602Y613190D02*
Y612310D01*
G01X157084Y613708D02*
X157602Y613190D01*
G01X157084Y617610D02*
Y613708D01*
G01X147045Y599500D02*
Y604499D01*
G01X160431Y599500D02*
Y604499D01*
G01X133659Y617633D02*
X132959Y610300D01*
G01X133659Y617610D02*
Y617633D01*
G01X150392Y610701D02*
X150391Y610700D01*
G01X150392Y611900D02*
Y610701D01*
G01X150912Y612420D02*
X150392Y611900D01*
G01X150912Y613280D02*
Y612420D01*
G01X150392Y613800D02*
X150912Y613280D01*
G01X150392Y617610D02*
Y613800D01*
G01X123620Y599500D02*
Y604499D01*
G01X190549Y-14877D02*
Y-9901D01*
G01X227360Y22923D02*
Y27899D01*
G01X203935Y22923D02*
Y27899D01*
G01X207281Y3233D02*
X206581Y-4100D01*
G01X193895Y-2608D02*
Y-3700D01*
G01X194413Y-2090D02*
X193895Y-2608D01*
G01X194413Y-1210D02*
Y-2090D01*
G01X193895Y-692D02*
X194413Y-1210D01*
G01X193895Y3232D02*
Y-692D01*
G01X193896Y3233D02*
X193895Y3232D01*
G01X230706Y-2608D02*
Y-3700D01*
G01X231224Y-2090D02*
X230706Y-2608D01*
G01X231224Y-1210D02*
Y-2090D01*
G01X230706Y-692D02*
X231224Y-1210D01*
G01X230706Y3232D02*
Y-692D01*
G01X230707Y3233D02*
X230706Y3232D01*
G01X187203Y-3699D02*
X187202Y-3700D01*
G01X187203Y-2500D02*
Y-3699D01*
G01X187723Y-1980D02*
X187203Y-2500D01*
G01X187723Y-1120D02*
Y-1980D01*
G01X187203Y-600D02*
X187723Y-1120D01*
G01X187203Y3233D02*
Y-600D01*
G01X220667Y22923D02*
Y27899D01*
G01X197242Y22923D02*
Y27899D01*
G01X190549Y22923D02*
Y27899D01*
G01X197242Y-14877D02*
Y-9901D01*
G01X220667Y-14877D02*
Y-9901D01*
G01X227360Y-14877D02*
Y-9901D01*
G01X183856Y22923D02*
Y27899D01*
G01X200588Y-2008D02*
X200202Y-4100D01*
G01X200588Y3233D02*
Y-2008D01*
G01X224014Y-3699D02*
X224013Y-3700D01*
G01X224014Y-2500D02*
Y-3699D01*
G01X224534Y-1980D02*
X224014Y-2500D01*
G01X224534Y-1120D02*
Y-1980D01*
G01X224014Y-600D02*
X224534Y-1120D01*
G01X224014Y3233D02*
Y-600D01*
G01X203935Y-14877D02*
Y-9901D01*
G01X170470Y3233D02*
X169770Y-4100D01*
G01X183856Y-14877D02*
Y-9901D01*
G01X230706Y72992D02*
Y71900D01*
G01X231224Y73510D02*
X230706Y72992D01*
G01X231224Y74390D02*
Y73510D01*
G01X230706Y74908D02*
X231224Y74390D01*
G01X230706Y78832D02*
Y74908D01*
G01X230707Y78833D02*
X230706Y78832D01*
G01X227360Y60723D02*
Y65699D01*
G01X193895Y72992D02*
Y71900D01*
G01X194413Y73510D02*
X193895Y72992D01*
G01X194413Y74390D02*
Y73510D01*
G01X193895Y74908D02*
X194413Y74390D01*
G01X193895Y78832D02*
Y74908D01*
G01X193896Y78833D02*
X193895Y78832D01*
G01X190549Y92757D02*
X192584Y94792D01*
G01X200588Y73592D02*
X200202Y71500D01*
G01X200588Y78833D02*
Y73592D01*
G01X170152Y75500D02*
X169770Y71500D01*
G01X170470Y78833D02*
X170152Y75500D01*
G01X220667Y60723D02*
Y65699D01*
G01X190549Y60723D02*
Y65699D01*
G01X188684Y94684D02*
X190700Y96700D01*
G01X188684Y91956D02*
Y94684D01*
G01X190434Y90206D02*
X188684Y91956D01*
G01X191403Y90206D02*
X190434D01*
G01X193895Y87714D02*
X191403Y90206D01*
G01X206963Y75500D02*
X206581Y71500D01*
G01X207281Y78833D02*
X206963Y75500D01*
G01X200350Y34500D02*
X200202Y33700D01*
G01X200588Y35792D02*
X200350Y34500D01*
G01X200588Y41033D02*
Y35792D01*
G01X193895Y35192D02*
Y34100D01*
G01X194413Y35710D02*
X193895Y35192D01*
G01X194413Y36590D02*
Y35710D01*
G01X193895Y37108D02*
X194413Y36590D01*
G01X193896Y37109D02*
X193895Y37108D01*
G01X193896Y41033D02*
Y37109D01*
G01X187203Y34101D02*
X187202Y34100D01*
G01X187203Y35300D02*
Y34101D01*
G01X187723Y35820D02*
X187203Y35300D01*
G01X187723Y36680D02*
Y35820D01*
G01X187203Y37200D02*
X187723Y36680D01*
G01X187203Y41033D02*
Y37200D01*
G01X183856Y60723D02*
Y65699D01*
G01X185892Y91900D02*
Y95192D01*
G01X185166Y91174D02*
X185892Y91900D01*
G01X185166Y89750D02*
Y91174D01*
G01X187202Y87714D02*
X185166Y89750D01*
G01X224014Y71901D02*
X224013Y71900D01*
G01X224014Y73100D02*
Y71901D01*
G01X224534Y73620D02*
X224014Y73100D01*
G01X224534Y74480D02*
Y73620D01*
G01X224014Y75000D02*
X224534Y74480D01*
G01X224014Y78833D02*
Y75000D01*
G01Y34101D02*
X224013Y34100D01*
G01X224014Y35300D02*
Y34101D01*
G01X224534Y35820D02*
X224014Y35300D01*
G01X224534Y36680D02*
Y35820D01*
G01X224014Y37200D02*
X224534Y36680D01*
G01X224014Y41033D02*
Y37200D01*
G01X203935Y60723D02*
Y65699D01*
G01X197242Y60723D02*
Y65699D01*
G01X206657Y34500D02*
X206581Y33700D01*
G01X207281Y41033D02*
X206657Y34500D01*
G01X169846D02*
X169770Y33700D01*
G01X170470Y41033D02*
X169846Y34500D01*
G01X187203Y71901D02*
X187202Y71900D01*
G01X187203Y73100D02*
Y71901D01*
G01X187723Y73620D02*
X187203Y73100D01*
G01X187723Y74480D02*
Y73620D01*
G01X187203Y75000D02*
X187723Y74480D01*
G01X187203Y78833D02*
Y75000D01*
G01X182892Y93721D02*
X183856Y92757D01*
G01X182892Y94850D02*
Y93721D01*
G01X230706Y35192D02*
Y34100D01*
G01X231224Y35710D02*
X230706Y35192D01*
G01X231224Y36590D02*
Y35710D01*
G01X230706Y37108D02*
X231224Y36590D01*
G01X230706Y41032D02*
Y37108D01*
G01X230707Y41033D02*
X230706Y41032D01*
G01X229500Y146702D02*
Y177100D01*
G01X227600Y144802D02*
X229500Y146702D01*
G01X227600Y134300D02*
Y144802D01*
G01X225718Y132418D02*
X227600Y134300D01*
G01X225718Y130200D02*
Y132418D01*
G01Y125426D02*
Y130200D01*
G01X209356Y109064D02*
X225718Y125426D01*
G01X209356Y108144D02*
Y109064D01*
G01X210310Y107190D02*
X209356Y108144D01*
G01X211230Y107190D02*
X210310D01*
G01X224456Y120416D02*
X211230Y107190D01*
G01X225376Y120416D02*
X224456D01*
G01X226330Y119462D02*
X225376Y120416D01*
G01X226330Y118542D02*
Y119462D01*
G01X202580Y94792D02*
X226330Y118542D01*
G01X192584Y94792D02*
X202580D01*
G01X201193Y154392D02*
Y178560D01*
G01X197581Y150780D02*
X201193Y154392D01*
G01X197581Y146857D02*
Y150780D01*
G01X194083Y143359D02*
X197581Y146857D01*
G01X194083Y133847D02*
Y143359D01*
G01X190762Y130526D02*
X194083Y133847D01*
G01X190762Y127072D02*
Y130526D01*
G01X190112Y126422D02*
X190762Y127072D01*
G01X185650Y126422D02*
X190112D01*
G01X185000Y125772D02*
X185650Y126422D01*
G01X185000Y124422D02*
Y125772D01*
G01X185650Y123772D02*
X185000Y124422D01*
G01X190112Y123772D02*
X185650D01*
G01X190762Y123122D02*
X190112Y123772D01*
G01X190762Y121862D02*
Y123122D01*
G01X187720Y118820D02*
X190762Y121862D01*
G01X182420Y118820D02*
X187720D01*
G01X198674Y155436D02*
Y179799D01*
G01X191564Y148326D02*
X198674Y155436D01*
G01X191564Y137564D02*
Y148326D01*
G01X180519Y126519D02*
X191564Y137564D01*
G01X180519Y120619D02*
Y126519D01*
G01X226500Y147265D02*
Y177859D01*
G01X222829Y143594D02*
X226500Y147265D01*
G01X222829Y141300D02*
Y143594D01*
G01Y126829D02*
Y141300D01*
G01X220962Y124962D02*
X222829Y126829D01*
G01X220042Y124962D02*
X220962D01*
G01X217214Y127790D02*
X220042Y124962D01*
G01X216294Y127790D02*
X217214D01*
G01X210162Y121658D02*
X216294Y127790D01*
G01X210162Y120738D02*
Y121658D01*
G01X211116Y119784D02*
X210162Y120738D01*
G01X212036Y119784D02*
X211116D01*
G01X216294Y124042D02*
X212036Y119784D01*
G01X217214Y124042D02*
X216294D01*
G01X218168Y123088D02*
X217214Y124042D01*
G01X218168Y122168D02*
Y123088D01*
G01X206700Y110700D02*
X218168Y122168D01*
G01X206700Y102700D02*
Y110700D01*
G01X200700Y96700D02*
X206700Y102700D01*
G01X190700Y96700D02*
X200700D01*
G01X223400Y147728D02*
Y178517D01*
G01X220300Y144628D02*
X223400Y147728D01*
G01X220300Y132600D02*
Y144628D01*
G01X219800Y132100D02*
X220300Y132600D01*
G01X216978Y132100D02*
X219800D01*
G01X216478Y132600D02*
X216978Y132100D01*
G01X216478Y140900D02*
Y132600D01*
G01X215978Y141400D02*
X216478Y140900D01*
G01X214328Y141400D02*
X215978D01*
G01X213828Y140900D02*
X214328Y141400D01*
G01X213828Y134900D02*
Y140900D01*
G01Y129628D02*
Y134900D01*
G01X207000Y122800D02*
X213828Y129628D01*
G01X207000Y115100D02*
Y122800D01*
G01X203500Y111600D02*
X207000Y115100D01*
G01X203500Y103300D02*
Y111600D01*
G01X200050Y99850D02*
X203500Y103300D01*
G01X190550Y99850D02*
X200050D01*
G01X185892Y95192D02*
X190550Y99850D01*
G01X231492Y142792D02*
X233592Y144892D01*
G01X234053Y112327D02*
X231492Y114888D01*
G01X189045Y149371D02*
X196155Y156481D01*
G01X189045Y138609D02*
Y149371D01*
G01X178000Y127564D02*
X189045Y138609D01*
G01X178000Y121700D02*
Y127564D01*
G01X213800Y150400D02*
Y157600D01*
G01X214300Y149900D02*
X213800Y150400D01*
G01X217100Y149900D02*
X214300D01*
G01X218341Y151141D02*
X217100Y149900D01*
G01X218341Y154800D02*
Y151141D01*
G01X218841Y155300D02*
X218341Y154800D01*
G01X220200Y155300D02*
X218841D01*
G01X220881Y154619D02*
X220200Y155300D01*
G01X220881Y149131D02*
Y154619D01*
G01X216500Y144750D02*
X220881Y149131D01*
G01X212850Y144750D02*
X216500D01*
G01X210896Y142796D02*
X212850Y144750D01*
G01X210896Y140300D02*
Y142796D01*
G01Y130597D02*
Y140300D01*
G01X204000Y123701D02*
X210896Y130597D01*
G01X204000Y115958D02*
Y123701D01*
G01X199221Y111179D02*
X204000Y115958D01*
G01X192817Y104775D02*
X182892Y94850D01*
G01X193525Y104775D02*
X192817D01*
G01X196540Y101760D02*
X193525Y104775D01*
G01X197460Y101760D02*
X196540D01*
G01X200496Y104796D02*
X197460Y101760D01*
G01X200496Y105504D02*
Y104796D01*
G01X197375Y108625D02*
X200496Y105504D01*
G01X197375Y109333D02*
Y108625D01*
G01X199221Y111179D02*
X197375Y109333D01*
G01X203712Y152492D02*
Y177321D01*
G01X200100Y148880D02*
X203712Y152492D01*
G01X200100Y144600D02*
Y148880D01*
G01X196602Y141102D02*
X200100Y144600D01*
G01X196602Y132802D02*
Y141102D01*
G01X193281Y129481D02*
X196602Y132802D01*
G01X193281Y120581D02*
Y129481D01*
G01X189000Y116300D02*
X193281Y120581D01*
G01X183603Y116301D02*
X189000Y116300D01*
G01X229500Y177100D02*
X262944Y210544D01*
G01X201193Y178560D02*
X253192Y230559D01*
G01X198674Y179799D02*
X252031Y233156D01*
G01X226500Y177859D02*
X261000Y212359D01*
G01X223400Y178517D02*
X259383Y214500D01*
G01X204317Y189200D02*
X250823Y235706D01*
G01X203399Y189200D02*
X204317D01*
G01X201860Y190740D02*
X203399Y189200D01*
G01X200942Y190740D02*
X201860D01*
G01X199986Y189784D02*
X200942Y190740D01*
G01X199986Y188866D02*
Y189784D01*
G01X201525Y187326D02*
X199986Y188866D01*
G01X201525Y186408D02*
Y187326D01*
G01X196155Y181038D02*
X201525Y186408D01*
G01X196155Y156481D02*
Y181038D01*
G01X217419Y176294D02*
X258125Y217000D01*
G01X217419Y172581D02*
Y176294D01*
G01X220400Y169600D02*
X217419Y172581D01*
G01X220400Y158600D02*
Y169600D01*
G01X219900Y158100D02*
X220400Y158600D01*
G01X214300Y158100D02*
X219900D01*
G01X213800Y157600D02*
X214300Y158100D01*
G01X203712Y177321D02*
X254247Y227856D01*
G01X259395Y366500D02*
X173089Y452806D01*
G01X258977Y363160D02*
X170392Y451745D01*
G01X200392Y451700D02*
Y487878D01*
G01X264149Y387943D02*
X200392Y451700D01*
G01X197724Y450540D02*
Y498710D01*
G01X262871Y385393D02*
X197724Y450540D01*
G01X186992Y453990D02*
Y506000D01*
G01X187682Y453300D02*
X186992Y453990D01*
G01X188992Y453300D02*
X187682D01*
G01X189682Y453990D02*
X188992Y453300D01*
G01X189682Y463610D02*
Y453990D01*
G01X190372Y464300D02*
X189682Y463610D01*
G01X191682Y464300D02*
X190372D01*
G01X192372Y463610D02*
X191682Y464300D01*
G01X192372Y448278D02*
Y463610D01*
G01X261890Y378760D02*
X192372Y448278D01*
G01X195029Y449428D02*
Y483810D01*
G01X261614Y382843D02*
X195029Y449428D01*
G01X173189Y464559D02*
X173839Y465209D01*
G01X173189Y463209D02*
Y464559D01*
G01X173839Y462559D02*
X173189Y463209D01*
G01X175442Y462559D02*
X173839D01*
G01X176092Y461909D02*
X175442Y462559D01*
G01X176092Y460559D02*
Y461909D01*
G01X175442Y459909D02*
X176092Y460559D01*
G01X173839Y459909D02*
X175442D01*
G01X173089Y459159D02*
X173839Y459909D01*
G01X173089Y452806D02*
Y459159D01*
G01X170392Y451745D02*
Y500600D01*
G01X190549Y523900D02*
Y528899D01*
G01X195012Y511997D02*
X193895Y513114D01*
G01X195012Y504280D02*
Y511997D01*
G01X196914Y502378D02*
X195012Y504280D01*
G01X204742Y502378D02*
X196914D01*
G01X205692Y501428D02*
X204742Y502378D01*
G01X205692Y475250D02*
Y501428D01*
G01X205042Y474600D02*
X205692Y475250D01*
G01X203692Y474600D02*
X205042D01*
G01X203042Y475250D02*
X203692Y474600D01*
G01X203042Y487878D02*
Y475250D01*
G01X202392Y488528D02*
X203042Y487878D01*
G01X201042Y488528D02*
X202392D01*
G01X200392Y487878D02*
X201042Y488528D01*
G01X197242Y523900D02*
Y528899D01*
G01X203935Y523900D02*
Y528899D01*
G01X190549Y513169D02*
Y518157D01*
G01X192344Y511374D02*
X190549Y513169D01*
G01X192344Y487690D02*
Y511374D01*
G01X193034Y487000D02*
X192344Y487690D01*
G01X194344Y487000D02*
X193034D01*
G01X195034Y487690D02*
X194344Y487000D01*
G01X195034Y498710D02*
Y487690D01*
G01X195724Y499400D02*
X195034Y498710D01*
G01X197034Y499400D02*
X195724D01*
G01X197724Y498710D02*
X197034Y499400D01*
G01X183856Y512936D02*
Y518157D01*
G01X185992Y510800D02*
X183856Y512936D01*
G01X185992Y507000D02*
Y510800D01*
G01X186992Y506000D02*
X185992Y507000D01*
G01X227360Y523900D02*
Y528899D01*
G01X183856Y523900D02*
Y528899D01*
G01X188692Y511624D02*
X187202Y513114D01*
G01X188692Y508000D02*
Y511624D01*
G01X189649Y507043D02*
X188692Y508000D01*
G01X189649Y467647D02*
Y507043D01*
G01X190339Y466957D02*
X189649Y467647D01*
G01X191649Y466957D02*
X190339D01*
G01X192339Y467647D02*
X191649Y466957D01*
G01X192339Y483610D02*
Y467647D01*
G01X193129Y484400D02*
X192339Y483610D01*
G01X194439Y484400D02*
X193129D01*
G01X195029Y483810D02*
X194439Y484400D01*
G01X231492Y497100D02*
X232892Y498500D01*
G01X220667Y523900D02*
Y528899D01*
G01X171078Y513114D02*
X169770D01*
G01X171766Y512426D02*
X171078Y513114D01*
G01X171766Y507574D02*
Y512426D01*
G01X170292Y506100D02*
X171766Y507574D01*
G01X170292Y505001D02*
Y506100D01*
G01X173089Y502204D02*
X170292Y505001D01*
G01X173089Y468609D02*
Y502204D01*
G01X173839Y467859D02*
X173089Y468609D01*
G01X175442Y467859D02*
X173839D01*
G01X176092Y467209D02*
X175442Y467859D01*
G01X176092Y465859D02*
Y467209D01*
G01X175442Y465209D02*
X176092Y465859D01*
G01X173839Y465209D02*
X175442D01*
G01X200588Y536792D02*
X200202Y534700D01*
G01X200588Y542010D02*
Y536792D01*
G01X197242Y561700D02*
Y566699D01*
G01X203935Y561700D02*
Y566699D01*
G01X207281Y542033D02*
X206581Y534700D01*
G01X207281Y542010D02*
Y542033D01*
G01X230706Y536192D02*
Y535100D01*
G01X231224Y536710D02*
X230706Y536192D01*
G01X231224Y537590D02*
Y536710D01*
G01X230706Y538108D02*
X231224Y537590D01*
G01X230706Y542010D02*
Y538108D01*
G01X230707Y542010D02*
X230706D01*
G01X220667Y561700D02*
Y566699D01*
G01X193895Y536192D02*
Y535100D01*
G01X194413Y536710D02*
X193895Y536192D01*
G01X194413Y537590D02*
Y536710D01*
G01X193895Y538108D02*
X194413Y537590D01*
G01X193895Y542010D02*
Y538108D01*
G01X193896Y542010D02*
X193895D01*
G01X183856Y561700D02*
Y566699D01*
G01X170470Y579833D02*
X169770Y572500D01*
G01X170470Y579810D02*
Y579833D01*
G01X187203Y535101D02*
X187202Y535100D01*
G01X187203Y536300D02*
Y535101D01*
G01X187723Y536820D02*
X187203Y536300D01*
G01X187723Y537680D02*
Y536820D01*
G01X187203Y538200D02*
X187723Y537680D01*
G01X187203Y542010D02*
Y538200D01*
G01X230706Y573992D02*
Y572900D01*
G01X231224Y574510D02*
X230706Y573992D01*
G01X231224Y575390D02*
Y574510D01*
G01X230706Y575908D02*
X231224Y575390D01*
G01X230706Y579810D02*
Y575908D01*
G01X230707Y579810D02*
X230706D01*
G01X200588Y574592D02*
X200202Y572500D01*
G01X200588Y579810D02*
Y574592D01*
G01X207281Y579833D02*
X206581Y572500D01*
G01X207281Y579810D02*
Y579833D01*
G01X227360Y561700D02*
Y566699D01*
G01X224014Y572901D02*
X224013Y572900D01*
G01X224014Y574100D02*
Y572901D01*
G01X224534Y574620D02*
X224014Y574100D01*
G01X224534Y575480D02*
Y574620D01*
G01X224014Y576000D02*
X224534Y575480D01*
G01X224014Y579810D02*
Y576000D01*
G01X190549Y561700D02*
Y566699D01*
G01X193895Y573992D02*
Y572900D01*
G01X194413Y574510D02*
X193895Y573992D01*
G01X194413Y575390D02*
Y574510D01*
G01X193895Y575908D02*
X194413Y575390D01*
G01X193895Y579810D02*
Y575908D01*
G01X193896Y579810D02*
X193895D01*
G01X224014Y535101D02*
X224013Y535100D01*
G01X224014Y536300D02*
Y535101D01*
G01X224534Y536820D02*
X224014Y536300D01*
G01X224534Y537680D02*
Y536820D01*
G01X224014Y538200D02*
X224534Y537680D01*
G01X224014Y542010D02*
Y538200D01*
G01X187203Y572901D02*
X187202Y572900D01*
G01X187203Y574100D02*
Y572901D01*
G01X187723Y574620D02*
X187203Y574100D01*
G01X187723Y575480D02*
Y574620D01*
G01X187203Y576000D02*
X187723Y575480D01*
G01X187203Y579810D02*
Y576000D01*
G01X170470Y542033D02*
X169770Y534700D01*
G01X170470Y542010D02*
Y542033D01*
G01X203935Y599500D02*
Y604499D01*
G01X170470Y617633D02*
X169770Y610300D01*
G01X170470Y617610D02*
Y617633D01*
G01X183856Y599500D02*
Y604499D01*
G01X230706Y611792D02*
Y610700D01*
G01X231224Y612310D02*
X230706Y611792D01*
G01X231224Y613190D02*
Y612310D01*
G01X230706Y613708D02*
X231224Y613190D01*
G01X230706Y617610D02*
Y613708D01*
G01X230707Y617610D02*
X230706D01*
G01X193895Y611792D02*
Y610700D01*
G01X194413Y612310D02*
X193895Y611792D01*
G01X194413Y613190D02*
Y612310D01*
G01X193895Y613708D02*
X194413Y613190D01*
G01X193895Y617610D02*
Y613708D01*
G01X193896Y617610D02*
X193895D01*
G01X197242Y599500D02*
Y604499D01*
G01X200588Y612392D02*
X200202Y610300D01*
G01X200588Y617610D02*
Y612392D01*
G01X220667Y599500D02*
Y604499D01*
G01X187203Y610701D02*
X187202Y610700D01*
G01X187203Y611900D02*
Y610701D01*
G01X187723Y612420D02*
X187203Y611900D01*
G01X187723Y613280D02*
Y612420D01*
G01X187203Y613800D02*
X187723Y613280D01*
G01X187203Y617610D02*
Y613800D01*
G01X207281Y617633D02*
X206581Y610300D01*
G01X207281Y617610D02*
Y617633D01*
G01X190549Y599500D02*
Y604499D01*
G01X227360Y599500D02*
Y604499D01*
G01X224014Y610701D02*
X224013Y610700D01*
G01X224014Y611900D02*
Y610701D01*
G01X224534Y612420D02*
X224014Y611900D01*
G01X224534Y613280D02*
Y612420D01*
G01X224014Y613800D02*
X224534Y613280D01*
G01X224014Y617610D02*
Y613800D01*
G01X234053Y-14877D02*
Y-9901D01*
G01X264171Y-14877D02*
Y-9901D01*
G01X257478Y22923D02*
Y27899D01*
G01Y-14877D02*
Y-9901D01*
G01X244092Y3233D02*
X243392Y-4100D01*
G01X234053Y22923D02*
Y27899D01*
G01X280903Y3233D02*
X280203Y-4100D01*
G01X237399Y-2008D02*
X237013Y-4100D01*
G01X237399Y3233D02*
Y-2008D01*
G01X274210D02*
X273824Y-4100D01*
G01X274210Y3233D02*
Y-2008D01*
G01X270864Y-14877D02*
Y-9901D01*
G01Y22923D02*
Y27899D01*
G01X267517Y-2608D02*
Y-3700D01*
G01X268035Y-2090D02*
X267517Y-2608D01*
G01X268035Y-1210D02*
Y-2090D01*
G01X267517Y-692D02*
X268035Y-1210D01*
G01X267517Y3232D02*
Y-692D01*
G01X267518Y3233D02*
X267517Y3232D01*
G01X277557Y22923D02*
Y27899D01*
G01Y-14877D02*
Y-9901D01*
G01X240746Y-14877D02*
Y-9901D01*
G01X264171Y22923D02*
Y27899D01*
G01X260825Y-3699D02*
X260824Y-3700D01*
G01X260825Y-2500D02*
Y-3699D01*
G01X261345Y-1980D02*
X260825Y-2500D01*
G01X261345Y-1120D02*
Y-1980D01*
G01X260825Y-600D02*
X261345Y-1120D01*
G01X260825Y3233D02*
Y-600D01*
G01X240746Y22923D02*
Y27899D01*
G01X234053Y60723D02*
Y65699D01*
G01X277557Y60723D02*
Y65699D01*
G01X260825Y71901D02*
X260824Y71900D01*
G01X260825Y73100D02*
Y71901D01*
G01X261345Y73620D02*
X260825Y73100D01*
G01X261345Y74480D02*
Y73620D01*
G01X260825Y75000D02*
X261345Y74480D01*
G01X260825Y78833D02*
Y75000D01*
G01X280279Y34500D02*
X280203Y33700D01*
G01X280903Y41033D02*
X280279Y34500D01*
G01X273972D02*
X273824Y33700D01*
G01X274210Y35792D02*
X273972Y34500D01*
G01X274210Y41033D02*
Y35792D01*
G01X243468Y34500D02*
X243392Y33700D01*
G01X244092Y41033D02*
X243468Y34500D01*
G01X260825Y34101D02*
X260824Y34100D01*
G01X260825Y35300D02*
Y34101D01*
G01X261345Y35820D02*
X260825Y35300D01*
G01X261345Y36680D02*
Y35820D01*
G01X260825Y37200D02*
X261345Y36680D01*
G01X260825Y41033D02*
Y37200D01*
G01X243774Y75500D02*
X243392Y71500D01*
G01X244092Y78833D02*
X243774Y75500D01*
G01X267517Y35192D02*
Y34100D01*
G01X268035Y35710D02*
X267517Y35192D01*
G01X268035Y36590D02*
Y35710D01*
G01X267517Y37108D02*
X268035Y36590D01*
G01X267517Y41032D02*
Y37108D01*
G01X267518Y41033D02*
X267517Y41032D01*
G01Y72992D02*
Y71900D01*
G01X268035Y73510D02*
X267517Y72992D01*
G01X268035Y74390D02*
Y73510D01*
G01X267517Y74908D02*
X268035Y74390D01*
G01X267517Y78832D02*
Y74908D01*
G01X267518Y78833D02*
X267517Y78832D01*
G01X237161Y34500D02*
X237013Y33700D01*
G01X237399Y35792D02*
X237161Y34500D01*
G01X237399Y41033D02*
Y35792D01*
G01X257478Y60723D02*
Y65699D01*
G01X270864Y60723D02*
Y65699D01*
G01X237399Y73592D02*
X237013Y71500D01*
G01X237399Y78833D02*
Y73592D01*
G01X264171Y60723D02*
Y65699D01*
G01X280585Y75500D02*
X280203Y71500D01*
G01X280903Y78833D02*
X280585Y75500D01*
G01X240746Y60723D02*
Y65699D01*
G01X274210Y73592D02*
X273824Y71500D01*
G01X274210Y78833D02*
Y73592D01*
G01X264529Y144650D02*
Y170836D01*
G01X263879Y144000D02*
X264529Y144650D01*
G01X262489Y144000D02*
X263879D01*
G01X261839Y144650D02*
X262489Y144000D01*
G01X261839Y146860D02*
Y144650D01*
G01X261149Y147550D02*
X261839Y146860D01*
G01X259839Y147550D02*
X261149D01*
G01X259149Y146860D02*
X259839Y147550D01*
G01X259149Y140500D02*
Y146860D01*
G01Y114100D02*
Y140500D01*
G01X259692Y113557D02*
X259149Y114100D01*
G01X259692Y111843D02*
Y113557D01*
G01X258992Y111143D02*
X259692Y111843D01*
G01X258992Y109116D02*
Y111143D01*
G01X260824Y107284D02*
X258992Y109116D01*
G01X236492Y140100D02*
Y167700D01*
G01X234192Y137800D02*
X236492Y140100D01*
G01X234192Y134000D02*
Y137800D01*
G01Y116050D02*
Y134000D01*
G01X235878Y114364D02*
X234192Y116050D01*
G01X235878Y111486D02*
Y114364D01*
G01X235192Y110800D02*
X235878Y111486D01*
G01X235192Y109159D02*
Y110800D01*
G01X237067Y107284D02*
X235192Y109159D01*
G01X237099Y107284D02*
X237067D01*
G01X276792Y113092D02*
X277557Y112327D01*
G01X276792Y119749D02*
Y113092D01*
G01X284592Y127549D02*
X276792Y119749D01*
G01X284592Y128743D02*
Y127549D01*
G01X283942Y129393D02*
X284592Y128743D01*
G01X282742Y129393D02*
X283942D01*
G01X282092Y130043D02*
X282742Y129393D01*
G01X282092Y131393D02*
Y130043D01*
G01X282742Y132043D02*
X282092Y131393D01*
G01X283942Y132043D02*
X282742D01*
G01X284592Y132693D02*
X283942Y132043D01*
G01X284592Y134043D02*
Y132693D01*
G01X283942Y134693D02*
X284592Y134043D01*
G01X282742Y134693D02*
X283942D01*
G01X282092Y135343D02*
X282742Y134693D01*
G01X282092Y136693D02*
Y135343D01*
G01X282742Y137343D02*
X282092Y136693D01*
G01X283942Y137343D02*
X282742D01*
G01X284592Y137993D02*
X283942Y137343D01*
G01X284592Y139343D02*
Y137993D01*
G01X283942Y139993D02*
X284592Y139343D01*
G01X282742Y139993D02*
X283942D01*
G01X282092Y140643D02*
X282742Y139993D01*
G01X282092Y141993D02*
Y140643D01*
G01X282742Y142643D02*
X282092Y141993D01*
G01X283942Y142643D02*
X282742D01*
G01X284592Y143293D02*
X283942Y142643D01*
G01X284592Y144643D02*
Y143293D01*
G01X283942Y145293D02*
X284592Y144643D01*
G01X282742Y145293D02*
X283942D01*
G01X282092Y145943D02*
X282742Y145293D01*
G01X282092Y147293D02*
Y145943D01*
G01X282742Y147943D02*
X282092Y147293D01*
G01X283942Y147943D02*
X282742D01*
G01X284592Y148593D02*
X283942Y147943D01*
G01X284592Y149943D02*
Y148593D01*
G01X283942Y150593D02*
X284592Y149943D01*
G01X282742Y150593D02*
X283942D01*
G01X282092Y151243D02*
X282742Y150593D01*
G01X282092Y152593D02*
Y151243D01*
G01X282742Y153243D02*
X282092Y152593D01*
G01X283942Y153243D02*
X282742D01*
G01X284592Y153893D02*
X283942Y153243D01*
G01X284592Y164196D02*
Y153893D01*
G01X270864Y121621D02*
Y112327D01*
G01X276692Y127449D02*
X270864Y121621D01*
G01X276692Y130963D02*
Y127449D01*
G01X275916Y131739D02*
X276692Y130963D01*
G01X274818Y131739D02*
X275916D01*
G01X274042Y132515D02*
X274818Y131739D01*
G01X274042Y133613D02*
Y132515D01*
G01X274818Y134389D02*
X274042Y133613D01*
G01X275916Y134389D02*
X274818D01*
G01X276692Y135165D02*
X275916Y134389D01*
G01X276692Y136263D02*
Y135165D01*
G01X275916Y137039D02*
X276692Y136263D01*
G01X274818Y137039D02*
X275916D01*
G01X274042Y137815D02*
X274818Y137039D01*
G01X274042Y138913D02*
Y137815D01*
G01X274818Y139689D02*
X274042Y138913D01*
G01X275916Y139689D02*
X274818D01*
G01X276692Y140465D02*
X275916Y139689D01*
G01X276692Y163709D02*
Y140465D01*
G01X239892Y113181D02*
X240746Y112327D01*
G01X239892Y118141D02*
Y113181D01*
G01X239242Y118791D02*
X239892Y118141D01*
G01X237842Y118791D02*
X239242D01*
G01X237192Y119441D02*
X237842Y118791D01*
G01X237192Y120791D02*
Y119441D01*
G01X237842Y121441D02*
X237192Y120791D01*
G01X239242Y121441D02*
X237842D01*
G01X239892Y122091D02*
X239242Y121441D01*
G01X239892Y123441D02*
Y122091D01*
G01X239242Y124091D02*
X239892Y123441D01*
G01X237842Y124091D02*
X239242D01*
G01X237192Y124741D02*
X237842Y124091D01*
G01X237192Y126091D02*
Y124741D01*
G01X237842Y126741D02*
X237192Y126091D01*
G01X239242Y126741D02*
X237842D01*
G01X239892Y127391D02*
X239242Y126741D01*
G01X239892Y128741D02*
Y127391D01*
G01X239242Y129391D02*
X239892Y128741D01*
G01X237842Y129391D02*
X239242D01*
G01X237192Y130041D02*
X237842Y129391D01*
G01X237192Y131391D02*
Y130041D01*
G01X237842Y132041D02*
X237192Y131391D01*
G01X239242Y132041D02*
X237842D01*
G01X239892Y132691D02*
X239242Y132041D01*
G01X239892Y135000D02*
Y132691D01*
G01Y149951D02*
Y135000D01*
G01X239202Y150641D02*
X239892Y149951D01*
G01X239202Y166834D02*
Y150641D01*
G01X271669Y107284D02*
X273910D01*
G01X271019Y107934D02*
X271669Y107284D01*
G01X271019Y109627D02*
Y107934D01*
G01X274092Y112700D02*
X271019Y109627D01*
G01X274092Y120951D02*
Y112700D01*
G01X279492Y126351D02*
X274092Y120951D01*
G01X279492Y162902D02*
Y126351D01*
G01X256492Y126896D02*
Y130000D01*
G01X255802Y126206D02*
X256492Y126896D01*
G01X255782Y126206D02*
X255802D01*
G01X255092Y125516D02*
X255782Y126206D01*
G01X255092Y124206D02*
Y125516D01*
G01X255782Y123516D02*
X255092Y124206D01*
G01X255802Y123516D02*
X255782D01*
G01X256492Y122826D02*
X255802Y123516D01*
G01X256492Y121516D02*
Y122826D01*
G01X255802Y120826D02*
X256492Y121516D01*
G01X255782Y120826D02*
X255802D01*
G01X255092Y120136D02*
X255782Y120826D01*
G01X255092Y118826D02*
Y120136D01*
G01X255782Y118136D02*
X255092Y118826D01*
G01X255802Y118136D02*
X255782D01*
G01X256492Y117446D02*
X255802Y118136D01*
G01X256492Y113313D02*
Y117446D01*
G01X257478Y112327D02*
X256492Y113313D01*
G01X261872Y155600D02*
Y171787D01*
G01X261372Y155100D02*
X261872Y155600D01*
G01X259682Y155100D02*
X261372D01*
G01X259182Y155600D02*
X259682Y155100D01*
G01X259182Y163350D02*
Y155600D01*
G01X256492Y130000D02*
Y163350D01*
G01X267186Y141000D02*
Y169877D01*
G01Y128604D02*
Y141000D01*
G01X266482Y127900D02*
X267186Y128604D01*
G01X265172Y127900D02*
X266482D01*
G01X264582Y128490D02*
X265172Y127900D01*
G01X264582Y135450D02*
Y128490D01*
G01X263932Y136100D02*
X264582Y135450D01*
G01X262542Y136100D02*
X263932D01*
G01X261892Y135450D02*
X262542Y136100D01*
G01X261892Y120759D02*
Y135450D01*
G01X262582Y120069D02*
X261892Y120759D01*
G01X262582Y117379D02*
Y120069D01*
G01X261892Y116689D02*
X262582Y117379D01*
G01X261892Y114606D02*
Y116689D01*
G01X264171Y112327D02*
X261892Y114606D01*
G01X280203Y102951D02*
Y106934D01*
G01X279552Y102300D02*
X280203Y102951D01*
G01X275992Y102300D02*
X279552D01*
G01X275292Y103000D02*
X275992Y102300D01*
G01X275292Y105800D02*
Y103000D01*
G01X275892Y106400D02*
X275292Y105800D01*
G01X275892Y109000D02*
Y106400D01*
G01X277192Y110300D02*
X275892Y109000D01*
G01X278292Y110300D02*
X277192D01*
G01X279492Y111500D02*
X278292Y110300D01*
G01X279492Y118551D02*
Y111500D01*
G01X288842Y127901D02*
X279492Y118551D01*
G01X288842Y129400D02*
Y127901D01*
G01X287292Y130950D02*
X288842Y129400D01*
G01X287292Y138200D02*
Y130950D01*
G01X288242Y139150D02*
X287292Y138200D01*
G01X288242Y141300D02*
Y139150D01*
G01X287292Y142250D02*
X288242Y141300D01*
G01X287292Y163289D02*
Y142250D01*
G01X233592Y144892D02*
Y168449D01*
G01X231492Y140500D02*
Y142792D01*
G01Y114888D02*
Y140500D01*
G01X270483Y156205D02*
Y157555D01*
G01X271133Y155555D02*
X270483Y156205D01*
G01X272542Y155555D02*
X271133D01*
G01X273192Y154905D02*
X272542Y155555D01*
G01X273192Y153555D02*
Y154905D01*
G01X272542Y152905D02*
X273192Y153555D01*
G01X271133Y152905D02*
X272542D01*
G01X270483Y152255D02*
X271133Y152905D01*
G01X270483Y150905D02*
Y152255D01*
G01X271133Y150255D02*
X270483Y150905D01*
G01X272542Y150255D02*
X271133D01*
G01X273192Y149605D02*
X272542Y150255D01*
G01X273192Y148255D02*
Y149605D01*
G01X272542Y147605D02*
X273192Y148255D01*
G01X271133Y147605D02*
X272542D01*
G01X270483Y146955D02*
X271133Y147605D01*
G01X270483Y145605D02*
Y146955D01*
G01X271133Y144955D02*
X270483Y145605D01*
G01X272542Y144955D02*
X271133D01*
G01X273192Y144305D02*
X272542Y144955D01*
G01X273192Y142955D02*
Y144305D01*
G01X272542Y142305D02*
X273192Y142955D01*
G01X271133Y142305D02*
X272542D01*
G01X270483Y141655D02*
X271133Y142305D01*
G01X270483Y140921D02*
Y141655D01*
G01X270504Y140900D02*
X270483Y140921D01*
G01X270504Y136000D02*
Y140900D01*
G01Y126113D02*
Y136000D01*
G01X265992Y121601D02*
X270504Y126113D01*
G01X265992Y111000D02*
Y121601D01*
G01X265192Y110200D02*
X265992Y111000D01*
G01X265192Y109609D02*
Y110200D01*
G01X267517Y107284D02*
X265192Y109609D01*
G01X245092Y155978D02*
X245742Y156628D01*
G01X244242Y155978D02*
X245092D01*
G01X243592Y155328D02*
X244242Y155978D01*
G01X243592Y153978D02*
Y155328D01*
G01X244242Y153328D02*
X243592Y153978D01*
G01X245092Y153328D02*
X244242D01*
G01X245742Y152678D02*
X245092Y153328D01*
G01X245742Y151251D02*
Y152678D01*
G01X242592Y148101D02*
X245742Y151251D01*
G01X242592Y142000D02*
Y148101D01*
G01Y111500D02*
Y142000D01*
G01X239766Y108674D02*
X242592Y111500D01*
G01X239766Y107584D02*
Y108674D01*
G01X240416Y106934D02*
X239766Y107584D01*
G01X243392Y106934D02*
X240416D01*
G01X264529Y170836D02*
X269291Y175598D01*
G01X236492Y167700D02*
X256792Y188000D01*
G01X294618Y174222D02*
X284592Y164196D01*
G01X278911Y165928D02*
X276692Y163709D01*
G01X278911Y167026D02*
Y165928D01*
G01X277639Y168298D02*
X278911Y167026D01*
G01X277639Y169396D02*
Y168298D01*
G01X278415Y170172D02*
X277639Y169396D01*
G01X279513Y170172D02*
X278415D01*
G01X280785Y168900D02*
X279513Y170172D01*
G01X281883Y168900D02*
X280785D01*
G01X290975Y177992D02*
X281883Y168900D01*
G01X258629Y186261D02*
X239202Y166834D01*
G01X258630Y186261D02*
X258629D01*
G01X292823Y176233D02*
X279492Y162902D01*
G01X261872Y171787D02*
X267487Y177402D01*
G01X258682Y163850D02*
X259182Y163350D01*
G01X256992Y163850D02*
X258682D01*
G01X256492Y163350D02*
X256992Y163850D01*
G01X267186Y169877D02*
X271099Y173790D01*
G01X296326Y172323D02*
X287292Y163289D01*
G01X255016Y189873D02*
X255018D01*
G01X243940Y178797D02*
X255016Y189873D01*
G01X243020Y178797D02*
X243940D01*
G01X242218Y179599D02*
X243020Y178797D01*
G01X241298Y179599D02*
X242218D01*
G01X240344Y178645D02*
X241298Y179599D01*
G01X240344Y177725D02*
Y178645D01*
G01X241146Y176923D02*
X240344Y177725D01*
G01X241146Y176003D02*
Y176923D01*
G01X240192Y175049D02*
X241146Y176003D01*
G01X239272Y175049D02*
X240192D01*
G01X238470Y175851D02*
X239272Y175049D01*
G01X237550Y175851D02*
X238470D01*
G01X236596Y174897D02*
X237550Y175851D01*
G01X236596Y173977D02*
Y174897D01*
G01X237398Y173175D02*
X236596Y173977D01*
G01X237398Y172255D02*
Y173175D01*
G01X233592Y168449D02*
X237398Y172255D01*
G01X270483Y169566D02*
X272903Y171986D01*
G01X270483Y161505D02*
Y169566D01*
G01X271133Y160855D02*
X270483Y161505D01*
G01X271242Y160855D02*
X271133D01*
G01X271892Y160205D02*
X271242Y160855D01*
G01X271892Y158855D02*
Y160205D01*
G01X271242Y158205D02*
X271892Y158855D01*
G01X271133Y158205D02*
X271242D01*
G01X270483Y157555D02*
X271133Y158205D01*
G01X245742Y169757D02*
X260438Y184453D01*
G01X245742Y161928D02*
Y169757D01*
G01X245092Y161278D02*
X245742Y161928D01*
G01X242642Y161278D02*
X245092D01*
G01X241992Y160628D02*
X242642Y161278D01*
G01X241992Y159278D02*
Y160628D01*
G01X242642Y158628D02*
X241992Y159278D01*
G01X245092Y158628D02*
X242642D01*
G01X245742Y157978D02*
X245092Y158628D01*
G01X245742Y156628D02*
Y157978D01*
G01X273489Y261760D02*
X271239D01*
G01X253192Y230559D02*
X262992D01*
G01X252031Y233156D02*
X264036D01*
G01X250823Y235706D02*
X264092D01*
G01X254247Y227856D02*
X262783D01*
G01X290389Y330009D02*
X288139D01*
G01X287009Y339760D02*
X284759D01*
G01X273489Y335860D02*
X271239D01*
G01X283629Y330009D02*
X281379D01*
G01X273489Y331960D02*
X271239D01*
G01X266729Y335860D02*
X264179D01*
G01X290389Y333909D02*
X288139D01*
G01X280249Y339760D02*
X277999D01*
G01X280249Y335860D02*
X277999D01*
G01X287009Y328060D02*
X284759D01*
G01X266729Y331960D02*
X264179D01*
G01X290389Y369010D02*
X288139D01*
G01X266034Y387943D02*
X264149D01*
G01X283629Y392410D02*
X281379D01*
G01X266729Y351460D02*
X264179D01*
G01X287009Y367060D02*
X284759D01*
G01X265495Y357309D02*
X257312D01*
G01X287009Y394359D02*
X284759D01*
G01X283629Y369010D02*
X281379D01*
G01X283629Y349509D02*
X281379D01*
G01X290389Y372909D02*
X288139D01*
G01X283629Y380709D02*
X281379D01*
G01X293769Y394359D02*
X291519D01*
G01X266484Y385393D02*
X262871D01*
G01X280249Y359260D02*
X277999D01*
G01X290389Y353409D02*
X288139D01*
G01X265520Y360500D02*
X257879D01*
G01X266665Y378760D02*
X261890D01*
G01X290389Y349509D02*
X288139D01*
G01X283629Y388509D02*
X281379D01*
G01X287009Y386560D02*
X284759D01*
G01X280249Y378760D02*
X277999D01*
G01X293769Y386560D02*
X291519D01*
G01X273489Y351460D02*
X271239D01*
G01X287009Y347560D02*
X284759D01*
G01X283629Y361209D02*
X281379D01*
G01X283629Y341709D02*
X281379D01*
G01X287009Y359260D02*
X284759D01*
G01X273489Y347560D02*
X271239D01*
G01X287009Y378760D02*
X284759D01*
G01X266525Y382843D02*
X261614D01*
G01X280249Y355360D02*
X277999D01*
G01X265804Y402349D02*
X237809Y430344D01*
G01X280656Y402349D02*
X265804D01*
G01X280249Y374860D02*
X277999D01*
G01X266729Y347560D02*
X264179D01*
G01X265700Y366500D02*
X259395D01*
G01X265605Y363160D02*
X258977D01*
G01X263327Y462218D02*
Y486335D01*
G01X264142Y461403D02*
X263327Y462218D01*
G01X265942Y461403D02*
X264142D01*
G01X266592Y460753D02*
X265942Y461403D01*
G01X266592Y459453D02*
Y460753D01*
G01X265942Y458803D02*
X266592Y459453D01*
G01X264142Y458803D02*
X265942D01*
G01X263492Y458153D02*
X264142Y458803D01*
G01X263492Y456853D02*
Y458153D01*
G01X264142Y456203D02*
X263492Y456853D01*
G01X265942Y456203D02*
X264142D01*
G01X266592Y455553D02*
X265942Y456203D01*
G01X266592Y454253D02*
Y455553D01*
G01X265942Y453603D02*
X266592Y454253D01*
G01X264142Y453603D02*
X265942D01*
G01X263492Y452953D02*
X264142Y453603D01*
G01X263492Y451653D02*
Y452953D01*
G01X264142Y451003D02*
X263492Y451653D01*
G01X265542Y451003D02*
X264142D01*
G01X266192Y450353D02*
X265542Y451003D01*
G01X266192Y449053D02*
Y450353D01*
G01X265542Y448403D02*
X266192Y449053D01*
G01X264242Y448403D02*
X265542D01*
G01X263453Y447614D02*
X264242Y448403D01*
G01X263453Y442690D02*
Y447614D01*
G01X281094Y425049D02*
X263453Y442690D01*
G01X284548Y425049D02*
X281094D01*
G01X282992Y464745D02*
X283567Y465320D01*
G01X282092Y464745D02*
X282992D01*
G01X281592Y464245D02*
X282092Y464745D01*
G01X281592Y462595D02*
Y464245D01*
G01X282092Y462095D02*
X281592Y462595D01*
G01X282842Y462095D02*
X282092D01*
G01X283492Y461445D02*
X282842Y462095D01*
G01X283492Y445408D02*
Y461445D01*
G01X304588Y424312D02*
X283492Y445408D01*
G01X278792Y419949D02*
X286241D01*
G01X258032Y440709D02*
X278792Y419949D01*
G01X258032Y444112D02*
Y440709D01*
G01X257238Y444906D02*
X258032Y444112D01*
G01X255852Y444906D02*
X257238D01*
G01X255175Y445583D02*
X255852Y444906D01*
G01X255175Y446893D02*
Y445583D01*
G01X255878Y447596D02*
X255175Y446893D01*
G01X257238Y447596D02*
X255878D01*
G01X257928Y448286D02*
X257238Y447596D01*
G01X257928Y451462D02*
Y448286D01*
G01X257428Y451962D02*
X257928Y451462D01*
G01X256704Y451962D02*
X257428D01*
G01X256204Y452462D02*
X256704Y451962D01*
G01X256204Y454101D02*
Y452462D01*
G01X256755Y454652D02*
X256204Y454101D01*
G01X257428Y454652D02*
X256755D01*
G01X258058Y455282D02*
X257428Y454652D01*
G01X258058Y461370D02*
Y455282D01*
G01X257229Y462199D02*
X258058Y461370D01*
G01X256045Y462199D02*
X257229D01*
G01X253595Y464649D02*
X256045Y462199D01*
G01X253595Y473250D02*
Y464649D01*
G01X278092Y462341D02*
Y487300D01*
G01X280876Y459557D02*
X278092Y462341D01*
G01X280876Y449772D02*
Y459557D01*
G01X280226Y449122D02*
X280876Y449772D01*
G01X279092Y449122D02*
X280226D01*
G01X278592Y448622D02*
X279092Y449122D01*
G01X278592Y446972D02*
Y448622D01*
G01X279092Y446472D02*
X278592Y446972D01*
G01X280226Y446472D02*
X279092D01*
G01X280876Y445822D02*
X280226Y446472D01*
G01X280876Y444374D02*
Y445822D01*
G01X301992Y423258D02*
X280876Y444374D01*
G01X275566Y459958D02*
Y488374D01*
G01X276241Y459283D02*
X275566Y459958D01*
G01X277579Y459283D02*
X276241D01*
G01X278229Y458633D02*
X277579Y459283D01*
G01X278229Y457283D02*
Y458633D01*
G01X277579Y456633D02*
X278229Y457283D01*
G01X276592Y456633D02*
X277579D01*
G01X276092Y456133D02*
X276592Y456633D01*
G01X276092Y454483D02*
Y456133D01*
G01X276592Y453983D02*
X276092Y454483D01*
G01X277579Y453983D02*
X276592D01*
G01X278229Y453333D02*
X277579Y453983D01*
G01X278229Y451983D02*
Y453333D01*
G01X277579Y451333D02*
X278229Y451983D01*
G01X276241Y451333D02*
X277579D01*
G01X275566Y450658D02*
X276241Y451333D01*
G01X275566Y446120D02*
Y450658D01*
G01X300747Y420939D02*
X275566Y446120D01*
G01X272816Y445173D02*
Y489776D01*
G01X299323Y418666D02*
X272816Y445173D01*
G01X279844Y422499D02*
X285148D01*
G01X260585Y441758D02*
X279844Y422499D01*
G01X260585Y445139D02*
Y441758D01*
G01X259860Y445864D02*
X260585Y445139D01*
G01X259860Y446634D02*
Y445864D01*
G01X260585Y447359D02*
X259860Y446634D01*
G01X260585Y453586D02*
Y447359D01*
G01X261386Y454387D02*
X260585Y453586D01*
G01X261386Y455458D02*
Y454387D01*
G01X260585Y456259D02*
X261386Y455458D01*
G01X260585Y464166D02*
Y456259D01*
G01X259895Y464856D02*
X260585Y464166D01*
G01X256241Y465571D02*
X256956Y464856D01*
G01X270802Y409999D02*
X281235D01*
G01X243292Y437509D02*
X270802Y409999D01*
G01X243292Y441158D02*
Y437509D01*
G01X242642Y441808D02*
X243292Y441158D01*
G01X241864Y441808D02*
X242642D01*
G01X241214Y442458D02*
X241864Y441808D01*
G01X241214Y443808D02*
Y442458D01*
G01X241864Y444458D02*
X241214Y443808D01*
G01X242642Y444458D02*
X241864D01*
G01X243292Y445108D02*
X242642Y444458D01*
G01X243292Y455248D02*
Y445108D01*
G01X242576Y455964D02*
X243292Y455248D01*
G01X242576Y456970D02*
Y455964D01*
G01X243292Y457686D02*
X242576Y456970D01*
G01X243292Y467318D02*
Y457686D01*
G01X282243Y427599D02*
X283848D01*
G01X269492Y440350D02*
X282243Y427599D01*
G01X269492Y442318D02*
Y440350D01*
G01X268842Y442968D02*
X269492Y442318D01*
G01X266902Y442968D02*
X268842D01*
G01X266252Y443618D02*
X266902Y442968D01*
G01X266252Y444968D02*
Y443618D01*
G01X266902Y445618D02*
X266252Y444968D01*
G01X268842Y445618D02*
X266902D01*
G01X269492Y446268D02*
X268842Y445618D01*
G01X269492Y448999D02*
Y446268D01*
G01X268792Y449699D02*
X269492Y448999D01*
G01X268792Y452239D02*
Y449699D01*
G01X269492Y452939D02*
X268792Y452239D01*
G01X269492Y456200D02*
Y452939D01*
G01X268892Y456800D02*
X269492Y456200D01*
G01X268892Y458400D02*
Y456800D01*
G01X269492Y459000D02*
X268892Y458400D01*
G01X269492Y463099D02*
Y459000D01*
G01X268691Y463900D02*
X269492Y463099D01*
G01X266392Y463900D02*
X268691D01*
G01X265892Y464400D02*
X266392Y463900D01*
G01X265892Y465881D02*
Y464400D01*
G01X240744Y463629D02*
Y464929D01*
G01X240068Y462953D02*
X240744Y463629D01*
G01X239342Y462953D02*
X240068D01*
G01X238692Y462303D02*
X239342Y462953D01*
G01X238692Y461003D02*
Y462303D01*
G01X239342Y460353D02*
X238692Y461003D01*
G01X239842Y460353D02*
X239342D01*
G01X240492Y459703D02*
X239842Y460353D01*
G01X240492Y458403D02*
Y459703D01*
G01X239842Y457753D02*
X240492Y458403D01*
G01X239342Y457753D02*
X239842D01*
G01X238692Y457103D02*
X239342Y457753D01*
G01X238692Y455803D02*
Y457103D01*
G01X239342Y455153D02*
X238692Y455803D01*
G01X239842Y455153D02*
X239342D01*
G01X240492Y454503D02*
X239842Y455153D01*
G01X240492Y453203D02*
Y454503D01*
G01X239842Y452553D02*
X240492Y453203D01*
G01X239342Y452553D02*
X239842D01*
G01X238692Y451903D02*
X239342Y452553D01*
G01X238692Y450603D02*
Y451903D01*
G01X239342Y449953D02*
X238692Y450603D01*
G01X239842Y449953D02*
X239342D01*
G01X240492Y449303D02*
X239842Y449953D01*
G01X240492Y448003D02*
Y449303D01*
G01X239842Y447353D02*
X240492Y448003D01*
G01X239342Y447353D02*
X239842D01*
G01X238692Y446703D02*
X239342Y447353D01*
G01X238692Y441679D02*
Y446703D01*
G01X240909Y436328D02*
X238692Y441679D01*
G01X269788Y407449D02*
X240909Y436328D01*
G01X281235Y407449D02*
X269788D01*
G01X231492Y445593D02*
Y497100D01*
G01X237809Y430344D02*
X231492Y445593D01*
G01X234092Y463700D02*
X236171Y465779D01*
G01X234092Y462100D02*
Y463700D01*
G01X236171Y460021D02*
X234092Y462100D01*
G01X236171Y458579D02*
Y460021D01*
G01X234092Y456500D02*
X236171Y458579D01*
G01X234092Y454900D02*
Y456500D01*
G01X235992Y453000D02*
X234092Y454900D01*
G01X235992Y450300D02*
Y453000D01*
G01X234092Y448400D02*
X235992Y450300D01*
G01X234092Y446111D02*
Y448400D01*
G01X239489Y433081D02*
X234092Y446111D01*
G01X267671Y404899D02*
X239489Y433081D01*
G01X280174Y404899D02*
X267671D01*
G01X264171Y523900D02*
Y528899D01*
G01X234053Y523900D02*
Y528899D01*
G01X265084Y499400D02*
X264171Y498487D01*
G01X266492Y499400D02*
X265084D01*
G01X267392Y498500D02*
X266492Y499400D01*
G01X267392Y496500D02*
Y498500D01*
G01X265692Y494800D02*
X267392Y496500D01*
G01X265692Y493100D02*
Y494800D01*
G01X265292Y492700D02*
X265692Y493100D01*
G01X265292Y488300D02*
Y492700D01*
G01X263327Y486335D02*
X265292Y488300D01*
G01X282166Y491281D02*
X280203Y493244D01*
G01X282166Y489658D02*
Y491281D01*
G01X283020Y488804D02*
X282166Y489658D01*
G01X283020Y487242D02*
Y488804D01*
G01X282370Y486592D02*
X283020Y487242D01*
G01X281502Y486592D02*
X282370D01*
G01X280852Y485942D02*
X281502Y486592D01*
G01X280852Y484592D02*
Y485942D01*
G01X281502Y483942D02*
X280852Y484592D01*
G01X282370Y483942D02*
X281502D01*
G01X283020Y483292D02*
X282370Y483942D01*
G01X283020Y481942D02*
Y483292D01*
G01X282370Y481292D02*
X283020Y481942D01*
G01X281502Y481292D02*
X282370D01*
G01X280852Y480642D02*
X281502Y481292D01*
G01X280852Y479292D02*
Y480642D01*
G01X281502Y478642D02*
X280852Y479292D01*
G01X282566Y478642D02*
X281502D01*
G01X283492Y477716D02*
X282566Y478642D01*
G01X283492Y475995D02*
Y477716D01*
G01X282842Y475345D02*
X283492Y475995D01*
G01X281476Y475345D02*
X282842D01*
G01X280826Y474695D02*
X281476Y475345D01*
G01X280826Y473345D02*
Y474695D01*
G01X281476Y472695D02*
X280826Y473345D01*
G01X282918Y472695D02*
X281476D01*
G01X283593Y472020D02*
X282918Y472695D01*
G01X283593Y470670D02*
Y472020D01*
G01X282968Y470045D02*
X283593Y470670D01*
G01X281476Y470045D02*
X282968D01*
G01X280826Y469395D02*
X281476Y470045D01*
G01X280826Y468045D02*
Y469395D01*
G01X281476Y467395D02*
X280826Y468045D01*
G01X282842Y467395D02*
X281476D01*
G01X283567Y466670D02*
X282842Y467395D01*
G01X283567Y465320D02*
Y466670D01*
G01X255892Y475547D02*
X253595Y473250D01*
G01X255892Y486100D02*
Y475547D01*
G01X258992Y489200D02*
X255892Y486100D01*
G01X258992Y494700D02*
Y489200D01*
G01X259392Y495100D02*
X258992Y494700D01*
G01X259392Y496573D02*
Y495100D01*
G01X257478Y498487D02*
X259392Y496573D01*
G01X279392Y496809D02*
X277557Y498644D01*
G01X279392Y495000D02*
Y496809D01*
G01X278366Y493974D02*
X279392Y495000D01*
G01X278366Y487574D02*
Y493974D01*
G01X278092Y487300D02*
X278366Y487574D01*
G01X257478Y523900D02*
Y528899D01*
G01X274692Y493744D02*
X273992D01*
G01X275792Y492644D02*
X274692Y493744D01*
G01X275792Y488600D02*
Y492644D01*
G01X275566Y488374D02*
X275792Y488600D01*
G01X271847Y498644D02*
X271092D01*
G01X272892Y497599D02*
X271847Y498644D01*
G01X272892Y495201D02*
Y497599D01*
G01X272092Y494401D02*
X272892Y495201D01*
G01X272092Y490500D02*
Y494401D01*
G01X272816Y489776D02*
X272092Y490500D01*
G01X277557Y523900D02*
Y528899D01*
G01X270864Y523900D02*
Y528899D01*
G01X256956Y464856D02*
X259895D01*
G01X256241Y466881D02*
Y465571D01*
G01X256906Y467546D02*
X256241Y466881D01*
G01X260185Y467546D02*
X256906D01*
G01X260787Y468148D02*
X260185Y467546D01*
G01X260787Y469596D02*
Y468148D01*
G01X260147Y470236D02*
X260787Y469596D01*
G01X256829Y470236D02*
X260147D01*
G01X256165Y470900D02*
X256829Y470236D01*
G01X256165Y472210D02*
Y470900D01*
G01X256881Y472926D02*
X256165Y472210D01*
G01X260044Y472926D02*
X256881D01*
G01X260785Y473667D02*
X260044Y472926D01*
G01X260785Y474977D02*
Y473667D01*
G01X260146Y475616D02*
X260785Y474977D01*
G01X259182Y475616D02*
X260146D01*
G01X258492Y476306D02*
X259182Y475616D01*
G01X258492Y477616D02*
Y476306D01*
G01X259182Y478306D02*
X258492Y477616D01*
G01X260071Y478306D02*
X259182D01*
G01X260787Y479022D02*
X260071Y478306D01*
G01X260787Y480332D02*
Y479022D01*
G01X260123Y480996D02*
X260787Y480332D01*
G01X259182Y480996D02*
X260123D01*
G01X258492Y481686D02*
X259182Y480996D01*
G01X258492Y482996D02*
Y481686D01*
G01X259182Y483686D02*
X258492Y482996D01*
G01X259895Y483686D02*
X259182D01*
G01X260585Y484376D02*
X259895Y483686D01*
G01X260585Y487193D02*
Y484376D01*
G01X262692Y489300D02*
X260585Y487193D01*
G01X262692Y493244D02*
Y489300D01*
G01X262192Y493744D02*
X262692Y493244D01*
G01X260824Y493744D02*
X262192D01*
G01X242642Y467968D02*
X243292Y467318D01*
G01X241866Y467968D02*
X242642D01*
G01X241216Y468618D02*
X241866Y467968D01*
G01X241216Y469918D02*
Y468618D01*
G01X241866Y470568D02*
X241216Y469918D01*
G01X242818Y470568D02*
X241866D01*
G01X243468Y471218D02*
X242818Y470568D01*
G01X243468Y472518D02*
Y471218D01*
G01X242818Y473168D02*
X243468Y472518D01*
G01X241866Y473168D02*
X242818D01*
G01X241216Y473818D02*
X241866Y473168D01*
G01X241216Y475118D02*
Y473818D01*
G01X241866Y475768D02*
X241216Y475118D01*
G01X242819Y475768D02*
X241866D01*
G01X243469Y476418D02*
X242819Y475768D01*
G01X243469Y477718D02*
Y476418D01*
G01X242819Y478368D02*
X243469Y477718D01*
G01X241865Y478368D02*
X242819D01*
G01X241215Y479018D02*
X241865Y478368D01*
G01X241215Y480318D02*
Y479018D01*
G01X241865Y480968D02*
X241215Y480318D01*
G01X242843Y480968D02*
X241865D01*
G01X243443Y481568D02*
X242843Y480968D01*
G01X243443Y482868D02*
Y481568D01*
G01X242743Y483568D02*
X243443Y482868D01*
G01X241865Y483568D02*
X242743D01*
G01X241292Y484141D02*
X241865Y483568D01*
G01X241292Y485598D02*
Y484141D01*
G01X241892Y486198D02*
X241292Y485598D01*
G01X242932Y486198D02*
X241892D01*
G01X243432Y486698D02*
X242932Y486198D01*
G01X243432Y488098D02*
Y486698D01*
G01X242792Y488738D02*
X243432Y488098D01*
G01X241878Y488738D02*
X242792D01*
G01X241378Y489238D02*
X241878Y488738D01*
G01X241378Y490688D02*
Y489238D01*
G01X241978Y491288D02*
X241378Y490688D01*
G01X244892Y491288D02*
X241978D01*
G01X245392Y491788D02*
X244892Y491288D01*
G01X245392Y495116D02*
Y491788D01*
G01X244814Y495694D02*
X245392Y495116D01*
G01X243392Y495694D02*
X244814D01*
G01X266542Y466531D02*
X265892Y465881D01*
G01X268842Y466531D02*
X266542D01*
G01X269492Y467181D02*
X268842Y466531D01*
G01X269492Y468531D02*
Y467181D01*
G01X268842Y469181D02*
X269492Y468531D01*
G01X266542Y469181D02*
X268842D01*
G01X265892Y469831D02*
X266542Y469181D01*
G01X265892Y471181D02*
Y469831D01*
G01X266542Y471831D02*
X265892Y471181D01*
G01X268842Y471831D02*
X266542D01*
G01X269492Y472481D02*
X268842Y471831D01*
G01X269492Y473831D02*
Y472481D01*
G01X268842Y474481D02*
X269492Y473831D01*
G01X266542Y474481D02*
X268842D01*
G01X265892Y475131D02*
X266542Y474481D01*
G01X265892Y476481D02*
Y475131D01*
G01X266542Y477131D02*
X265892Y476481D01*
G01X268842Y477131D02*
X266542D01*
G01X269492Y477781D02*
X268842Y477131D01*
G01X269492Y479131D02*
Y477781D01*
G01X268842Y479781D02*
X269492Y479131D01*
G01X266542Y479781D02*
X268842D01*
G01X265892Y480431D02*
X266542Y479781D01*
G01X265892Y481884D02*
Y480431D01*
G01X266392Y482384D02*
X265892Y481884D01*
G01X268792Y482384D02*
X266392D01*
G01X269492Y483084D02*
X268792Y482384D01*
G01X269492Y484384D02*
Y483084D01*
G01X268892Y484984D02*
X269492Y484384D01*
G01X268159Y484984D02*
X268892D01*
G01X267492Y485651D02*
X268159Y484984D01*
G01X267492Y487056D02*
Y485651D01*
G01X268286Y487850D02*
X267492Y487056D01*
G01X268992Y487850D02*
X268286D01*
G01X269492Y488350D02*
X268992Y487850D01*
G01X269492Y493700D02*
Y488350D01*
G01X268992Y494200D02*
X269492Y493700D01*
G01X267865Y494200D02*
X268992D01*
G01X267584Y493919D02*
X267865Y494200D01*
G01X238692Y495000D02*
X239592Y495900D01*
G01X238692Y466203D02*
Y495000D01*
G01X239342Y465553D02*
X238692Y466203D01*
G01X240120Y465553D02*
X239342D01*
G01X240744Y464929D02*
X240120Y465553D01*
G01X240746Y523900D02*
Y528899D01*
G01X232892Y498500D02*
X233292D01*
G01X235492Y489400D02*
X236892Y490800D01*
G01X235492Y485401D02*
Y489400D01*
G01X234092Y484001D02*
X235492Y485401D01*
G01X234092Y482301D02*
Y484001D01*
G01X235792Y480601D02*
X234092Y482301D01*
G01X235792Y479300D02*
Y480601D01*
G01X234092Y477600D02*
X235792Y479300D01*
G01X234092Y476000D02*
Y477600D01*
G01X236171Y473921D02*
X234092Y476000D01*
G01X236171Y472779D02*
Y473921D01*
G01X234092Y470700D02*
X236171Y472779D01*
G01X234092Y469200D02*
Y470700D01*
G01X236171Y467121D02*
X234092Y469200D01*
G01X236171Y465779D02*
Y467121D01*
G01X237399Y536792D02*
X237013Y534700D01*
G01X237399Y542010D02*
Y536792D01*
G01X267517Y573992D02*
Y572900D01*
G01X268035Y574510D02*
X267517Y573992D01*
G01X268035Y575390D02*
Y574510D01*
G01X267517Y575908D02*
X268035Y575390D01*
G01X267517Y579810D02*
Y575908D01*
G01X267518Y579810D02*
X267517D01*
G01X277557Y561700D02*
Y566699D01*
G01X244092Y542033D02*
X243392Y534700D01*
G01X244092Y542010D02*
Y542033D01*
G01X260825Y572901D02*
X260824Y572900D01*
G01X260825Y574100D02*
Y572901D01*
G01X261345Y574620D02*
X260825Y574100D01*
G01X261345Y575480D02*
Y574620D01*
G01X260825Y576000D02*
X261345Y575480D01*
G01X260825Y579810D02*
Y576000D01*
G01X280903Y579833D02*
X280203Y572500D01*
G01X280903Y579810D02*
Y579833D01*
G01X270864Y561700D02*
Y566699D01*
G01X274210Y574592D02*
X273824Y572500D01*
G01X274210Y579810D02*
Y574592D01*
G01X257478Y561700D02*
Y566699D01*
G01X240746Y561700D02*
Y566699D01*
G01X267517Y536192D02*
Y535100D01*
G01X268035Y536710D02*
X267517Y536192D01*
G01X268035Y537590D02*
Y536710D01*
G01X267517Y538108D02*
X268035Y537590D01*
G01X267517Y542010D02*
Y538108D01*
G01X267518Y542010D02*
X267517D01*
G01X260825Y535101D02*
X260824Y535100D01*
G01X260825Y536300D02*
Y535101D01*
G01X261345Y536820D02*
X260825Y536300D01*
G01X261345Y537680D02*
Y536820D01*
G01X260825Y538200D02*
X261345Y537680D01*
G01X260825Y542010D02*
Y538200D01*
G01X264171Y561700D02*
Y566699D01*
G01X280903Y542033D02*
X280203Y534700D01*
G01X280903Y542010D02*
Y542033D01*
G01X244092Y579833D02*
X243392Y572500D01*
G01X244092Y579810D02*
Y579833D01*
G01X237399Y574592D02*
X237013Y572500D01*
G01X237399Y579810D02*
Y574592D01*
G01X274210Y536792D02*
X273824Y534700D01*
G01X274210Y542010D02*
Y536792D01*
G01X234053Y561700D02*
Y566699D01*
G01X237399Y612392D02*
X237013Y610300D01*
G01X237399Y617610D02*
Y612392D01*
G01X280903Y617633D02*
X280203Y610300D01*
G01X280903Y617610D02*
Y617633D01*
G01X257478Y599500D02*
Y604499D01*
G01X274210Y612392D02*
X273824Y610300D01*
G01X274210Y617610D02*
Y612392D01*
G01X264171Y599500D02*
Y604499D01*
G01X260825Y610701D02*
X260824Y610700D01*
G01X260825Y611900D02*
Y610701D01*
G01X261345Y612420D02*
X260825Y611900D01*
G01X261345Y613280D02*
Y612420D01*
G01X260825Y613800D02*
X261345Y613280D01*
G01X260825Y617610D02*
Y613800D01*
G01X240746Y599500D02*
Y604499D01*
G01X270864Y599500D02*
Y604499D01*
G01X234053Y599500D02*
Y604499D01*
G01X244092Y617633D02*
X243392Y610300D01*
G01X244092Y617610D02*
Y617633D01*
G01X277557Y599500D02*
Y604499D01*
G01X267517Y611792D02*
Y610700D01*
G01X268035Y612310D02*
X267517Y611792D01*
G01X268035Y613190D02*
Y612310D01*
G01X267517Y613708D02*
X268035Y613190D01*
G01X267517Y617610D02*
Y613708D01*
G01X267518Y617610D02*
X267517D01*
G01X294289Y22923D02*
Y27899D01*
G01X324407Y-14877D02*
Y-9901D01*
G01X327754Y3233D02*
Y-1743D01*
G01X321061Y-14877D02*
Y-7108D01*
G01X304328Y-2608D02*
Y-3700D01*
G01X304846Y-2090D02*
X304328Y-2608D01*
G01X304846Y-1210D02*
Y-2090D01*
G01X304328Y-692D02*
X304846Y-1210D01*
G01X304328Y3232D02*
Y-692D01*
G01X304329Y3233D02*
X304328Y3232D01*
G01X331100Y28014D02*
Y22923D01*
G01X334447Y3233D02*
Y-1743D01*
G01X300982Y-14877D02*
Y-9901D01*
G01X331100Y-14877D02*
Y-9786D01*
G01X314368Y-14877D02*
Y-7108D01*
G01X344486Y-14877D02*
Y-9786D01*
G01X334447Y28013D02*
X334446Y28014D01*
G01X334447Y22923D02*
Y28013D01*
G01X354525Y3233D02*
Y-1742D01*
G01X347833Y3233D02*
Y-1743D01*
G01X334447Y-14877D02*
Y-7108D01*
G01X297636Y-3699D02*
X297635Y-3700D01*
G01X297636Y-2500D02*
Y-3699D01*
G01X298156Y-1980D02*
X297636Y-2500D01*
G01X298156Y-1120D02*
Y-1980D01*
G01X297636Y-600D02*
X298156Y-1120D01*
G01X297636Y3233D02*
Y-600D01*
G01X344486Y3233D02*
Y-4536D01*
G01X311021Y3233D02*
Y-4536D01*
G01X341140Y-14877D02*
Y-7108D01*
G01X294289Y-14877D02*
Y-9901D01*
G01X337793Y3233D02*
Y-4536D01*
G01X351179Y28022D02*
Y22923D01*
G01X300982D02*
Y27899D01*
G01X354525Y28022D02*
Y22923D01*
G01X341140Y28022D02*
Y22923D01*
G01X354526Y-14876D02*
Y-7108D01*
G01X354525Y-14877D02*
X354526Y-14876D01*
G01X324407Y3233D02*
Y-4536D01*
G01Y22923D02*
Y28014D01*
G01X344486Y22923D02*
Y28022D01*
G01X321061Y22923D02*
Y28014D01*
G01X351179Y-14877D02*
Y-9901D01*
G01X314368Y22923D02*
Y28014D01*
G01X324407Y78833D02*
Y73757D01*
G01X351179Y65822D02*
Y60723D01*
G01X352083Y89964D02*
X351179D01*
G01X352640Y90521D02*
X352083Y89964D01*
G01X352640Y93890D02*
Y90521D01*
G01X351677Y94853D02*
X352640Y93890D01*
G01X314368Y60723D02*
Y65814D01*
G01X344486Y41033D02*
Y35957D01*
G01X334447Y65813D02*
X334446Y65814D01*
G01X334447Y60723D02*
Y65813D01*
G01X300982Y60723D02*
Y65699D01*
G01X354526Y36057D02*
Y35957D01*
G01X354525Y36058D02*
X354526Y36057D01*
G01X354525Y41033D02*
Y36058D01*
G01X337793Y41033D02*
Y35957D01*
G01X341140Y94559D02*
Y92757D01*
G01X341790Y95209D02*
X341140Y94559D01*
G01Y65822D02*
Y60723D01*
G01X324407Y41033D02*
Y35957D01*
G01X314368Y92657D02*
Y97176D01*
G01X344486Y78833D02*
Y73757D01*
G01Y86894D02*
Y84714D01*
G01X346311Y88719D02*
X344486Y86894D01*
G01X346311Y91749D02*
Y88719D01*
G01X346008Y92052D02*
X346311Y91749D01*
G01X346008Y93514D02*
Y92052D01*
G01X347592Y95098D02*
X346008Y93514D01*
G01X321061Y92757D02*
Y96269D01*
G01Y60723D02*
Y65814D01*
G01X304328Y72992D02*
Y71900D01*
G01X304846Y73510D02*
X304328Y72992D01*
G01X304846Y74390D02*
Y73510D01*
G01X304328Y74908D02*
X304846Y74390D01*
G01X304328Y78832D02*
Y74908D01*
G01X304329Y78833D02*
X304328Y78832D01*
G01X354415Y92757D02*
Y94785D01*
G01X354525Y65822D02*
Y60723D01*
G01X343292Y93627D02*
X345492Y95827D01*
G01X343292Y92382D02*
Y93627D01*
G01X341965Y91055D02*
X343292Y92382D01*
G01X341965Y89956D02*
Y91055D01*
G01X342761Y89160D02*
X341965Y89956D01*
G01X343682Y89160D02*
X342761D01*
G01X344486Y89964D02*
X343682Y89160D01*
G01X344486Y60723D02*
Y65822D01*
G01X354526Y73857D02*
Y73757D01*
G01X354525Y73858D02*
X354526Y73857D01*
G01X354525Y78833D02*
Y73858D01*
G01X355480Y87392D02*
X354415D01*
G01X331100Y65814D02*
Y60723D01*
G01X334447Y41033D02*
Y35957D01*
G01X310192Y91900D02*
Y99500D01*
G01X308992Y90700D02*
X310192Y91900D01*
G01X308992Y89400D02*
Y90700D01*
G01X309992Y88400D02*
X308992Y89400D01*
G01X309992Y86600D02*
Y88400D01*
G01X308692Y85300D02*
X309992Y86600D01*
G01X308692Y84100D02*
Y85300D01*
G01X311021Y81771D02*
X308692Y84100D01*
G01X311021Y78833D02*
Y81771D01*
G01X337892Y93100D02*
Y113956D01*
G01X335792Y91000D02*
X337892Y93100D01*
G01X335792Y89300D02*
Y91000D01*
G01X337793Y87299D02*
X335792Y89300D01*
G01X337793Y84599D02*
Y87299D01*
G01Y78833D02*
Y73757D01*
G01X327754Y78833D02*
Y73757D01*
G01Y89804D02*
X335792Y97842D01*
G01X327754Y87392D02*
Y89804D01*
G01X311021Y41033D02*
Y35957D01*
G01X294289Y60723D02*
Y65699D01*
G01X297636Y71901D02*
X297635Y71900D01*
G01X297636Y73100D02*
Y71901D01*
G01X298156Y73620D02*
X297636Y73100D01*
G01X298156Y74480D02*
Y73620D01*
G01X297636Y75000D02*
X298156Y74480D01*
G01X297636Y78833D02*
Y75000D01*
G01X324407Y60723D02*
Y65814D01*
G01Y89964D02*
Y94982D01*
G01X347833Y41033D02*
Y35957D01*
G01Y78833D02*
Y73757D01*
G01X348766Y88325D02*
X347833Y87392D01*
G01X348766Y90674D02*
Y88325D01*
G01X349692Y91600D02*
X348766Y90674D01*
G01X349692Y108643D02*
Y91600D01*
G01X327754Y41033D02*
Y35957D01*
G01X304328Y35192D02*
Y34100D01*
G01X304846Y35710D02*
X304328Y35192D01*
G01X304846Y36590D02*
Y35710D01*
G01X304328Y37108D02*
X304846Y36590D01*
G01X304328Y41032D02*
Y37108D01*
G01X304329Y41033D02*
X304328Y41032D01*
G01X312292Y85985D02*
X311021Y84714D01*
G01X312292Y88500D02*
Y85985D01*
G01X312992Y89200D02*
X312292Y88500D01*
G01X312992Y90700D02*
Y89200D01*
G01X312192Y91500D02*
X312992Y90700D01*
G01X312192Y98599D02*
Y91500D01*
G01X334447Y78833D02*
Y73757D01*
G01X297636Y34101D02*
X297635Y34100D01*
G01X297636Y35300D02*
Y34101D01*
G01X298156Y35820D02*
X297636Y35300D01*
G01X298156Y36680D02*
Y35820D01*
G01X297636Y37200D02*
X298156Y36680D01*
G01X297636Y41033D02*
Y37200D01*
G01X294946Y105084D02*
X297635D01*
G01X294472Y105558D02*
X294946Y105084D01*
G01X294472Y107480D02*
Y105558D01*
G01X297592Y110600D02*
X294472Y107480D01*
G01X297592Y115050D02*
Y110600D01*
G01X299507Y116965D02*
X297592Y115050D01*
G01X301257Y116965D02*
X299507D01*
G01X302301Y118009D02*
X301257Y116965D01*
G01X302301Y119759D02*
Y118009D01*
G01X303255Y120713D02*
X302301Y119759D01*
G01X304175Y120713D02*
X303255D01*
G01X305130Y119758D02*
X304175Y120713D01*
G01X306050Y119758D02*
X305130D01*
G01X307004Y120712D02*
X306050Y119758D01*
G01X307004Y121632D02*
Y120712D01*
G01X306049Y122587D02*
X307004Y121632D01*
G01X306049Y123507D02*
Y122587D01*
G01X307742Y125200D02*
X306049Y123507D01*
G01X307742Y130150D02*
Y125200D01*
G01X312742Y135150D02*
X307742Y130150D01*
G01X312742Y145150D02*
Y135150D01*
G01X310592Y147300D02*
X312742Y145150D01*
G01X306992Y147300D02*
X310592D01*
G01X304592Y149700D02*
X306992Y147300D01*
G01X304592Y162854D02*
Y149700D01*
G01X361912Y122486D02*
X353842Y114416D01*
G01X351677Y112251D02*
Y94853D01*
G01X353842Y114416D02*
X351677Y112251D01*
G01X329573Y105502D02*
Y107022D01*
G01X327092Y103021D02*
X329573Y105502D01*
G01X344047Y134397D02*
Y186736D01*
G01X329573Y119923D02*
X344047Y134397D01*
G01X329573Y107022D02*
Y119923D01*
G01X342335Y95209D02*
X341790D01*
G01X343176Y96050D02*
X342335Y95209D01*
G01X343176Y97191D02*
Y96050D01*
G01X342438Y97929D02*
X343176Y97191D01*
G01X340403Y97929D02*
X342438D01*
G01X339903Y98429D02*
X340403Y97929D01*
G01X339903Y99807D02*
Y98429D01*
G01X340600Y100504D02*
X339903Y99807D01*
G01X342786Y100504D02*
X340600D01*
G01X343436Y101154D02*
X342786Y100504D01*
G01X343436Y102454D02*
Y101154D01*
G01X342786Y103104D02*
X343436Y102454D01*
G01X340776Y103104D02*
X342786D01*
G01X340201Y103679D02*
X340776Y103104D01*
G01X340201Y104979D02*
Y103679D01*
G01X340926Y105704D02*
X340201Y104979D01*
G01X342725Y105704D02*
X340926D01*
G01X343375Y106354D02*
X342725Y105704D01*
G01X343375Y107614D02*
Y106354D01*
G01X342685Y108304D02*
X343375Y107614D01*
G01X340377Y108304D02*
X342685D01*
G01X339877Y108804D02*
X340377Y108304D01*
G01X339877Y110258D02*
Y108804D01*
G01X340527Y110908D02*
X339877Y110258D01*
G01X341883Y110908D02*
X340527D01*
G01X342518Y111543D02*
X341883Y110908D01*
G01X342518Y112893D02*
Y111543D01*
G01X341853Y113558D02*
X342518Y112893D01*
G01X340836Y113558D02*
X341853D01*
G01X340230Y114164D02*
X340836Y113558D01*
G01X340230Y115920D02*
Y114164D01*
G01X353972Y129662D02*
X340230Y115920D01*
G01X353972Y186457D02*
Y129662D01*
G01X320042Y104150D02*
X324046Y108154D01*
G01X320042Y102850D02*
Y104150D01*
G01X314368Y97176D02*
X320042Y102850D01*
G01X342062Y135371D02*
Y182619D01*
G01X326792Y120101D02*
X342062Y135371D01*
G01X326792Y110900D02*
Y120101D01*
G01X324046Y108154D02*
X326792Y110900D01*
G01X347592Y113784D02*
Y103993D01*
G01X357942Y124134D02*
X347592Y113784D01*
G01Y103993D02*
Y95098D01*
G01X331592Y104700D02*
Y114748D01*
G01X325892Y99000D02*
X331592Y104700D01*
G01X323792Y99000D02*
X325892D01*
G01X321061Y96269D02*
X323792Y99000D01*
G01X346032Y133419D02*
Y186625D01*
G01X331592Y118979D02*
X346032Y133419D01*
G01X331592Y114748D02*
Y118979D01*
G01X353714Y96478D02*
Y103936D01*
G01X354415Y94785D02*
X353714Y96478D01*
G01Y111479D02*
X363897Y121662D01*
G01X353714Y103936D02*
Y111479D01*
G01X345492Y95827D02*
Y112063D01*
G01X354757Y127368D02*
X355957Y128568D01*
G01X354757Y126449D02*
Y127368D01*
G01X355644Y125562D02*
X354757Y126449D01*
G01X354723Y123723D02*
X355644Y124644D01*
G01X353806Y123723D02*
X354723D01*
G01X352784Y124745D02*
X353806Y123723D01*
G01X351864Y124745D02*
X352784D01*
G01X351026Y123907D02*
X351864Y124745D01*
G01X351026Y122825D02*
Y123907D01*
G01X351966Y121885D02*
X351026Y122825D01*
G01X351966Y120966D02*
Y121885D01*
G01X351045Y120045D02*
X351966Y120966D01*
G01X350128Y120045D02*
X351045D01*
G01X349240Y120933D02*
X350128Y120045D01*
G01X348322Y120933D02*
X349240D01*
G01X347401Y120012D02*
X348322Y120933D01*
G01X347401Y119093D02*
Y120012D01*
G01X348288Y118206D02*
X347401Y119093D01*
G01X348288Y117288D02*
Y118206D01*
G01X345492Y114492D02*
X348288Y117288D01*
G01X345492Y112063D02*
Y114492D01*
G01X315892Y106500D02*
X317912Y108520D01*
G01X315892Y105200D02*
Y106500D01*
G01X310192Y99500D02*
X315892Y105200D01*
G01X338092Y138156D02*
Y182563D01*
G01X336912Y136976D02*
X338092Y138156D01*
G01X336203Y136976D02*
X336912D01*
G01X334930Y138249D02*
X336203Y136976D01*
G01X333985Y138249D02*
X334930D01*
G01X333031Y137295D02*
X333985Y138249D01*
G01X333031Y136400D02*
Y137295D01*
G01X334707Y134724D02*
X333031Y136400D01*
G01X334707Y134015D02*
Y134724D01*
G01X322692Y122000D02*
X334707Y134015D01*
G01X322692Y113300D02*
Y122000D01*
G01X317912Y108520D02*
X322692Y113300D01*
G01X351987Y130485D02*
Y186312D01*
G01X337892Y116390D02*
X351987Y130485D01*
G01X337892Y113956D02*
Y116390D01*
G01X350002Y131463D02*
Y186360D01*
G01X335792Y117253D02*
X350002Y131463D01*
G01X335792Y104069D02*
Y117253D01*
G01Y97842D02*
Y104069D01*
G01X348017Y132441D02*
Y186310D01*
G01X333692Y118116D02*
X348017Y132441D01*
G01X333692Y110190D02*
Y118116D01*
G01Y103904D02*
Y110190D01*
G01X332246Y102458D02*
X333692Y103904D01*
G01X332246Y101538D02*
Y102458D01*
G01X333270Y100514D02*
X332246Y101538D01*
G01X333270Y99806D02*
Y100514D01*
G01X332139Y98675D02*
X333270Y99806D01*
G01X331431Y98675D02*
X332139D01*
G01X330407Y99699D02*
X331431Y98675D01*
G01X329487Y99699D02*
X330407D01*
G01X328568Y98780D02*
X329487Y99699D01*
G01X328568Y97860D02*
Y98780D01*
G01X329443Y96985D02*
X328568Y97860D01*
G01X329443Y96277D02*
Y96985D01*
G01X328312Y95146D02*
X329443Y96277D01*
G01X327604Y95146D02*
X328312D01*
G01X326758Y95992D02*
X327604Y95146D01*
G01X325417Y95992D02*
X326758D01*
G01X324407Y94982D02*
X325417Y95992D01*
G01X305826Y107684D02*
X313267Y115125D01*
G01X304178Y107684D02*
X305826D01*
G01X311092Y155700D02*
X310388Y156404D01*
G01X312192Y155700D02*
X311092D01*
G01X313192Y156700D02*
X312192Y155700D01*
G01X316192Y155000D02*
Y160050D01*
G01X323192Y148000D02*
X316192Y155000D01*
G01X323192Y132750D02*
Y148000D01*
G01X314492Y124050D02*
X323192Y132750D01*
G01X314492Y116350D02*
Y124050D01*
G01X313267Y115125D02*
X314492Y116350D01*
G01X349692Y113075D02*
Y108643D01*
G01X359927Y123310D02*
X349692Y113075D01*
G01X303442Y109700D02*
X305817Y112075D01*
G01X300982Y109700D02*
X303442D01*
G01X307692Y152450D02*
Y160497D01*
G01X309642Y150500D02*
X307692Y152450D01*
G01X311869Y150500D02*
X309642D01*
G01X315992Y146377D02*
X311869Y150500D01*
G01X319992Y146377D02*
X315992D01*
G01X320642Y145727D02*
X319992Y146377D01*
G01X320642Y137750D02*
Y145727D01*
G01X319992Y137100D02*
X320642Y137750D01*
G01X318642Y137100D02*
X319992D01*
G01X317992Y137750D02*
X318642Y137100D01*
G01X317992Y141600D02*
Y137750D01*
G01X317342Y142250D02*
X317992Y141600D01*
G01X315992Y142250D02*
X317342D01*
G01X315342Y141600D02*
X315992Y142250D01*
G01X315342Y134000D02*
Y141600D01*
G01X310992Y129650D02*
X315342Y134000D01*
G01X310992Y117250D02*
Y129650D01*
G01X305817Y112075D02*
X310992Y117250D01*
G01X324692Y121000D02*
Y114882D01*
G01X340077Y136385D02*
X324692Y121000D01*
G01X340077Y182436D02*
Y136385D01*
G01X317892Y104299D02*
X312192Y98599D01*
G01X317892Y105500D02*
Y104299D01*
G01X324692Y112300D02*
X317892Y105500D01*
G01X324692Y114882D02*
Y112300D01*
G01X294889Y116147D02*
Y110927D01*
G01X304742Y126000D02*
X294889Y116147D01*
G01X304742Y140800D02*
Y126000D01*
G01X305242Y141300D02*
X304742Y140800D01*
G01X306892Y141300D02*
X305242D01*
G01X307392Y140800D02*
X306892Y141300D01*
G01X307392Y136350D02*
Y140800D01*
G01X308042Y135700D02*
X307392Y136350D01*
G01X309392Y135700D02*
X308042D01*
G01X310042Y136350D02*
X309392Y135700D01*
G01X310042Y144000D02*
Y136350D01*
G01X309542Y144500D02*
X310042Y144000D01*
G01X305693Y144500D02*
X309542D01*
G01X301942Y148251D02*
X305693Y144500D01*
G01X301942Y163795D02*
Y148251D01*
G01X305358Y163620D02*
X304592Y162854D01*
G01X341088Y210239D02*
X342218Y209109D01*
G01X341088Y211060D02*
Y210239D01*
G01X310388Y156404D02*
Y160796D01*
G01X313192Y160050D02*
Y156700D01*
G01X313692Y160550D02*
X313192Y160050D01*
G01X315692Y160550D02*
X313692D01*
G01X316192Y160050D02*
X315692Y160550D01*
G01X307692Y160497D02*
X307968Y160773D01*
G01X303258Y165111D02*
X301942Y163795D01*
G01X347848Y230559D02*
X345598D01*
G01X344468Y224709D02*
X342218D01*
G01X327568Y331960D02*
X325318D01*
G01X300529Y335860D02*
X298279D01*
G01X317428Y326110D02*
X315178D01*
G01X307289Y335860D02*
X305039D01*
G01X314048Y328060D02*
X311798D01*
G01X307289Y339760D02*
X305039D01*
G01X303909Y333909D02*
X301659D01*
G01X341088Y335860D02*
X338838D01*
G01X324188Y326110D02*
X321938D01*
G01X314048Y331960D02*
X311798D01*
G01X327568Y328060D02*
X325318D01*
G01X334328Y335860D02*
X332078D01*
G01X317428Y333909D02*
X315178D01*
G01X324188D02*
X321938D01*
G01X344468Y337809D02*
X342218D01*
G01X351228Y357309D02*
X348978D01*
G01X300529Y355360D02*
X298279D01*
G01X314048Y367060D02*
X311798D01*
G01X310668Y380709D02*
X308418D01*
G01X347848Y386560D02*
X345598D01*
G01X297149Y376809D02*
X294899D01*
G01X297149Y380709D02*
X294899D01*
G01X307289Y355360D02*
X305039D01*
G01X307289Y359260D02*
X305039D01*
G01X297149Y345609D02*
X294899D01*
G01X297149Y365109D02*
X294899D01*
G01X341088Y343660D02*
X338838D01*
G01X300529Y374860D02*
X298279D01*
G01X351228Y380709D02*
X348978D01*
G01X307289Y382660D02*
X305039D01*
G01X300529Y347560D02*
X298279D01*
G01X324188Y372909D02*
X321938D01*
G01X303909Y365109D02*
X301659D01*
G01X337708Y353409D02*
X335458D01*
G01X344468Y341709D02*
X342218D01*
G01X297149D02*
X294899D01*
G01X343091Y402909D02*
Y449049D01*
G01X347848Y378760D02*
X345598D01*
G01X297149Y388509D02*
X294899D01*
G01X303909Y353409D02*
X301659D01*
G01X351228Y402764D02*
X351192Y402800D01*
G01X351228Y400209D02*
Y402764D01*
G01X314048Y363160D02*
X311798D01*
G01X297149Y392410D02*
X294899D01*
G01X347848Y355360D02*
X345598D01*
G01X327568Y359260D02*
X325318D01*
G01X303909Y345609D02*
X301659D01*
G01X324188Y357309D02*
X321938D01*
G01X334328Y343660D02*
X332078D01*
G01X334328Y359260D02*
X332078D01*
G01X317428Y361209D02*
X315178D01*
G01X344468Y380709D02*
X342218D01*
G01X310668Y376809D02*
X308418D01*
G01X307289Y374860D02*
X305039D01*
G01X327568Y351460D02*
X325318D01*
G01X351228Y392410D02*
X348978Y388509D01*
G01X330948Y341709D02*
X328698D01*
G01X317428Y372909D02*
X315178D01*
G01X337708Y357309D02*
X335458D01*
G01X300529Y382660D02*
X298279D01*
G01X297149Y361209D02*
X294899D01*
G01X341900Y396309D02*
X341892Y396301D01*
G01X344468Y396309D02*
X341900D01*
G01X320808Y363160D02*
X318558D01*
G01X324188Y353409D02*
X321938D01*
G01X300529Y367060D02*
X298279D01*
G01X340996Y402882D02*
Y447473D01*
G01X320808Y374860D02*
X318558D01*
G01X324188Y369010D02*
X321938D01*
G01X334328Y351460D02*
X332078D01*
G01X345384Y450211D02*
X326922Y468673D01*
G01X345384Y403714D02*
Y450211D01*
G01X310729Y443735D02*
Y479500D01*
G01X315621Y438843D02*
X310729Y443735D01*
G01X347479Y451016D02*
Y405432D01*
G01X329730Y468765D02*
X347479Y451016D01*
G01X353764Y453532D02*
X338441Y468855D01*
G01X353764Y408372D02*
Y453532D01*
G01X297692Y446027D02*
Y476403D01*
G01X311171Y432548D02*
X297692Y446027D01*
G01X349574Y451922D02*
X331830Y469666D01*
G01X349574Y406130D02*
Y451922D01*
G01X343091Y449049D02*
X324784Y467356D01*
G01X360049Y456451D02*
X345126Y471374D01*
G01X351669Y452727D02*
X333930Y470466D01*
G01X351669Y407377D02*
Y452727D01*
G01X355859Y454367D02*
X341021Y469205D01*
G01X357954Y455549D02*
X343056Y470447D01*
G01X300240Y447116D02*
Y488152D01*
G01X300940Y446416D02*
X300240Y447116D01*
G01X302290Y446416D02*
X300940D01*
G01X302890Y447016D02*
X302290Y446416D01*
G01X302890Y455300D02*
Y447016D01*
G01X303390Y455800D02*
X302890Y455300D01*
G01X305040Y455800D02*
X303390D01*
G01X305540Y455300D02*
X305040Y455800D01*
G01X305540Y441750D02*
Y455300D01*
G01X312483Y434807D02*
X305540Y441750D01*
G01X302892Y461484D02*
Y491500D01*
G01X303509Y460867D02*
X302892Y461484D01*
G01X304859Y460867D02*
X303509D01*
G01X305509Y461517D02*
X304859Y460867D01*
G01X305509Y464200D02*
Y461517D01*
G01X306009Y464700D02*
X305509Y464200D01*
G01X307659Y464700D02*
X306009D01*
G01X308159Y464200D02*
X307659Y464700D01*
G01X308159Y442736D02*
Y464200D01*
G01X314082Y436813D02*
X308159Y442736D01*
G01X340996Y447473D02*
X322686Y465783D01*
G01X326922Y468673D02*
Y497170D01*
G01X304392Y493500D02*
Y494700D01*
G01X305429Y492463D02*
X304392Y493500D01*
G01X305429Y469888D02*
Y492463D01*
G01X306079Y469238D02*
X305429Y469888D01*
G01X307429Y469238D02*
X306079D01*
G01X308079Y469888D02*
X307429Y469238D01*
G01X308079Y479500D02*
Y469888D01*
G01X308579Y480000D02*
X308079Y479500D01*
G01X310229Y480000D02*
X308579D01*
G01X310729Y479500D02*
X310229Y480000D01*
G01X329730Y502062D02*
Y489798D01*
G01X326892Y504900D02*
X329730Y502062D01*
G01X325192Y504900D02*
X326892D01*
G01X320292Y509800D02*
X325192Y504900D01*
G01X320292Y510300D02*
Y509800D01*
G01X318542Y512050D02*
X320292Y510300D01*
G01X318142Y512050D02*
X318542D01*
G01X315592Y514600D02*
X318142Y512050D01*
G01X315592Y516542D02*
Y514600D01*
G01X316292Y517242D02*
X315592Y516542D01*
G01X316292Y518699D02*
Y517242D01*
G01X314368Y520623D02*
X316292Y518699D01*
G01X314368Y523900D02*
Y520623D01*
G01X329730Y489798D02*
Y468765D01*
G01X337793Y495330D02*
Y509999D01*
G01X338983Y494140D02*
X337793Y495330D01*
G01X338983Y491135D02*
Y494140D01*
G01X337977Y490129D02*
X338983Y491135D01*
G01X337413Y490129D02*
X337977D01*
G01X336763Y489479D02*
X337413Y490129D01*
G01X336763Y488129D02*
Y489479D01*
G01X337413Y487479D02*
X336763Y488129D01*
G01X338363Y487479D02*
X337413D01*
G01X339013Y486829D02*
X338363Y487479D01*
G01X339013Y485479D02*
Y486829D01*
G01X338363Y484829D02*
X339013Y485479D01*
G01X337166Y484829D02*
X338363D01*
G01X336516Y484179D02*
X337166Y484829D01*
G01X336516Y482830D02*
Y484179D01*
G01X337167Y482179D02*
X336516Y482830D01*
G01X338363Y482179D02*
X337167D01*
G01X339013Y481529D02*
X338363Y482179D01*
G01X339013Y480104D02*
Y481529D01*
G01X338363Y479454D02*
X339013Y480104D01*
G01X337638Y479454D02*
X338363D01*
G01X336988Y478804D02*
X337638Y479454D01*
G01X336988Y477454D02*
Y478804D01*
G01X337638Y476804D02*
X336988Y477454D01*
G01X338363Y476804D02*
X337638D01*
G01X339013Y476154D02*
X338363Y476804D01*
G01X339013Y474804D02*
Y476154D01*
G01X338441Y474232D02*
X339013Y474804D01*
G01X338441Y468855D02*
Y474232D01*
G01X296534Y490958D02*
X294392Y493100D01*
G01X296534Y488158D02*
Y490958D01*
G01X297692Y487000D02*
X296534Y488158D01*
G01X297692Y485653D02*
Y487000D01*
G01X297042Y485003D02*
X297692Y485653D01*
G01X295520Y485003D02*
X297042D01*
G01X294870Y484353D02*
X295520Y485003D01*
G01X294870Y483003D02*
Y484353D01*
G01X295520Y482353D02*
X294870Y483003D01*
G01X297042Y482353D02*
X295520D01*
G01X297692Y481703D02*
X297042Y482353D01*
G01X297692Y480353D02*
Y481703D01*
G01X297042Y479703D02*
X297692Y480353D01*
G01X295520Y479703D02*
X297042D01*
G01X294870Y479053D02*
X295520Y479703D01*
G01X294870Y477703D02*
Y479053D01*
G01X295520Y477053D02*
X294870Y477703D01*
G01X297042Y477053D02*
X295520D01*
G01X297692Y476403D02*
X297042Y477053D01*
G01X321061Y523900D02*
Y529014D01*
G01Y516025D02*
Y518157D01*
G01X326742Y510344D02*
X321061Y516025D01*
G01X326742Y508250D02*
Y510344D01*
G01X331830Y503162D02*
X326742Y508250D01*
G01X331830Y469666D02*
Y503162D01*
G01X313192Y516881D02*
X314368Y518057D01*
G01X313192Y514300D02*
Y516881D01*
G01X312092Y513200D02*
X313192Y514300D01*
G01X312092Y511800D02*
Y513200D01*
G01X312992Y510900D02*
X312092Y511800D01*
G01X312992Y506682D02*
Y510900D01*
G01X324784Y494890D02*
X312992Y506682D01*
G01X324784Y467356D02*
Y494890D01*
G01X347279Y512238D02*
X347833Y512792D01*
G01X347279Y472184D02*
Y512238D01*
G01X362144Y457319D02*
X347279Y472184D01*
G01X334447Y523900D02*
Y529013D01*
G01X345126Y509474D02*
X344486Y510114D01*
G01X345126Y471374D02*
Y509474D01*
G01X294289Y523900D02*
Y528899D01*
G01X331100Y523900D02*
Y529014D01*
G01X324407Y523900D02*
Y529014D01*
G01X327752Y515364D02*
X324407D01*
G01X329646Y513470D02*
X327752Y515364D01*
G01X329646Y511654D02*
Y513470D01*
G01X329092Y511100D02*
X329646Y511654D01*
G01X329092Y509400D02*
Y511100D01*
G01X330230Y508262D02*
X329092Y509400D01*
G01X333391Y508262D02*
X330230D01*
G01X334839Y506814D02*
X333391Y508262D01*
G01X334839Y504643D02*
Y506814D01*
G01X333930Y503734D02*
X334839Y504643D01*
G01X333930Y494655D02*
Y503734D01*
G01X334580Y494005D02*
X333930Y494655D01*
G01X335779Y494005D02*
X334580D01*
G01X336413Y493371D02*
X335779Y494005D01*
G01X336413Y492021D02*
Y493371D01*
G01X335747Y491355D02*
X336413Y492021D01*
G01X334580Y491355D02*
X335747D01*
G01X333930Y490705D02*
X334580Y491355D01*
G01X333930Y476107D02*
Y490705D01*
G01X334580Y475457D02*
X333930Y476107D01*
G01X335546Y475457D02*
X334580D01*
G01X336212Y474791D02*
X335546Y475457D01*
G01X336212Y473441D02*
Y474791D01*
G01X335578Y472807D02*
X336212Y473441D01*
G01X334580Y472807D02*
X335578D01*
G01X333930Y472157D02*
X334580Y472807D01*
G01X333930Y470466D02*
Y472157D01*
G01X341140Y523900D02*
Y529022D01*
G01Y515527D02*
Y518157D01*
G01X339292Y513679D02*
X341140Y515527D01*
G01X339292Y511400D02*
Y513679D01*
G01X340192Y510500D02*
X339292Y511400D01*
G01X340192Y496400D02*
Y510500D01*
G01X341021Y495571D02*
X340192Y496400D01*
G01X341021Y469205D02*
Y495571D01*
G01X344486Y523900D02*
Y529022D01*
G01X344947Y514903D02*
X344486Y515364D01*
G01X344947Y513455D02*
Y514903D01*
G01X342356Y510864D02*
X344947Y513455D01*
G01X342356Y508534D02*
Y510864D01*
G01X343056Y507834D02*
X342356Y508534D01*
G01X343056Y505704D02*
Y507834D01*
G01X342113Y504761D02*
X343056Y505704D01*
G01X342113Y503054D02*
Y504761D01*
G01X343056Y502111D02*
X342113Y503054D01*
G01X343056Y500404D02*
Y502111D01*
G01X342226Y499574D02*
X343056Y500404D01*
G01X342226Y497641D02*
Y499574D01*
G01X343056Y496811D02*
X342226Y497641D01*
G01X343056Y470447D02*
Y496811D01*
G01X299066Y493713D02*
X297835Y494944D01*
G01X299066Y489326D02*
Y493713D01*
G01X300240Y488152D02*
X299066Y489326D01*
G01X300982Y523900D02*
Y528899D01*
G01X302892Y491500D02*
X301092Y493300D01*
G01X354307Y506766D02*
Y512792D01*
G01X354808Y506265D02*
X354307Y506766D01*
G01X353739Y498701D02*
X354808Y499770D01*
G01X353739Y494543D02*
Y498701D01*
G01X354994Y493288D02*
X353739Y494543D01*
G01Y487913D02*
X354994Y489168D01*
G01X353739Y484273D02*
Y487913D01*
G01X355373Y482639D02*
X353739Y484273D01*
G01X311021Y505613D02*
Y510114D01*
G01X322686Y493948D02*
X311021Y505613D01*
G01X322686Y465783D02*
Y493948D01*
G01X354525Y523900D02*
Y529022D01*
G01X353174Y516805D02*
X354526Y518157D01*
G01X353174Y514606D02*
Y516805D01*
G01X352222Y513654D02*
X353174Y514606D01*
G01X352222Y511970D02*
Y513654D01*
G01X352657Y511535D02*
X352222Y511970D01*
G01X352657Y508327D02*
Y511535D01*
G01X351695Y507365D02*
X352657Y508327D01*
G01X351695Y504862D02*
Y507365D01*
G01X353092Y503465D02*
X351695Y504862D01*
G01X353092Y501172D02*
Y503465D01*
G01X351665Y499745D02*
X353092Y501172D01*
G01X351665Y473603D02*
Y499745D01*
G01X366334Y458934D02*
X351665Y473603D01*
G01X351179Y523900D02*
Y529022D01*
G01X350046Y514231D02*
X351179Y515364D01*
G01X350046Y512294D02*
Y514231D01*
G01X349027Y511275D02*
X350046Y512294D01*
G01X349027Y508934D02*
Y511275D01*
G01X349264Y508697D02*
X349027Y508934D01*
G01X349264Y473069D02*
Y508697D01*
G01X364239Y458094D02*
X349264Y473069D01*
G01X334447Y566813D02*
X334446Y566814D01*
G01X334447Y561700D02*
Y566813D01*
G01X311021Y536957D02*
Y542010D01*
G01X300982Y561700D02*
Y566699D01*
G01X324407Y536957D02*
Y542010D01*
G01Y561700D02*
Y566814D01*
G01Y574757D02*
Y579810D01*
G01X341140Y561700D02*
Y566822D01*
G01X351179Y561700D02*
Y566822D01*
G01X344486Y561700D02*
Y566822D01*
G01X337793Y536957D02*
Y542010D01*
G01X327754Y574757D02*
Y579810D01*
G01X334447Y574757D02*
Y579810D01*
G01X297636Y572901D02*
X297635Y572900D01*
G01X297636Y574100D02*
Y572901D01*
G01X298156Y574620D02*
X297636Y574100D01*
G01X298156Y575480D02*
Y574620D01*
G01X297636Y576000D02*
X298156Y575480D01*
G01X297636Y579810D02*
Y576000D01*
G01X304328Y536192D02*
Y535100D01*
G01X304846Y536710D02*
X304328Y536192D01*
G01X304846Y537590D02*
Y536710D01*
G01X304328Y538108D02*
X304846Y537590D01*
G01X304328Y542010D02*
Y538108D01*
G01X304329Y542010D02*
X304328D01*
G01X321061Y561700D02*
Y566814D01*
G01X347833Y574757D02*
Y579810D01*
G01Y536957D02*
Y542010D01*
G01X334447Y529013D02*
X334446Y529014D01*
G01X344486Y536957D02*
Y542010D01*
G01X337793Y574757D02*
Y579810D01*
G01X354525Y561700D02*
Y566822D01*
G01X334447Y536957D02*
Y542010D01*
G01X294289Y561700D02*
Y566699D01*
G01X304328Y573992D02*
Y572900D01*
G01X304846Y574510D02*
X304328Y573992D01*
G01X304846Y575390D02*
Y574510D01*
G01X304328Y575908D02*
X304846Y575390D01*
G01X304328Y579810D02*
Y575908D01*
G01X304329Y579810D02*
X304328D01*
G01X314368Y561700D02*
Y566814D01*
G01X354526Y537057D02*
Y536957D01*
G01X354525Y537058D02*
X354526Y537057D01*
G01X354525Y542010D02*
Y537058D01*
G01X327754Y536957D02*
Y542010D01*
G01X311021Y574757D02*
Y579810D01*
G01X331100Y561700D02*
Y566814D01*
G01X354526Y574857D02*
Y574757D01*
G01X354525Y574858D02*
X354526Y574857D01*
G01X354525Y579810D02*
Y574858D01*
G01X344486Y574757D02*
Y579810D01*
G01X297636Y535101D02*
X297635Y535100D01*
G01X297636Y536300D02*
Y535101D01*
G01X298156Y536820D02*
X297636Y536300D01*
G01X298156Y537680D02*
Y536820D01*
G01X297636Y538200D02*
X298156Y537680D01*
G01X297636Y542010D02*
Y538200D01*
G01X327754Y617610D02*
Y612457D01*
G01X300982Y599500D02*
Y604499D01*
G01X341140Y599500D02*
Y607292D01*
G01X344486Y617610D02*
Y609864D01*
G01X334447Y599500D02*
Y607292D01*
G01X314368Y599500D02*
Y607292D01*
G01X351179Y599500D02*
Y604499D01*
G01X324407Y599500D02*
Y604499D01*
G01X334447Y617610D02*
Y612457D01*
G01X344486Y599500D02*
Y604614D01*
G01X347833Y617610D02*
Y612357D01*
G01X354526Y599524D02*
Y607292D01*
G01X354525Y599523D02*
X354526Y599524D01*
G01X354525Y599500D02*
Y599523D01*
G01X331100Y599500D02*
Y604614D01*
G01X321061Y599500D02*
Y607292D01*
G01X297636Y610701D02*
X297635Y610700D01*
G01X297636Y611500D02*
Y610701D01*
G01X298156Y612020D02*
X297636Y611500D01*
G01X298156Y612880D02*
Y612020D01*
G01X297636Y613400D02*
X298156Y612880D01*
G01X297636Y617610D02*
Y613400D01*
G01X311021Y609864D02*
Y617610D01*
G01X324407D02*
Y609864D01*
G01X354525Y617610D02*
Y612358D01*
G01X337793Y617610D02*
Y609864D01*
G01X304328Y611792D02*
Y610700D01*
G01X304846Y612310D02*
X304328Y611792D01*
G01X304846Y613190D02*
Y612310D01*
G01X304328Y613708D02*
X304846Y613190D01*
G01X304328Y617610D02*
Y613708D01*
G01X304329Y617610D02*
X304328D01*
G01X294289Y599500D02*
Y604499D01*
G01X414762Y-1742D02*
X414761Y-1743D01*
G01X414762Y3233D02*
Y-1742D01*
G01X398029Y28007D02*
Y22923D01*
G01X404722Y28021D02*
X404723Y28022D01*
G01X404722Y22923D02*
Y28021D01*
G01Y3233D02*
Y-4536D01*
G01X394683Y3233D02*
Y-2200D01*
G01X398029Y-14877D02*
Y-9901D01*
G01X408069Y28007D02*
Y22923D01*
G01X414762D02*
Y28021D01*
G01X404722Y-14877D02*
Y-9901D01*
G01X401376Y-1742D02*
X401375Y-1743D01*
G01X401376Y3233D02*
Y-1742D01*
G01X408069Y-7109D02*
X408068Y-7108D01*
G01X408069Y-14877D02*
Y-7109D01*
G01X414762D02*
X414761Y-7108D01*
G01X414762Y-14877D02*
Y-7109D01*
G01X404723Y36057D02*
Y35957D01*
G01X404722Y36058D02*
X404723Y36057D01*
G01X404722Y41033D02*
Y36058D01*
G01X414762Y65821D02*
X414763Y65822D01*
G01X414762Y60723D02*
Y65821D01*
G01X413292Y91288D02*
X414761Y92757D01*
G01X413292Y88710D02*
Y91288D01*
G01X411964Y87382D02*
X413292Y88710D01*
G01X410866Y87382D02*
X411964D01*
G01X408908Y89340D02*
X410866Y87382D01*
G01X408908Y90516D02*
Y89340D01*
G01X410606Y92214D02*
X408908Y90516D01*
G01X410606Y93714D02*
Y92214D01*
G01X411992Y95100D02*
X410606Y93714D01*
G01X404722Y73758D02*
X404723Y73757D01*
G01X404722Y78833D02*
Y73758D01*
G01X414762D02*
X414763Y73757D01*
G01X414762Y78833D02*
Y73758D01*
G01X416292Y88923D02*
X414761Y87392D01*
G01X416292Y91100D02*
Y88923D01*
G01X417013Y91821D02*
X416292Y91100D01*
G01X401376Y73758D02*
X401377Y73757D01*
G01X401376Y78833D02*
Y73758D01*
G01X408069Y65807D02*
Y60723D01*
G01X407313Y92002D02*
X408068Y92757D01*
G01X404690Y92002D02*
X407313D01*
G01X402999Y93693D02*
X404690Y92002D01*
G01X402999Y94712D02*
Y93693D01*
G01X394683Y87391D02*
Y78833D01*
G01X394682Y87392D02*
X394683Y87391D01*
G01X394682Y93010D02*
Y87392D01*
G01X383938Y103754D02*
X394682Y93010D01*
G01X394684Y36057D02*
Y35957D01*
G01X394683Y36058D02*
X394684Y36057D01*
G01X394683Y41033D02*
Y36058D01*
G01X356130Y88042D02*
X355480Y87392D01*
G01X356130Y88962D02*
Y88042D01*
G01X355492Y89600D02*
X356130Y88962D01*
G01X355492Y90567D02*
Y89600D01*
G01X356190Y91265D02*
X355492Y90567D01*
G01X356190Y93933D02*
Y91265D01*
G01X357343Y95086D02*
X356190Y93933D01*
G01X401376Y35958D02*
X401377Y35957D01*
G01X401376Y41033D02*
Y35958D01*
G01X414762D02*
X414763Y35957D01*
G01X414762Y41033D02*
Y35958D01*
G01X398029Y65807D02*
Y60723D01*
G01X396189Y94404D02*
X398029Y89964D01*
G01X382392Y108201D02*
X396189Y94404D01*
G01X399364Y94128D02*
X393192Y100300D01*
G01X399364Y91412D02*
Y94128D01*
G01X401518Y89258D02*
X399364Y91412D01*
G01X404016Y89258D02*
X401518D01*
G01X404722Y89964D02*
X404016Y89258D01*
G01X404722Y65821D02*
X404723Y65822D01*
G01X404722Y60723D02*
Y65821D01*
G01X416017Y143222D02*
X425505Y133734D01*
G01X416017Y159300D02*
Y143222D01*
G01X361912Y188639D02*
Y122486D01*
G01X395684Y108807D02*
X398408Y106083D01*
G01X388347Y119788D02*
X395684Y108807D01*
G01X388347Y179613D02*
Y119788D01*
G01X398408Y106083D02*
X401375Y103116D01*
G01X390332Y120753D02*
X396832Y114253D01*
G01X390332Y186892D02*
Y120753D01*
G01X411992Y96168D02*
Y95100D01*
G01X410835Y97325D02*
X411992Y96168D01*
G01X409647Y97325D02*
X410835D01*
G01X408767Y96445D02*
X409647Y97325D01*
G01X407847Y96445D02*
X408767D01*
G01X403192Y101100D02*
X407847Y96445D01*
G01X403192Y107893D02*
Y101100D01*
G01X402295Y108790D02*
X403192Y107893D01*
G01X401322Y108790D02*
X402295D01*
G01X400472Y107940D02*
X401322Y108790D01*
G01X399552Y107940D02*
X400472D01*
G01X398302Y109190D02*
X399552Y107940D01*
G01X398302Y110210D02*
Y109190D01*
G01X399228Y111136D02*
X398302Y110210D01*
G01X399228Y111857D02*
Y111136D01*
G01X396832Y114253D02*
X399228Y111857D01*
G01X405733Y108259D02*
Y104472D01*
G01X392317Y121675D02*
X405733Y108259D01*
G01X392317Y187013D02*
Y121675D01*
G01X411645Y99683D02*
X417013Y94315D01*
G01X407609Y99683D02*
X411645D01*
G01X405733Y101559D02*
X407609Y99683D01*
G01X405733Y104472D02*
Y101559D01*
G01X357942Y189634D02*
Y124134D01*
G01X406212Y129824D02*
Y190701D01*
G01X424817Y111219D02*
X406212Y129824D01*
G01X386362Y115131D02*
X389148Y112345D01*
G01X386362Y180000D02*
Y115131D01*
G01X404097Y95810D02*
X402999Y94712D01*
G01X404097Y97317D02*
Y95810D01*
G01X403447Y97967D02*
X404097Y97317D01*
G01X401941Y97967D02*
X403447D01*
G01X400743Y96769D02*
X401941Y97967D01*
G01X399823Y96769D02*
X400743D01*
G01X398904Y97688D02*
X399823Y96769D01*
G01X398904Y98609D02*
Y97688D01*
G01X400330Y100035D02*
X398904Y98609D01*
G01X400330Y100955D02*
Y100035D01*
G01X399411Y101874D02*
X400330Y100955D01*
G01X398491Y101874D02*
X399411D01*
G01X397064Y100447D02*
X398491Y101874D01*
G01X396147Y100447D02*
X397064D01*
G01X395226Y101368D02*
X396147Y100447D01*
G01X395226Y102286D02*
Y101368D01*
G01X396423Y103484D02*
X395226Y102286D01*
G01X396423Y104672D02*
Y103484D01*
G01X395772Y105323D02*
X396423Y104672D01*
G01X394584Y105323D02*
X395772D01*
G01X393986Y104725D02*
X394584Y105323D01*
G01X393069Y104725D02*
X393986D01*
G01X392148Y105646D02*
X393069Y104725D01*
G01X392148Y106564D02*
Y105646D01*
G01X392745Y107161D02*
X392148Y106564D01*
G01X392745Y108748D02*
Y107161D01*
G01X389148Y112345D02*
X392745Y108748D01*
G01X380407Y107285D02*
X383938Y103754D01*
G01X380407Y181141D02*
Y107285D01*
G01X363897Y121662D02*
Y188142D01*
G01X355957Y128568D02*
Y185958D01*
G01X355644Y124644D02*
Y125562D01*
G01X357343Y97014D02*
Y95086D01*
G01X355699Y98658D02*
X357343Y97014D01*
G01X355699Y100129D02*
Y98658D01*
G01X356349Y100779D02*
X355699Y100129D01*
G01X356757Y100779D02*
X356349D01*
G01X357407Y101429D02*
X356757Y100779D01*
G01X357407Y102779D02*
Y101429D01*
G01X356757Y103429D02*
X357407Y102779D01*
G01X356349Y103429D02*
X356757D01*
G01X355699Y104079D02*
X356349Y103429D01*
G01X355699Y105429D02*
Y104079D01*
G01X356349Y106079D02*
X355699Y105429D01*
G01X356982Y106079D02*
X356349D01*
G01X357482Y106579D02*
X356982Y106079D01*
G01X357482Y108229D02*
Y106579D01*
G01X356982Y108729D02*
X357482Y108229D01*
G01X356349Y108729D02*
X356982D01*
G01X355699Y109379D02*
X356349Y108729D01*
G01X355699Y110656D02*
Y109379D01*
G01X365882Y120839D02*
X355699Y110656D01*
G01X365882Y188215D02*
Y120839D01*
G01X404227Y128578D02*
X425492Y107313D01*
G01X404227Y189513D02*
Y128578D01*
G01X412792Y107163D02*
Y104540D01*
G01X396287Y123668D02*
X412792Y107163D01*
G01X396287Y186770D02*
Y123668D01*
G01X414492Y100700D02*
X416982D01*
G01X412792Y102400D02*
X414492Y100700D01*
G01X412792Y104540D02*
Y102400D01*
G01X400257Y125866D02*
Y187877D01*
G01X419092Y107031D02*
X400257Y125866D01*
G01X412167Y132758D02*
X439767Y105158D01*
G01X412167Y195724D02*
Y132758D01*
G01X410182Y131780D02*
X433172Y108790D01*
G01X410182Y194610D02*
Y131780D01*
G01X398272Y124888D02*
X410543Y112617D01*
G01X398272Y187498D02*
Y124888D01*
G01X416692Y104989D02*
X414819Y103116D01*
G01X410543Y112617D02*
X416692Y106468D01*
G01X394302Y122690D02*
X404022Y112970D01*
G01X394302Y187013D02*
Y122690D01*
G01X410042Y103116D02*
X408126D01*
G01X410692Y103766D02*
X410042Y103116D01*
G01X410692Y106300D02*
Y103766D01*
G01X404022Y112970D02*
X410692Y106300D01*
G01X382392Y180801D02*
Y109922D01*
G01D02*
Y108201D01*
G01X408197Y130802D02*
Y193595D01*
G01X422606Y116393D02*
X408197Y130802D01*
G01X359927Y189913D02*
Y123310D01*
G01X384377Y109115D02*
Y114881D01*
G01X390554Y102938D02*
X384377Y109115D01*
G01X392154Y102938D02*
X390554D01*
G01X393192Y101900D02*
X392154Y102938D01*
G01X393192Y100300D02*
Y101900D01*
G01X384377Y114881D02*
Y180486D01*
G01X402242Y127600D02*
Y188251D01*
G01X417190Y112652D02*
X402242Y127600D01*
G01X418084Y216196D02*
X415634D01*
G01X378267Y213009D02*
X376017D01*
G01X411492Y196399D02*
X412167Y195724D01*
G01X411492Y208400D02*
Y196399D01*
G01X406883Y213009D02*
X411492Y208400D01*
G01X405306Y213009D02*
X406883D01*
G01X409292Y195500D02*
X410182Y194610D01*
G01X409292Y204360D02*
Y195500D01*
G01X408442Y205210D02*
X409292Y204360D01*
G01X405306Y205210D02*
X408442D01*
G01X398547Y205211D02*
X398546Y205210D01*
G01X402381Y205211D02*
X398547D01*
G01X404429Y203163D02*
X402381Y205211D01*
G01X405755Y203163D02*
X404429D01*
G01X407192Y201726D02*
X405755Y203163D01*
G01X407192Y194600D02*
Y201726D01*
G01X408197Y193595D02*
X407192Y194600D01*
G01X418084Y231797D02*
X415634D01*
G01X378267Y228610D02*
X376017D01*
G01X418084Y220096D02*
X415634D01*
G01X418084Y227896D02*
X415634D01*
G01X381647Y234460D02*
X379397D01*
G01X372637Y390460D02*
X374887D01*
G01X378267Y384609D02*
X376017D01*
G01X378267Y369010D02*
X376017D01*
G01X395166Y386560D02*
X392916D01*
G01X413642Y396123D02*
Y407549D01*
G01X398546Y384609D02*
X396296D01*
G01X401926Y390460D02*
X399676D01*
G01X402192Y402200D02*
X412017Y412025D01*
G01X391787Y384609D02*
X389537D01*
G01X372637Y386560D02*
X374887D01*
G01X411242Y402684D02*
X410592Y403334D01*
G01X411242Y397350D02*
Y402684D01*
G01X410392Y396500D02*
X411242Y397350D01*
G01X407824Y396500D02*
X410392D01*
G01X405306Y393982D02*
X407824Y396500D01*
G01X405306Y392410D02*
Y393982D01*
G01X383767Y410585D02*
Y497821D01*
G01X404077Y417443D02*
Y480286D01*
G01X387967Y495863D02*
Y411056D01*
G01X394152Y413168D02*
Y485823D01*
G01X394267Y413053D02*
X394152Y413168D01*
G01X400107Y415513D02*
Y482816D01*
G01X396137Y413983D02*
X396367Y413753D01*
G01X396137Y484901D02*
Y413983D01*
G01X362144Y410009D02*
Y457319D01*
G01X415987Y409894D02*
Y471319D01*
G01X413642Y407549D02*
X415987Y409894D01*
G01X406062Y479070D02*
Y417690D01*
G01X360049Y409566D02*
Y456451D01*
G01X385867Y496814D02*
Y410585D01*
G01X398122Y483886D02*
Y414698D01*
G01X392167Y411853D02*
Y487420D01*
G01X355859Y408774D02*
Y454367D01*
G01X402092Y481900D02*
Y416028D01*
G01X408047Y418266D02*
Y478055D01*
G01X357954Y408976D02*
Y455549D01*
G01X368429Y459994D02*
X355373Y473050D01*
G01X368429Y410774D02*
Y459994D01*
G01X390067Y410927D02*
Y494857D01*
G01X410032Y413141D02*
X401863Y404972D01*
G01X410032Y477140D02*
Y413141D01*
G01X412017Y412025D02*
Y476185D01*
G01X366334Y410519D02*
Y458934D01*
G01X414002Y411110D02*
Y473054D01*
G01X411242Y408350D02*
X414002Y411110D01*
G01X411242Y406634D02*
Y408350D01*
G01X410592Y405984D02*
X411242Y406634D01*
G01X408666Y405984D02*
X410592D01*
G01X407953Y405271D02*
X408666Y405984D01*
G01X407953Y403921D02*
Y405271D01*
G01X408540Y403334D02*
X407953Y403921D01*
G01X410592Y403334D02*
X408540D01*
G01X364239Y410143D02*
Y458094D01*
G01X394682Y511562D02*
Y512792D01*
G01X389010Y505890D02*
X394682Y511562D01*
G01X389010Y503064D02*
Y505890D01*
G01X383767Y497821D02*
X389010Y503064D01*
G01X404077Y480286D02*
X423876Y500085D01*
G01X393150Y501046D02*
X387967Y495863D01*
G01X393150Y505190D02*
Y501046D01*
G01X395834Y507874D02*
X393150Y505190D01*
G01X398610Y507874D02*
X395834D01*
G01X399992Y509256D02*
X398610Y507874D01*
G01X399992Y511500D02*
Y509256D01*
G01X399492Y512000D02*
X399992Y511500D01*
G01X399492Y514110D02*
Y512000D01*
G01X400746Y515364D02*
X399492Y514110D01*
G01X404722Y515364D02*
X400746D01*
G01X404722Y523900D02*
Y529021D01*
G01X403192Y495065D02*
Y498191D01*
G01X402208Y494081D02*
X403192Y495065D01*
G01X401207Y494081D02*
X402208D01*
G01X400472Y494816D02*
X401207Y494081D01*
G01X399552Y494816D02*
X400472D01*
G01X398302Y493566D02*
X399552Y494816D01*
G01X398302Y492546D02*
Y493566D01*
G01X398970Y491878D02*
X398302Y492546D01*
G01X398970Y490641D02*
Y491878D01*
G01X394152Y485823D02*
X398970Y490641D01*
G01X414762Y520971D02*
Y523900D01*
G01X412892Y519101D02*
X414762Y520971D01*
G01X412892Y517400D02*
Y519101D01*
G01X416592Y513700D02*
X412892Y517400D01*
G01X412792Y508200D02*
X416592Y512000D01*
G01X409592Y508200D02*
X412792D01*
G01X403192Y501800D02*
X409592Y508200D01*
G01X403192Y498191D02*
Y501800D01*
G01X415965Y500652D02*
X417943D01*
G01X412556Y497243D02*
X415965Y500652D01*
G01X412556Y495265D02*
Y497243D01*
G01X400107Y482816D02*
X412556Y495265D01*
G01X407048Y495812D02*
X396137Y484901D01*
G01X407048Y501686D02*
Y495812D01*
G01X411462Y506100D02*
X407048Y501686D01*
G01X416792Y506100D02*
X411462D01*
G01X414761Y518157D02*
X418035D01*
G01X415987Y471319D02*
X440192Y495524D01*
G01X419651Y492659D02*
X406062Y479070D01*
G01X390750Y501697D02*
X385867Y496814D01*
G01X390750Y505262D02*
Y501697D01*
G01X396892Y511404D02*
X390750Y505262D01*
G01X396892Y514227D02*
Y511404D01*
G01X398029Y515364D02*
X396892Y514227D01*
G01X398029Y523900D02*
Y529007D01*
G01X409483Y495247D02*
X406851Y492615D01*
G01X409483Y500379D02*
Y495247D01*
G01X412988Y503884D02*
X409483Y500379D01*
G01X417276Y503884D02*
X412988D01*
G01X406851Y492615D02*
X398122Y483886D01*
G01X410984Y512792D02*
X414761D01*
G01X400016Y501824D02*
X410984Y512792D01*
G01X399032Y501824D02*
X400016D01*
G01X397129Y499921D02*
X399032Y501824D01*
G01X397129Y499001D02*
Y499921D01*
G01X397957Y498173D02*
X397129Y499001D01*
G01X397957Y496837D02*
Y498173D01*
G01X395760Y494640D02*
X397957Y496837D01*
G01X394384Y494640D02*
X395760D01*
G01X392420Y492676D02*
X394384Y494640D01*
G01X392420Y491191D02*
Y492676D01*
G01X393547Y490064D02*
X392420Y491191D01*
G01X393547Y488800D02*
Y490064D01*
G01X392167Y487420D02*
X393547Y488800D01*
G01X418874Y498682D02*
X402092Y481900D01*
G01X408047Y478055D02*
X438122Y508130D01*
G01X354808Y499770D02*
Y506265D01*
G01X354994Y489168D02*
Y493288D01*
G01X355373Y473050D02*
Y482639D01*
G01X408068Y516076D02*
Y518157D01*
G01X402892Y510900D02*
X408068Y516076D01*
G01X402892Y508334D02*
Y510900D01*
G01X394596Y500038D02*
X402892Y508334D01*
G01X394596Y499386D02*
Y500038D01*
G01X390067Y494857D02*
X394596Y499386D01*
G01X408069Y523900D02*
Y529007D01*
G01X427596Y494704D02*
X410032Y477140D01*
G01X413578Y477747D02*
X431294Y495463D01*
G01X413578Y477746D02*
Y477747D01*
G01X412017Y476185D02*
X413578Y477746D01*
G01X415890Y474098D02*
X418160Y476368D01*
G01X415046Y474098D02*
X415890D01*
G01X414002Y473054D02*
X415046Y474098D01*
G01X401376Y536958D02*
X401377Y536957D01*
G01X401376Y542010D02*
Y536958D01*
G01X394684Y574857D02*
Y574757D01*
G01X394683Y574858D02*
X394684Y574857D01*
G01X394683Y579810D02*
Y574858D01*
G01Y537146D02*
X394595Y537058D01*
G01X394683Y542010D02*
Y537146D01*
G01X414762Y574758D02*
X414763Y574757D01*
G01X414762Y579810D02*
Y574758D01*
G01X404723Y574857D02*
Y574757D01*
G01X404722Y574858D02*
X404723Y574857D01*
G01X404722Y579810D02*
Y574858D01*
G01Y529021D02*
X404723Y529022D01*
G01X398029Y561700D02*
Y566807D01*
G01X404722Y566821D02*
X404723Y566822D01*
G01X404722Y561700D02*
Y566821D01*
G01X414762D02*
X414763Y566822D01*
G01X414762Y561700D02*
Y566821D01*
G01Y536958D02*
X414763Y536957D01*
G01X414762Y542010D02*
Y536958D01*
G01X404722D02*
X404723Y536957D01*
G01X404722Y542010D02*
Y536958D01*
G01X401376Y574758D02*
X401377Y574757D01*
G01X401376Y579810D02*
Y574758D01*
G01X408069Y561700D02*
Y566807D01*
G01X414762Y607291D02*
X414761Y607292D01*
G01X414762Y599500D02*
Y607291D01*
G01Y612658D02*
X414761Y612657D01*
G01X414762Y617610D02*
Y612658D01*
G01X404722Y617610D02*
Y609864D01*
G01X394682Y617610D02*
Y612657D01*
G01X394683Y617610D02*
X394682D01*
G01X408069Y607291D02*
X408068Y607292D01*
G01X408069Y599500D02*
Y607291D01*
G01X398029Y599500D02*
Y604499D01*
G01X404722Y599500D02*
Y604499D01*
G01X401376Y617610D02*
Y612658D01*
G01X443071Y-42265D02*
G02Y-45915I0J-1825D01*
G01X444880Y3233D02*
Y-4536D01*
G01X424801Y22923D02*
Y28007D01*
G01X451573Y22923D02*
Y27899D01*
G01X458266Y22923D02*
Y27899D01*
G01X474998Y-14877D02*
Y-9901D01*
G01X444880Y-14877D02*
Y-9786D01*
G01X421454Y-14876D02*
Y-7108D01*
G01X421455Y-14877D02*
X421454Y-14876D01*
G01X461612Y3233D02*
X460912Y-4100D01*
G01X431494Y-14877D02*
Y-9901D01*
G01X454919Y-2008D02*
X454533Y-4100D01*
G01X454919Y3233D02*
Y-2008D01*
G01X438187Y3233D02*
Y-4536D01*
G01Y28020D02*
X438189Y28022D01*
G01X438187Y22923D02*
Y28020D01*
G01X474998Y22923D02*
Y27899D01*
G01X438187Y-14877D02*
Y-9786D01*
G01X424801Y-14877D02*
Y-9786D01*
G01X444880Y28022D02*
Y22923D01*
G01X434840Y3233D02*
Y-1743D01*
G01X458266Y-14877D02*
Y-9901D01*
G01X428147Y3233D02*
Y-1743D01*
G01X451573Y-14877D02*
Y-9901D01*
G01X431494Y28007D02*
Y22923D01*
G01X421455Y28021D02*
X421456Y28022D01*
G01X421455Y22923D02*
Y28021D01*
G01X454919Y73592D02*
X454533Y71500D01*
G01X454919Y78833D02*
Y73592D01*
G01X451523Y92807D02*
X451573Y92757D01*
G01X451523Y100106D02*
Y92807D01*
G01X476842Y87714D02*
X478344D01*
G01X476192Y88364D02*
X476842Y87714D01*
G01X476192Y91200D02*
Y88364D01*
G01X479092Y94100D02*
X476192Y91200D01*
G01X474998Y60723D02*
Y65699D01*
G01X434840Y35959D02*
X434842Y35957D01*
G01X434840Y41033D02*
Y35959D01*
G01Y73759D02*
X434842Y73757D01*
G01X434840Y78833D02*
Y73759D01*
G01X417013Y94315D02*
Y91821D01*
G01X444880Y65822D02*
Y60723D01*
G01X461294Y75500D02*
X460912Y71500D01*
G01X461612Y78833D02*
X461294Y75500D01*
G01X456742Y94281D02*
X458266Y92757D01*
G01X456742Y102405D02*
Y94281D01*
G01X460988Y34500D02*
X460912Y33700D01*
G01X461036Y35000D02*
X460988Y34500D01*
G01X461612Y41033D02*
X461036Y35000D01*
G01X474998Y94305D02*
Y92757D01*
G01X476292Y95599D02*
X474998Y94305D01*
G01X456588Y89683D02*
X454619Y87714D01*
G01X456588Y91104D02*
Y89683D01*
G01X454142Y93550D02*
X456588Y91104D01*
G01X454142Y101245D02*
Y93550D01*
G01X451573Y60723D02*
Y65699D01*
G01X436692Y91459D02*
X438187Y89964D01*
G01X436692Y93900D02*
Y91459D01*
G01X430292Y100300D02*
X436692Y93900D01*
G01X424801Y92711D02*
Y89964D01*
G01X421873Y95639D02*
X424801Y92711D01*
G01X428147Y73759D02*
X428149Y73757D01*
G01X428147Y78833D02*
Y73759D01*
G01X430392Y93000D02*
Y97301D01*
G01X431494Y91898D02*
X430392Y93000D01*
G01X431494Y89964D02*
Y91898D01*
G01X445993Y85827D02*
X444880Y84714D01*
G01X445993Y88301D02*
Y85827D01*
G01X446792Y89100D02*
X445993Y88301D01*
G01X446792Y98133D02*
Y89100D01*
G01X444880Y35959D02*
X444882Y35957D01*
G01X444880Y41033D02*
Y35959D01*
G01X444092Y90752D02*
X444880Y89964D01*
G01X444092Y97980D02*
Y90752D01*
G01X431494Y65807D02*
Y60723D01*
G01X424801D02*
Y65807D01*
G01X454681Y34500D02*
X454533Y33700D01*
G01X454773Y35000D02*
X454681Y34500D01*
G01X454919Y35792D02*
X454773Y35000D01*
G01X454919Y41033D02*
Y35792D01*
G01X428147Y35959D02*
X428149Y35957D01*
G01X428147Y41033D02*
Y35959D01*
G01X439592Y93900D02*
X432124Y101368D01*
G01X439592Y91700D02*
Y93900D01*
G01X442092Y89200D02*
X439592Y91700D01*
G01X442392Y89200D02*
X442092D01*
G01X443392Y88200D02*
X442392Y89200D01*
G01X443392Y86500D02*
Y88200D01*
G01X442792Y85900D02*
X443392Y86500D01*
G01X442792Y83901D02*
Y85900D01*
G01X444880Y81813D02*
X442792Y83901D01*
G01X444880Y78833D02*
Y81813D01*
G01X438187Y65820D02*
X438189Y65822D01*
G01X438187Y60723D02*
Y65820D01*
G01X421455Y65821D02*
X421456Y65822D01*
G01X421455Y60723D02*
Y65821D01*
G01X458266Y60723D02*
Y65699D01*
G01X458908Y89718D02*
X460912Y87714D01*
G01X458908Y90866D02*
Y89718D01*
G01X460358Y92316D02*
X458908Y90866D01*
G01X460358Y93856D02*
Y92316D01*
G01X459342Y94872D02*
X460358Y93856D01*
G01X420165Y131464D02*
X451523Y100106D01*
G01X420165Y132172D02*
Y131464D01*
G01X421359Y133366D02*
X420165Y132172D01*
G01X422067Y133366D02*
X421359D01*
G01X423602Y131831D02*
X422067Y133366D01*
G01X424522Y131831D02*
X423602D01*
G01X425505Y132814D02*
X424522Y131831D01*
G01X425505Y133734D02*
Y132814D01*
G01X452392Y156300D02*
X486092Y122600D01*
G01X474326Y109758D02*
X479092Y104992D01*
G01X474326Y112500D02*
Y109758D01*
G01Y117848D02*
Y112500D01*
G01X435950Y156224D02*
X474326Y117848D01*
G01X435950Y159100D02*
Y156224D01*
G01X445892Y159001D02*
X483292Y121601D01*
G01X476104Y142600D02*
X479292D01*
G01X461692Y157012D02*
X476104Y142600D01*
G01X429528Y106508D02*
X424817Y111219D01*
G01X429528Y104932D02*
Y106508D01*
G01X427696Y103100D02*
X429528Y104932D01*
G01X436308Y122839D02*
X454520Y104627D01*
G01X436308Y123915D02*
Y122839D01*
G01X437135Y124742D02*
X436308Y123915D01*
G01X438212Y124742D02*
X437135D01*
G01X441163Y121791D02*
X438212Y124742D01*
G01X442083Y121791D02*
X441163D01*
G01X443065Y122773D02*
X442083Y121791D01*
G01X443065Y123693D02*
Y122773D01*
G01X421055Y145703D02*
X443065Y123693D01*
G01X421055Y159000D02*
Y145703D01*
G01X454520Y104627D02*
X456742Y102405D01*
G01X476845Y112696D02*
X481691Y107850D01*
G01X476845Y118893D02*
Y112696D01*
G01X438469Y157269D02*
X476845Y118893D01*
G01X476292Y96501D02*
Y95599D01*
G01X475793Y97000D02*
X476292Y96501D01*
G01X470692Y97000D02*
X475793D01*
G01X469892Y97800D02*
X470692Y97000D01*
G01X469892Y99850D02*
Y97800D01*
G01X470442Y100400D02*
X469892Y99850D01*
G01X475842Y100400D02*
X470442D01*
G01X476492Y101050D02*
X475842Y100400D01*
G01X476492Y102550D02*
Y101050D01*
G01X475842Y103200D02*
X476492Y102550D01*
G01X470593Y103200D02*
X475842D01*
G01X470092Y103701D02*
X470593Y103200D01*
G01X470092Y118518D02*
Y103701D01*
G01X433431Y155179D02*
X470092Y118518D01*
G01X433431Y159100D02*
Y155179D01*
G01X428692Y126695D02*
X454142Y101245D01*
G01X428692Y134305D02*
Y126695D01*
G01X418536Y144461D02*
X428692Y134305D01*
G01X418536Y159100D02*
Y144461D01*
G01X478111Y140081D02*
X482042Y136150D01*
G01X472413Y140081D02*
X478111D01*
G01X464754Y147740D02*
X472413Y140081D01*
G01X464754Y148660D02*
Y147740D01*
G01X465133Y149039D02*
X464754Y148660D01*
G01X465133Y149959D02*
Y149039D01*
G01X464179Y150913D02*
X465133Y149959D01*
G01X463259Y150913D02*
X464179D01*
G01X462880Y150534D02*
X463259Y150913D01*
G01X461960Y150534D02*
X462880D01*
G01X461006Y151488D02*
X461960Y150534D01*
G01X461006Y152408D02*
Y151488D01*
G01X461385Y152787D02*
X461006Y152408D01*
G01X461385Y153707D02*
Y152787D01*
G01X459967Y155125D02*
X461385Y153707D01*
G01X458592Y155125D02*
X459967D01*
G01X457942Y155775D02*
X458592Y155125D01*
G01X456742Y155775D02*
X457942D01*
G01X456092Y156425D02*
X456742Y155775D01*
G01X425492Y107313D02*
Y104752D01*
G01X427692Y100300D02*
X430292D01*
G01X425492Y102500D02*
X427692Y100300D01*
G01X425492Y104752D02*
Y102500D01*
G01X420757Y95639D02*
X421873D01*
G01X418791Y97605D02*
X420757Y95639D01*
G01X418791Y98891D02*
Y97605D01*
G01X416982Y100700D02*
X418791Y98891D01*
G01X419092Y102500D02*
Y104695D01*
G01X420792Y100800D02*
X419092Y102500D01*
G01X423393Y100800D02*
X420792D01*
G01X424838Y99355D02*
X423393Y100800D01*
G01X424838Y95699D02*
Y99355D01*
G01X425611Y94926D02*
X424838Y95699D01*
G01X426942Y94926D02*
X425611D01*
G01X427592Y95576D02*
X426942Y94926D01*
G01X427592Y97472D02*
Y95576D01*
G01X428243Y98123D02*
X427592Y97472D01*
G01X429570Y98123D02*
X428243D01*
G01X430392Y97301D02*
X429570Y98123D01*
G01X419092Y104695D02*
Y107031D01*
G01X439767Y105158D02*
X446792Y98133D01*
G01X443107Y98965D02*
X444092Y97980D01*
G01X442187Y98965D02*
X443107D01*
G01X440417Y97195D02*
X442187Y98965D01*
G01X439497Y97195D02*
X440417D01*
G01X438578Y98114D02*
X439497Y97195D01*
G01X438578Y99034D02*
Y98114D01*
G01X440348Y100804D02*
X438578Y99034D01*
G01X440348Y101724D02*
Y100804D01*
G01X439418Y102654D02*
X440348Y101724D01*
G01X438498Y102654D02*
X439418D01*
G01X436740Y100896D02*
X438498Y102654D01*
G01X435820Y100896D02*
X436740D01*
G01X434901Y101815D02*
X435820Y100896D01*
G01X434901Y102735D02*
Y101815D01*
G01X436692Y104526D02*
X434901Y102735D01*
G01X436692Y105270D02*
Y104526D01*
G01X433172Y108790D02*
X436692Y105270D01*
G01X416692Y106468D02*
Y104989D01*
G01X432124Y106875D02*
X422606Y116393D01*
G01X432124Y101368D02*
Y106875D01*
G01X423392Y106450D02*
X417190Y112652D01*
G01X423392Y104996D02*
Y106450D01*
G01X421512Y103116D02*
X423392Y104996D01*
G01X440988Y158314D02*
X479364Y119938D01*
G01X459342Y103565D02*
Y94872D01*
G01X447286Y115621D02*
X459342Y103565D01*
G01X447286Y116595D02*
Y115621D01*
G01X448214Y117523D02*
X447286Y116595D01*
G01X449190Y117523D02*
X448214D01*
G01X451442Y115271D02*
X449190Y117523D01*
G01X452362Y115271D02*
X451442D01*
G01X453344Y116253D02*
X452362Y115271D01*
G01X453344Y117173D02*
Y116253D01*
G01X423574Y146943D02*
X453344Y117173D01*
G01X423574Y158900D02*
Y146943D01*
G01X452392Y158200D02*
Y156300D01*
G01X455892Y161700D02*
X452392Y158200D01*
G01X476992Y161900D02*
X479092Y159800D01*
G01X445892Y163750D02*
Y159001D01*
G01X446542Y164400D02*
X445892Y163750D01*
G01X448792Y164400D02*
X446542D01*
G01X449292Y163900D02*
X448792Y164400D01*
G01X449292Y163500D02*
Y163900D01*
G01X449792Y163000D02*
X449292Y163500D01*
G01X451992Y163000D02*
X449792D01*
G01X461692Y161400D02*
Y157012D01*
G01X438469Y159300D02*
Y157269D01*
G01X456092Y157775D02*
Y156425D01*
G01X456742Y158425D02*
X456092Y157775D01*
G01X457942Y158425D02*
X456742D01*
G01X458592Y159075D02*
X457942Y158425D01*
G01X458592Y161000D02*
Y159075D01*
G01X440988Y159600D02*
Y158314D01*
G01X428224Y389747D02*
X430474D01*
G01X448503Y381947D02*
X450753D01*
G01X472163Y387796D02*
X474413D01*
G01X451883Y356596D02*
X454133D01*
G01X458643Y383896D02*
X460893D01*
G01X472163Y376096D02*
X474413D01*
G01X462023Y370247D02*
X464273D01*
G01X438363Y387796D02*
X440613D01*
G01X462023Y389747D02*
X464273D01*
G01X451883Y360496D02*
X454133D01*
G01X458643Y356596D02*
X460893D01*
G01X438363Y360496D02*
X440613D01*
G01X468783Y362447D02*
X471033D01*
G01X451883Y383896D02*
X454133D01*
G01X424844Y364396D02*
X427094D01*
G01X448503Y389747D02*
X450753D01*
G01X438363Y383896D02*
X440613D01*
G01X431604Y372197D02*
X433854D01*
G01X451883Y376096D02*
X454133D01*
G01X441743Y354647D02*
X443993D01*
G01X458643Y376096D02*
X460893D01*
G01X421464Y389747D02*
X423714D01*
G01X421464Y393647D02*
X423714D01*
G01X448503Y354647D02*
X450753D01*
G01X458643Y387796D02*
X460893D01*
G01X428224Y381947D02*
X430474D01*
G01X472163Y368296D02*
X474413D01*
G01X472163Y383896D02*
X474413D01*
G01X468783Y389747D02*
X471033D01*
G01X462023Y381947D02*
X464273D01*
G01X458643Y368296D02*
X460893D01*
G01X468783Y374146D02*
X471033D01*
G01X458643Y360496D02*
X460893D01*
G01X472163Y356596D02*
X474413D01*
G01X448503Y374146D02*
X450753D01*
G01X431604Y387796D02*
X433854D01*
G01X431604Y383896D02*
X433854D01*
G01X434983Y370247D02*
X437233D01*
G01X462023Y354647D02*
X464273D01*
G01X421464Y378047D02*
X423714D01*
G01X462023Y362447D02*
X464273D01*
G01X441743D02*
X443993D01*
G01X472163Y360496D02*
X474413D01*
G01X441743Y381947D02*
X443993D01*
G01X468783Y354647D02*
X471033D01*
G01X441743Y389747D02*
X443993D01*
G01X421464Y370247D02*
X423714D01*
G01X448503D02*
X450753D01*
G01X458643Y372197D02*
X460893D01*
G01X434983Y374146D02*
X437233D01*
G01X438363Y368296D02*
X440613D01*
G01X431604D02*
X433854D01*
G01X431604Y376096D02*
X433854D01*
G01X438363Y356596D02*
X440613D01*
G01X431604Y364396D02*
X433854D01*
G01X462023Y374146D02*
X464273D01*
G01X421464Y366347D02*
X423714D01*
G01X468783Y381947D02*
X471033D01*
G01X468783Y370247D02*
X471033D01*
G01X434983Y366347D02*
X437233D01*
G01X421464Y381947D02*
X423714D01*
G01X451883Y368296D02*
X454133D01*
G01X448503Y362447D02*
X450753D01*
G01X451883Y387796D02*
X454133D01*
G01X470106Y462914D02*
X476919Y469727D01*
G01X469186Y462914D02*
X470106D01*
G01X468548Y463552D02*
X469186Y462914D01*
G01X467628Y463552D02*
X468548D01*
G01X466674Y462598D02*
X467628Y463552D01*
G01X466674Y461678D02*
Y462598D01*
G01X467312Y461040D02*
X466674Y461678D01*
G01X467312Y460120D02*
Y461040D01*
G01X466358Y459166D02*
X467312Y460120D01*
G01X465438Y459166D02*
X466358D01*
G01X464800Y459804D02*
X465438Y459166D01*
G01X463880Y459804D02*
X464800D01*
G01X462926Y458850D02*
X463880Y459804D01*
G01X462926Y457930D02*
Y458850D01*
G01X463564Y457292D02*
X462926Y457930D01*
G01X463564Y456372D02*
Y457292D01*
G01X461392Y454200D02*
X463564Y456372D01*
G01X461392Y450700D02*
Y454200D01*
G01X460992Y450300D02*
X461392Y450700D01*
G01X446192Y462742D02*
X457780Y474330D01*
G01X446192Y453300D02*
Y462742D01*
G01X441042Y448150D02*
X446192Y453300D01*
G01X425692Y457800D02*
Y471986D01*
G01X422435Y454543D02*
X425692Y457800D01*
G01X422435Y443457D02*
Y454543D01*
G01X454292Y459568D02*
X484892Y490168D01*
G01X454292Y449200D02*
Y459568D01*
G01X445992Y440900D02*
X454292Y449200D01*
G01X441092Y440900D02*
X445992D01*
G01X477566Y459864D02*
X478664D01*
G01X476660Y460770D02*
X477566Y459864D01*
G01X475562Y460770D02*
X476660D01*
G01X474786Y459994D02*
X475562Y460770D01*
G01X474786Y458896D02*
Y459994D01*
G01X475692Y457990D02*
X474786Y458896D01*
G01X475692Y456892D02*
Y457990D01*
G01X473700Y454900D02*
X475692Y456892D01*
G01X469792Y454900D02*
X473700D01*
G01X467392Y452500D02*
X469792Y454900D01*
G01X467392Y449300D02*
Y452500D01*
G01X466192Y448100D02*
X467392Y449300D01*
G01X464392Y453372D02*
X486720Y475700D01*
G01X464392Y449900D02*
Y453372D01*
G01X463592Y449100D02*
X464392Y449900D01*
G01X428292Y456601D02*
Y470984D01*
G01X424954Y453263D02*
X428292Y456601D01*
G01X424954Y443937D02*
Y453263D01*
G01X451392Y460426D02*
X476421Y485455D01*
G01X451392Y450400D02*
Y460426D01*
G01X444492Y443500D02*
X451392Y450400D01*
G01X441293Y443500D02*
X444492D01*
G01X458392Y457922D02*
X467263Y466793D01*
G01X458392Y451400D02*
Y457922D01*
G01X423092Y458900D02*
Y472976D01*
G01X419892Y455700D02*
X423092Y458900D01*
G01X419892Y443500D02*
Y455700D01*
G01X434236Y464378D02*
Y465476D01*
G01X433460Y463602D02*
X434236Y464378D01*
G01X431668Y463602D02*
X433460D01*
G01X430892Y462826D02*
X431668Y463602D01*
G01X430892Y461728D02*
Y462826D01*
G01X431668Y460952D02*
X430892Y461728D01*
G01X433460Y460952D02*
X431668D01*
G01X434236Y460176D02*
X433460Y460952D01*
G01X434236Y458771D02*
Y460176D01*
G01X427473Y452008D02*
X434236Y458771D01*
G01X427473Y446981D02*
Y452008D01*
G01X448792Y461584D02*
X461462Y474254D01*
G01X448792Y452000D02*
Y461584D01*
G01X442792Y446000D02*
X448792Y452000D01*
G01X478008Y473784D02*
X478928D01*
G01X476919Y472695D02*
X478008Y473784D01*
G01X476919Y469727D02*
Y472695D01*
G01X472892Y516051D02*
X474998Y518157D01*
G01X472892Y515326D02*
Y516051D01*
G01X477092Y511126D02*
X472892Y515326D01*
G01X477092Y509600D02*
Y511126D01*
G01X475592Y508100D02*
X477092Y509600D01*
G01X475592Y496858D02*
Y508100D01*
G01X463488Y484754D02*
X475592Y496858D01*
G01X463488Y483778D02*
Y484754D01*
G01X464639Y482627D02*
X463488Y483778D01*
G01X464639Y481600D02*
Y482627D01*
G01X463712Y480673D02*
X464639Y481600D01*
G01X462736Y480673D02*
X463712D01*
G01X461534Y481875D02*
X462736Y480673D01*
G01X460609Y481875D02*
X461534D01*
G01X457780Y479046D02*
X460609Y481875D01*
G01X457780Y474330D02*
Y479046D01*
G01X451573Y523900D02*
Y528899D01*
G01X456291Y511442D02*
X454619Y513114D01*
G01X456291Y508498D02*
Y511442D01*
G01X454526Y506733D02*
X456291Y508498D01*
G01X454526Y505749D02*
Y506733D01*
G01X455913Y504362D02*
X454526Y505749D01*
G01X455913Y503141D02*
Y504362D01*
G01X454702Y501930D02*
X455913Y503141D01*
G01X453707Y501930D02*
X454702D01*
G01X452824Y502813D02*
X453707Y501930D01*
G01X452057Y502813D02*
X452824D01*
G01X450733Y501489D02*
X452057Y502813D01*
G01X450733Y500319D02*
Y501489D01*
G01X452912Y498140D02*
X450733Y500319D01*
G01X452912Y497220D02*
Y498140D01*
G01X451929Y496237D02*
X452912Y497220D01*
G01X451009Y496237D02*
X451929D01*
G01X448956Y498290D02*
X451009Y496237D01*
G01X448083Y498290D02*
X448956D01*
G01X446987Y497194D02*
X448083Y498290D01*
G01X446987Y496372D02*
Y497194D01*
G01X447890Y495469D02*
X446987Y496372D01*
G01X447890Y494184D02*
Y495469D01*
G01X425692Y471986D02*
X447890Y494184D01*
G01X432441Y514417D02*
X431494Y515364D01*
G01X432441Y512351D02*
Y514417D01*
G01X434046Y510746D02*
X432441Y512351D01*
G01X434046Y509407D02*
Y510746D01*
G01X432539Y507900D02*
X434046Y509407D01*
G01X430636Y507900D02*
X432539D01*
G01X428835Y506099D02*
X430636Y507900D01*
G01X428835Y504456D02*
Y506099D01*
G01X427669Y503290D02*
X428835Y504456D01*
G01X425888Y503290D02*
X427669D01*
G01X423876Y501278D02*
X425888Y503290D01*
G01X423876Y500085D02*
Y501278D01*
G01X416592Y512000D02*
Y513700D01*
G01X425992Y514173D02*
X424801Y515364D01*
G01X425992Y512501D02*
Y514173D01*
G01X426592Y511901D02*
X425992Y512501D01*
G01X426592Y509301D02*
Y511901D01*
G01X417943Y500652D02*
X426592Y509301D01*
G01X419920Y509228D02*
X416792Y506100D01*
G01X419920Y511072D02*
Y509228D01*
G01X419492Y511500D02*
X419920Y511072D01*
G01X419492Y513800D02*
Y511500D01*
G01X419992Y514300D02*
X419492Y513800D01*
G01X419992Y516200D02*
Y514300D01*
G01X418035Y518157D02*
X419992Y516200D01*
G01X456492Y516383D02*
X458266Y518157D01*
G01X456492Y514500D02*
Y516383D01*
G01X460092Y510900D02*
X456492Y514500D01*
G01X460092Y508100D02*
Y510900D01*
G01X458092Y506100D02*
X460092Y508100D01*
G01X458092Y505000D02*
Y506100D01*
G01X460592Y502500D02*
X458092Y505000D01*
G01X460592Y501084D02*
Y502500D01*
G01X459665Y500157D02*
X460592Y501084D01*
G01X458689Y500157D02*
X459665D01*
G01X457666Y501180D02*
X458689Y500157D01*
G01X456740Y501180D02*
X457666D01*
G01X455813Y500253D02*
X456740Y501180D01*
G01X455813Y499227D02*
Y500253D01*
G01X456786Y498254D02*
X455813Y499227D01*
G01X456786Y497278D02*
Y498254D01*
G01X451308Y491800D02*
X456786Y497278D01*
G01X449108Y491800D02*
X451308D01*
G01X428292Y470984D02*
X449108Y491800D01*
G01X476915Y489743D02*
X478324Y488334D01*
G01X475988Y489743D02*
X476915D01*
G01X475061Y488816D02*
X475988Y489743D01*
G01X475061Y487791D02*
Y488816D01*
G01X476421Y486431D02*
X475061Y487791D01*
G01X476421Y485455D02*
Y486431D01*
G01X445892Y512920D02*
X444880Y515364D01*
G01X445892Y511700D02*
Y512920D01*
G01X446792Y510800D02*
X445892Y511700D01*
G01X446792Y507844D02*
Y510800D01*
G01X440192Y501244D02*
X446792Y507844D01*
G01X440192Y495524D02*
Y501244D01*
G01X473805Y473335D02*
X484570Y484100D01*
G01X473805Y472415D02*
Y473335D01*
G01X474384Y471836D02*
X473805Y472415D01*
G01X474384Y470916D02*
Y471836D01*
G01X473430Y469962D02*
X474384Y470916D01*
G01X472510Y469962D02*
X473430D01*
G01X471892Y470580D02*
X472510Y469962D01*
G01X470972Y470580D02*
X471892D01*
G01X470018Y469626D02*
X470972Y470580D01*
G01X470018Y468706D02*
Y469626D01*
G01X470636Y468088D02*
X470018Y468706D01*
G01X470636Y467168D02*
Y468088D01*
G01X469682Y466214D02*
X470636Y467168D01*
G01X468762Y466214D02*
X469682D01*
G01X468183Y466793D02*
X468762Y466214D01*
G01X467263Y466793D02*
X468183D01*
G01X436392Y509400D02*
X419651Y492659D01*
G01X436392Y511000D02*
Y509400D01*
G01X436892Y511500D02*
X436392Y511000D01*
G01X436892Y513566D02*
Y511500D01*
G01X436127Y514331D02*
X436892Y513566D01*
G01X436127Y515935D02*
Y514331D01*
G01X438187Y517995D02*
X436127Y515935D01*
G01X438187Y523900D02*
Y517995D01*
G01X452492Y517238D02*
X451573Y518157D01*
G01X452492Y512000D02*
Y517238D01*
G01X453545Y510947D02*
X452492Y512000D01*
G01X453545Y509453D02*
Y510947D01*
G01X450992Y506900D02*
X453545Y509453D01*
G01X450992Y505300D02*
Y506900D01*
G01X444092Y498400D02*
X450992Y505300D01*
G01X444092Y493976D02*
Y498400D01*
G01X423092Y472976D02*
X444092Y493976D01*
G01X422692Y509300D02*
X417276Y503884D01*
G01X422692Y511500D02*
Y509300D01*
G01X423292Y512100D02*
X422692Y511500D01*
G01X423292Y513700D02*
Y512100D01*
G01X422292Y514700D02*
X423292Y513700D01*
G01X422292Y516100D02*
Y514700D01*
G01X424292Y518100D02*
X422292Y516100D01*
G01X424292Y523414D02*
Y518100D01*
G01X424801Y523923D02*
X424292Y523414D01*
G01X424801Y523900D02*
Y523923D01*
G01X431483Y523912D02*
X431494Y523900D01*
G01X431292Y523721D02*
X431483Y523912D01*
G01X431292Y517900D02*
Y523721D01*
G01X429592Y516200D02*
X431292Y517900D01*
G01X429592Y514500D02*
Y516200D01*
G01X429946Y514146D02*
X429592Y514500D01*
G01X429946Y511754D02*
Y514146D01*
G01X428492Y510300D02*
X429946Y511754D01*
G01X428492Y508300D02*
Y510300D01*
G01X418874Y498682D02*
X428492Y508300D01*
G01X439992Y511006D02*
X438187Y515364D01*
G01X439992Y509300D02*
Y511006D01*
G01X439317Y508625D02*
X439992Y509300D01*
G01X438122Y508130D02*
X439317Y508625D01*
G01X458266Y523900D02*
Y528899D01*
G01X461978Y513114D02*
X460912D01*
G01X462908Y512184D02*
X461978Y513114D01*
G01X462908Y509184D02*
Y512184D01*
G01X462345Y508621D02*
X462908Y509184D01*
G01X462345Y507114D02*
Y508621D01*
G01X463142Y506317D02*
X462345Y507114D01*
G01X463942Y506317D02*
X463142D01*
G01X464592Y505667D02*
X463942Y506317D01*
G01X464592Y503727D02*
Y505667D01*
G01X463942Y503077D02*
X464592Y503727D01*
G01X463142Y503077D02*
X463942D01*
G01X462492Y502427D02*
X463142Y503077D01*
G01X462492Y499226D02*
Y502427D01*
G01X450069Y486803D02*
X462492Y499226D01*
G01X449149Y486803D02*
X450069D01*
G01X448882Y487070D02*
X449149Y486803D01*
G01X447962Y487070D02*
X448882D01*
G01X446590Y485698D02*
X447962Y487070D01*
G01X446590Y484778D02*
Y485698D01*
G01X446932Y484436D02*
X446590Y484778D01*
G01X446932Y483415D02*
Y484436D01*
G01X445560Y482043D02*
X446932Y483415D01*
G01X444741Y482043D02*
X445560D01*
G01X444298Y482486D02*
X444741Y482043D01*
G01X443378Y482486D02*
X444298D01*
G01X442006Y481114D02*
X443378Y482486D01*
G01X442006Y480194D02*
Y481114D01*
G01X442349Y479851D02*
X442006Y480194D01*
G01X442349Y478830D02*
Y479851D01*
G01X440977Y477458D02*
X442349Y478830D01*
G01X440158Y477458D02*
X440977D01*
G01X439714Y477902D02*
X440158Y477458D01*
G01X438794Y477902D02*
X439714D01*
G01X437422Y476530D02*
X438794Y477902D01*
G01X437422Y475610D02*
Y476530D01*
G01X437840Y475192D02*
X437422Y475610D01*
G01X437840Y474297D02*
Y475192D01*
G01X436468Y472925D02*
X437840Y474297D01*
G01X434886Y472925D02*
X436468D01*
G01X434236Y472275D02*
X434886Y472925D01*
G01X434236Y469678D02*
Y472275D01*
G01X433460Y468902D02*
X434236Y469678D01*
G01X431668Y468902D02*
X433460D01*
G01X430892Y468126D02*
X431668Y468902D01*
G01X430892Y467028D02*
Y468126D01*
G01X431668Y466252D02*
X430892Y467028D01*
G01X433460Y466252D02*
X431668D01*
G01X434236Y465476D02*
X433460Y466252D01*
G01X439668Y506776D02*
X427596Y494704D01*
G01X441205Y507413D02*
X439668Y506776D01*
G01X442542Y508750D02*
X441205Y507413D01*
G01X442542Y510450D02*
Y508750D01*
G01X443792Y511700D02*
X442542Y510450D01*
G01X443792Y513600D02*
Y511700D01*
G01X443092Y514300D02*
X443792Y513600D01*
G01X443092Y516600D02*
Y514300D01*
G01X444880Y518388D02*
X443092Y516600D01*
G01X444880Y523900D02*
Y518388D01*
G01X474998Y523900D02*
Y528899D01*
G01X477570Y506920D02*
X479792Y509142D01*
G01X477570Y504170D02*
Y506920D01*
G01X478070Y503670D02*
X477570Y504170D01*
G01X479448Y503670D02*
X478070D01*
G01X478192Y499880D02*
X478742Y500430D01*
G01X478192Y496840D02*
Y499880D01*
G01X478842Y496190D02*
X478192Y496840D01*
G01X475442Y492950D02*
X478942D01*
G01X471252Y488760D02*
X475442Y492950D01*
G01X471252Y487784D02*
Y488760D01*
G01X472701Y486335D02*
X471252Y487784D01*
G01X472701Y485359D02*
Y486335D01*
G01X471774Y484432D02*
X472701Y485359D01*
G01X470798Y484432D02*
X471774D01*
G01X469223Y486007D02*
X470798Y484432D01*
G01X468310Y486007D02*
X469223D01*
G01X467183Y484880D02*
X468310Y486007D01*
G01X467183Y483841D02*
Y484880D01*
G01X468492Y482532D02*
X467183Y483841D01*
G01X468492Y481284D02*
Y482532D01*
G01X464288Y477080D02*
X468492Y481284D01*
G01X463331Y477080D02*
X464288D01*
G01X462252Y478159D02*
X463331Y477080D01*
G01X461395Y478159D02*
X462252D01*
G01X460304Y477068D02*
X461395Y478159D01*
G01X460304Y476359D02*
Y477068D01*
G01X461462Y475201D02*
X460304Y476359D01*
G01X461462Y474254D02*
Y475201D01*
G01X435192Y497100D02*
Y499400D01*
G01X433555Y495463D02*
X435192Y497100D01*
G01X431294Y495463D02*
X433555D01*
G01X421455Y523900D02*
Y529021D01*
G01X444880Y508289D02*
Y510114D01*
G01X437941Y501350D02*
X444880Y508289D01*
G01X437941Y496149D02*
Y501350D01*
G01X432640Y490848D02*
X437941Y496149D01*
G01X431720Y490848D02*
X432640D01*
G01X431158Y491410D02*
X431720Y490848D01*
G01X430086Y491410D02*
X431158D01*
G01X429173Y490497D02*
X430086Y491410D01*
G01X429173Y489647D02*
Y490497D01*
G01X429846Y488974D02*
X429173Y489647D01*
G01X429846Y488054D02*
Y488974D01*
G01X428892Y487100D02*
X429846Y488054D01*
G01X427972Y487100D02*
X428892D01*
G01X427329Y487743D02*
X427972Y487100D01*
G01X426394Y487743D02*
X427329D01*
G01X425440Y486789D02*
X426394Y487743D01*
G01X425440Y485884D02*
Y486789D01*
G01X426098Y485226D02*
X425440Y485884D01*
G01X426098Y484306D02*
Y485226D01*
G01X425144Y483352D02*
X426098Y484306D01*
G01X424224Y483352D02*
X425144D01*
G01X423581Y483995D02*
X424224Y483352D01*
G01X422646Y483995D02*
X423581D01*
G01X421692Y483041D02*
X422646Y483995D01*
G01X421692Y482136D02*
Y483041D01*
G01X422350Y481478D02*
X421692Y482136D01*
G01X422350Y480558D02*
Y481478D01*
G01X420954Y479162D02*
X422350Y480558D01*
G01X420034Y479162D02*
X420954D01*
G01X419404Y479792D02*
X420034Y479162D01*
G01X418484Y479792D02*
X419404D01*
G01X417530Y478838D02*
X418484Y479792D01*
G01X417530Y477918D02*
Y478838D01*
G01X418160Y477288D02*
X417530Y477918D01*
G01X418160Y476368D02*
Y477288D01*
G01X474998Y561700D02*
Y566699D01*
G01X434840Y574759D02*
X434842Y574757D01*
G01X434840Y579810D02*
Y574759D01*
G01X438187Y566820D02*
X438189Y566822D01*
G01X438187Y561700D02*
Y566820D01*
G01X444880Y561700D02*
Y566822D01*
G01X428147Y574759D02*
X428149Y574757D01*
G01X428147Y579810D02*
Y574759D01*
G01X461612Y542033D02*
X460912Y534700D01*
G01X461612Y542010D02*
Y542033D01*
G01Y579833D02*
X460912Y572500D01*
G01X461612Y579810D02*
Y579833D01*
G01X458266Y561700D02*
Y566699D01*
G01X444880Y574759D02*
X444882Y574757D01*
G01X444880Y579810D02*
Y574759D01*
G01X424801Y561700D02*
Y566807D01*
G01X428147Y536959D02*
X428149Y536957D01*
G01X428147Y542010D02*
Y536959D01*
G01X454919Y536792D02*
X454533Y534700D01*
G01X454919Y542010D02*
Y536792D01*
G01Y574592D02*
X454533Y572500D01*
G01X454919Y579810D02*
Y574592D01*
G01X421455Y566821D02*
X421456Y566822D01*
G01X421455Y561700D02*
Y566821D01*
G01X431494Y561700D02*
Y566807D01*
G01X434840Y536959D02*
X434842Y536957D01*
G01X434840Y542010D02*
Y536959D01*
G01X444880D02*
X444882Y536957D01*
G01X444880Y542010D02*
Y536959D01*
G01X421455Y529021D02*
X421456Y529022D01*
G01X451573Y561700D02*
Y566699D01*
G01X428147Y617610D02*
Y612657D01*
G01X461612Y617633D02*
X460912Y610300D01*
G01X461612Y617610D02*
Y617633D01*
G01X421455Y607291D02*
X421454Y607292D01*
G01X421455Y599500D02*
Y607291D01*
G01X438187Y599500D02*
Y604614D01*
G01X431494Y599500D02*
Y604499D01*
G01X474998Y599500D02*
Y604499D01*
G01X454919Y612392D02*
X454533Y610300D01*
G01X454919Y617610D02*
Y612392D01*
G01X434840Y617610D02*
Y612657D01*
G01X444880Y599500D02*
Y604614D01*
G01X438187Y617610D02*
Y609864D01*
G01X458266Y599500D02*
Y604499D01*
G01X424801Y599500D02*
Y604614D01*
G01X451573Y599500D02*
Y604499D01*
G01X444880Y617610D02*
Y609864D01*
G01X498423Y3233D02*
X497723Y-4100D01*
G01X511809Y-14877D02*
Y-9901D01*
G01X488384Y22923D02*
Y27899D01*
G01X535234Y3233D02*
X534534Y-4100D01*
G01X491730Y-2008D02*
X491344Y-4100D01*
G01X491730Y3233D02*
Y-2008D01*
G01X495077Y22923D02*
Y27899D01*
G01X511809Y22923D02*
Y27899D01*
G01X531888Y22923D02*
Y27899D01*
G01X518502Y22923D02*
Y27899D01*
G01Y-14877D02*
Y-9901D01*
G01X531888Y-14877D02*
Y-9901D01*
G01X478345Y-3699D02*
X478344Y-3700D01*
G01X478345Y-2500D02*
Y-3699D01*
G01X478865Y-1980D02*
X478345Y-2500D01*
G01X478865Y-1120D02*
Y-1980D01*
G01X478345Y-600D02*
X478865Y-1120D01*
G01X478345Y3232D02*
Y-600D01*
G01X478344Y3233D02*
X478345Y3232D01*
G01X515156Y-3699D02*
X515155Y-3700D01*
G01X515156Y-2500D02*
Y-3699D01*
G01X515676Y-1980D02*
X515156Y-2500D01*
G01X515676Y-1120D02*
Y-1980D01*
G01X515156Y-600D02*
X515676Y-1120D01*
G01X515156Y3232D02*
Y-600D01*
G01X515155Y3233D02*
X515156Y3232D01*
G01X525195Y-14877D02*
Y-9901D01*
G01X495077Y-14877D02*
Y-9901D01*
G01X481691Y-14877D02*
Y-9901D01*
G01Y22923D02*
Y27899D01*
G01X521848Y-2608D02*
Y-3700D01*
G01X522366Y-2090D02*
X521848Y-2608D01*
G01X522366Y-1210D02*
Y-2090D01*
G01X521848Y-692D02*
X522366Y-1210D01*
G01X521848Y3233D02*
Y-692D01*
G01X488384Y-14877D02*
Y-9901D01*
G01X525195Y22923D02*
Y27899D01*
G01X485037Y-2608D02*
Y-3700D01*
G01X485555Y-2090D02*
X485037Y-2608D01*
G01X485555Y-1210D02*
Y-2090D01*
G01X485037Y-692D02*
X485555Y-1210D01*
G01X485037Y3233D02*
Y-692D01*
G01X528541Y-2008D02*
X528155Y-4100D01*
G01X528541Y3233D02*
Y-2008D01*
G01X531888Y60723D02*
Y65699D01*
G01X515156Y34101D02*
X515155Y34100D01*
G01X515156Y35300D02*
Y34101D01*
G01X515676Y35820D02*
X515156Y35300D01*
G01X515676Y36680D02*
Y35820D01*
G01X515156Y37200D02*
X515676Y36680D01*
G01X515156Y41032D02*
Y37200D01*
G01X515155Y41033D02*
X515156Y41032D01*
G01X479092Y104992D02*
Y94100D01*
G01X495077Y60723D02*
Y65699D01*
G01X491492Y34500D02*
X491344Y33700D01*
G01X491584Y35000D02*
X491492Y34500D01*
G01X491730Y35792D02*
X491584Y35000D01*
G01X491730Y41033D02*
Y35792D01*
G01X521848Y35192D02*
Y34100D01*
G01X522366Y35710D02*
X521848Y35192D01*
G01X522366Y36590D02*
Y35710D01*
G01X521848Y37108D02*
X522366Y36590D01*
G01X521848Y41033D02*
Y37108D01*
G01X528541Y73592D02*
X528155Y71500D01*
G01X528541Y78833D02*
Y73592D01*
G01X485037Y35192D02*
Y34100D01*
G01X485555Y35710D02*
X485037Y35192D01*
G01X485555Y36590D02*
Y35710D01*
G01X485037Y37108D02*
X485555Y36590D01*
G01X485037Y41033D02*
Y37108D01*
G01X525195Y60723D02*
Y65699D01*
G01X485037Y72992D02*
Y71900D01*
G01X485555Y73510D02*
X485037Y72992D01*
G01X485555Y74390D02*
Y73510D01*
G01X485037Y74908D02*
X485555Y74390D01*
G01X485037Y78833D02*
Y74908D01*
G01X480592Y91658D02*
X481691Y92757D01*
G01X480592Y90340D02*
Y91658D01*
G01X481584Y89348D02*
X480592Y90340D01*
G01X482292Y89348D02*
X481584D01*
G01X483178Y90234D02*
X482292Y89348D01*
G01X483178Y91176D02*
Y90234D01*
G01X483492Y91490D02*
X483178Y91176D01*
G01X483492Y92101D02*
Y91490D01*
G01X484192Y92801D02*
X483492Y92101D01*
G01X484192Y94700D02*
Y92801D01*
G01X481691Y97201D02*
X484192Y94700D01*
G01X478345Y71901D02*
X478344Y71900D01*
G01X478345Y73100D02*
Y71901D01*
G01X478865Y73620D02*
X478345Y73100D01*
G01X478865Y74480D02*
Y73620D01*
G01X478345Y75000D02*
X478865Y74480D01*
G01X478345Y78832D02*
Y75000D01*
G01X478344Y78833D02*
X478345Y78832D01*
G01X534610Y34500D02*
X534534Y33700D01*
G01X534658Y35000D02*
X534610Y34500D01*
G01X535234Y41033D02*
X534658Y35000D01*
G01X497799Y34500D02*
X497723Y33700D01*
G01X497847Y35000D02*
X497799Y34500D01*
G01X498423Y41033D02*
X497847Y35000D01*
G01X488384Y60723D02*
Y65699D01*
G01X491730Y73592D02*
X491344Y71500D01*
G01X491730Y78833D02*
Y73592D01*
G01X528303Y34500D02*
X528155Y33700D01*
G01X528395Y35000D02*
X528303Y34500D01*
G01X528541Y35792D02*
X528395Y35000D01*
G01X528541Y41033D02*
Y35792D01*
G01X478345Y34101D02*
X478344Y34100D01*
G01X478345Y35300D02*
Y34101D01*
G01X478865Y35820D02*
X478345Y35300D01*
G01X478865Y36680D02*
Y35820D01*
G01X478345Y37200D02*
X478865Y36680D01*
G01X478345Y41032D02*
Y37200D01*
G01X478344Y41033D02*
X478345Y41032D01*
G01X521848Y72992D02*
Y71900D01*
G01X522366Y73510D02*
X521848Y72992D01*
G01X522366Y74390D02*
Y73510D01*
G01X521848Y74908D02*
X522366Y74390D01*
G01X521848Y78833D02*
Y74908D01*
G01X518502Y60723D02*
Y65699D01*
G01X534916Y75500D02*
X534534Y71500D01*
G01X535234Y78833D02*
X534916Y75500D01*
G01X515156Y71901D02*
X515155Y71900D01*
G01X515156Y73100D02*
Y71901D01*
G01X515676Y73620D02*
X515156Y73100D01*
G01X515676Y74480D02*
Y73620D01*
G01X515156Y75000D02*
X515676Y74480D01*
G01X515156Y78832D02*
Y75000D01*
G01X515155Y78833D02*
X515156Y78832D01*
G01X487092Y89769D02*
X485037Y87714D01*
G01X487961Y89769D02*
X487092D01*
G01X490738Y92546D02*
X487961Y89769D01*
G01X490738Y95454D02*
Y92546D01*
G01X481691Y60723D02*
Y65699D01*
G01X511809Y60723D02*
Y65699D01*
G01X498105Y75500D02*
X497723Y71500D01*
G01X498423Y78833D02*
X498105Y75500D01*
G01X490666Y106200D02*
X491430Y106964D01*
G01X489008Y106200D02*
X490666D01*
G01X487594Y107614D02*
X489008Y106200D01*
G01X487594Y109750D02*
Y107614D01*
G01X488244Y110400D02*
X487594Y109750D01*
G01X489592Y110400D02*
X488244D01*
G01X490992Y111800D02*
X489592Y110400D01*
G01X490992Y113600D02*
Y111800D01*
G01X488242Y116350D02*
X490992Y113600D01*
G01X486092Y118500D02*
X488242Y116350D01*
G01X486092Y122600D02*
Y118500D01*
G01X512024Y114668D02*
Y112357D01*
G01X508892Y117800D02*
X512024Y114668D01*
G01X508892Y122500D02*
Y117800D01*
G01Y127800D02*
Y122500D01*
G01X505158Y131534D02*
X508892Y127800D01*
G01X505158Y132454D02*
Y131534D01*
G01X507038Y134334D02*
X505158Y132454D01*
G01X507038Y135254D02*
Y134334D01*
G01X506084Y136208D02*
X507038Y135254D01*
G01X505164Y136208D02*
X506084D01*
G01X503284Y134328D02*
X505164Y136208D01*
G01X502364Y134328D02*
X503284D01*
G01X501410Y135282D02*
X502364Y134328D01*
G01X501410Y136202D02*
Y135282D01*
G01X503290Y138082D02*
X501410Y136202D01*
G01X503290Y139002D02*
Y138082D01*
G01X502336Y139956D02*
X503290Y139002D01*
G01X501416Y139956D02*
X502336D01*
G01X499536Y138076D02*
X501416Y139956D01*
G01X498616Y138076D02*
X499536D01*
G01X497662Y139030D02*
X498616Y138076D01*
G01X497662Y139950D02*
Y139030D01*
G01X499542Y141830D02*
X497662Y139950D01*
G01X499542Y142750D02*
Y141830D01*
G01X498588Y143704D02*
X499542Y142750D01*
G01X497668Y143704D02*
X498588D01*
G01X495788Y141824D02*
X497668Y143704D01*
G01X494868Y141824D02*
X495788D01*
G01X479092Y157600D02*
X494868Y141824D01*
G01X483292Y117699D02*
X488634Y112357D01*
G01X483292Y121601D02*
Y117699D01*
G01X518317Y118599D02*
Y112357D01*
G01X517667Y119249D02*
X518317Y118599D01*
G01X515142Y119249D02*
X517667D01*
G01X514492Y119899D02*
X515142Y119249D01*
G01X514492Y121249D02*
Y119899D01*
G01X515142Y121899D02*
X514492Y121249D01*
G01X517667Y121899D02*
X515142D01*
G01X518317Y122549D02*
X517667Y121899D01*
G01X518317Y124850D02*
Y122549D01*
G01X517667Y125500D02*
X518317Y124850D01*
G01X514842Y125500D02*
X517667D01*
G01X514192Y126150D02*
X514842Y125500D01*
G01X514192Y127523D02*
Y126150D01*
G01X514842Y128173D02*
X514192Y127523D01*
G01X515792Y128173D02*
X514842D01*
G01X516442Y128823D02*
X515792Y128173D01*
G01X516442Y130500D02*
Y128823D01*
G01Y134850D02*
Y130500D01*
G01X502092Y149200D02*
X516442Y134850D01*
G01X494692Y149200D02*
X502092D01*
G01X485692Y158200D02*
X494692Y149200D01*
G01X497723Y102150D02*
Y106964D01*
G01X497073Y101500D02*
X497723Y102150D01*
G01X494892Y101500D02*
X497073D01*
G01X493092Y103300D02*
X494892Y101500D01*
G01X493092Y105200D02*
Y103300D01*
G01X494692Y106800D02*
X493092Y105200D01*
G01X494692Y109224D02*
Y106800D01*
G01X496902Y111434D02*
X494692Y109224D01*
G01X496902Y116000D02*
Y111434D01*
G01Y119010D02*
Y116000D01*
G01X497892Y120000D02*
X496902Y119010D01*
G01X497892Y121400D02*
Y120000D01*
G01X497392Y121900D02*
X497892Y121400D01*
G01X495892Y121900D02*
X497392D01*
G01X484561Y133231D02*
X495892Y121900D01*
G01X484561Y137331D02*
Y133231D01*
G01X479292Y142600D02*
X484561Y137331D01*
G01X511492Y135675D02*
Y133000D01*
G01X500848Y146400D02*
X511492Y135675D01*
G01X493892Y146400D02*
X500848D01*
G01X482392Y157900D02*
X493892Y146400D01*
G01X513328Y106964D02*
X514820D01*
G01X512692Y107600D02*
X513328Y106964D01*
G01X512692Y110348D02*
Y107600D01*
G01X514681Y112337D02*
X512692Y110348D01*
G01X514681Y116110D02*
Y112337D01*
G01X511492Y119299D02*
X514681Y116110D01*
G01X511492Y133000D02*
Y119299D01*
G01X533203Y128720D02*
Y119500D01*
G01X534992Y130509D02*
X533203Y128720D01*
G01X534992Y138214D02*
Y130509D01*
G01X536442Y139664D02*
X534992Y138214D01*
G01X536442Y142650D02*
Y139664D01*
G01X518692Y160400D02*
X536442Y142650D01*
G01X534534Y104092D02*
Y106964D01*
G01X532642Y102200D02*
X534534Y104092D01*
G01X530142Y102200D02*
X532642D01*
G01X529492Y102850D02*
X530142Y102200D01*
G01X529492Y105400D02*
Y102850D01*
G01X531692Y107600D02*
X529492Y105400D01*
G01X531692Y109500D02*
Y107600D01*
G01X533692Y111500D02*
X531692Y109500D01*
G01X533692Y113200D02*
Y111500D01*
G01X533203Y113689D02*
X533692Y113200D01*
G01X533203Y119500D02*
Y113689D01*
G01X523092Y108943D02*
X521113Y106964D01*
G01X523092Y110320D02*
Y108943D01*
G01X521052Y112360D02*
X523092Y110320D01*
G01X521052Y117000D02*
Y112360D01*
G01Y134140D02*
Y117000D01*
G01X503392Y151800D02*
X521052Y134140D01*
G01X495792Y151800D02*
X503392D01*
G01X488211Y159381D02*
X495792Y151800D01*
G01X481691Y107850D02*
Y104000D01*
G01D02*
Y97201D01*
G01X530492Y113753D02*
X531888Y112357D01*
G01X530492Y129572D02*
Y113753D01*
G01X532473Y131553D02*
X530492Y129572D01*
G01X532473Y132950D02*
Y131553D01*
G01X530192Y135231D02*
X532473Y132950D01*
G01X530192Y137519D02*
Y135231D01*
G01X533747Y141074D02*
X530192Y137519D01*
G01X533747Y141782D02*
Y141074D01*
G01X532090Y143439D02*
X533747Y141782D01*
G01X531382Y143439D02*
X532090D01*
G01X530071Y142128D02*
X531382Y143439D01*
G01X529363Y142128D02*
X530071D01*
G01X528097Y143394D02*
X529363Y142128D01*
G01X528097Y144104D02*
Y143394D01*
G01X529407Y145414D02*
X528097Y144104D01*
G01X529407Y146122D02*
Y145414D01*
G01X527993Y147536D02*
X529407Y146122D01*
G01X527285Y147536D02*
X527993D01*
G01X524174Y144425D02*
X527285Y147536D01*
G01X523466Y144425D02*
X524174D01*
G01X522384Y145507D02*
X523466Y144425D01*
G01X522384Y146229D02*
Y145507D01*
G01X525175Y149020D02*
X522384Y146229D01*
G01X525175Y150316D02*
Y149020D01*
G01X516092Y159399D02*
X525175Y150316D01*
G01X493692Y113592D02*
X494927Y112357D01*
G01X493692Y114900D02*
Y113592D01*
G01X492292Y116300D02*
X493692Y114900D01*
G01X492292Y117200D02*
Y116300D01*
G01X494188Y119096D02*
X492292Y117200D01*
G01X494188Y119804D02*
Y119096D01*
G01X492752Y121240D02*
X494188Y119804D01*
G01X491832Y121240D02*
X492752D01*
G01X490152Y119560D02*
X491832Y121240D01*
G01X489444Y119560D02*
X490152D01*
G01X488611Y120393D02*
X489444Y119560D01*
G01X488611Y121767D02*
Y120393D01*
G01X489958Y123114D02*
X488611Y121767D01*
G01X489958Y124034D02*
Y123114D01*
G01X482042Y131950D02*
X489958Y124034D01*
G01X482042Y136150D02*
Y131950D01*
G01X524392Y113099D02*
X525134Y112357D01*
G01X524392Y132500D02*
Y113099D01*
G01Y135496D02*
Y132500D01*
G01X509896Y149992D02*
X524392Y135496D01*
G01X509896Y151016D02*
Y149992D01*
G01X510850Y151970D02*
X509896Y151016D01*
G01X511770Y151970D02*
X510850D01*
G01X513906Y149834D02*
X511770Y151970D01*
G01X514826Y149834D02*
X513906D01*
G01X515703Y150711D02*
X514826Y149834D01*
G01X515703Y151631D02*
Y150711D01*
G01X511770Y155564D02*
X515703Y151631D01*
G01X510850Y155564D02*
X511770D01*
G01X510049Y154763D02*
X510850Y155564D01*
G01X509129Y154763D02*
X510049D01*
G01X508146Y155746D02*
X509129Y154763D01*
G01X508146Y156454D02*
Y155746D01*
G01X484492Y101700D02*
X490738Y95454D01*
G01X484492Y110200D02*
Y101700D01*
G01X481792Y112900D02*
X484492Y110200D01*
G01X479364Y115328D02*
X481792Y112900D01*
G01X479364Y119938D02*
Y115328D01*
G01X526911Y136541D02*
Y125000D01*
G01X516428Y147024D02*
X526911Y136541D01*
G01X516428Y147872D02*
Y147024D01*
G01X517620Y149064D02*
X516428Y147872D01*
G01X518328Y149064D02*
X517620D01*
G01X519288Y148104D02*
X518328Y149064D01*
G01X519996Y148104D02*
X519288D01*
G01X521488Y149596D02*
X519996Y148104D01*
G01X521488Y150304D02*
Y149596D01*
G01X513560Y158232D02*
X521488Y150304D01*
G01X526266Y109289D02*
X528241Y107314D01*
G01X526266Y110574D02*
Y109289D01*
G01X527973Y112281D02*
X526266Y110574D01*
G01X527973Y114719D02*
Y112281D01*
G01X526911Y115781D02*
X527973Y114719D01*
G01X526911Y125000D02*
Y115781D01*
G01X479092Y159800D02*
Y157600D01*
G01X532938Y171200D02*
X557692Y146446D01*
G01X485692Y160407D02*
Y158200D01*
G01X482296Y163803D02*
X485692Y160407D01*
G01X482392Y160100D02*
Y157900D01*
G01X479792Y162700D02*
X482392Y160100D01*
G01X518692Y165406D02*
Y160400D01*
G01X518660Y165438D02*
X518692Y165406D01*
G01X488211Y162081D02*
Y159381D01*
G01X484392Y165900D02*
X488211Y162081D01*
G01X516092Y165812D02*
Y159399D01*
G01X516110Y165830D02*
X516092Y165812D01*
G01X531592Y168982D02*
X555147Y145427D01*
G01X511010Y159318D02*
X508146Y156454D01*
G01X511010Y167318D02*
Y159318D01*
G01X485682Y216196D02*
X483432D01*
G01X529692Y167319D02*
X547328Y149683D01*
G01X513560Y166768D02*
Y158232D01*
G01X534102Y173600D02*
X560211Y147491D01*
G01X485682Y220096D02*
X483432D01*
G01X485682Y227896D02*
X483432D01*
G01X481172Y383896D02*
X478922D01*
G01Y368296D02*
X481172D01*
G01X492442Y399496D02*
X494692D01*
G01X489062Y393647D02*
X491312D01*
G01X489062Y401447D02*
X491312D01*
G01X492442Y395597D02*
X494692D01*
G01X482302Y389747D02*
X484552D01*
G01X481172Y387796D02*
X478922D01*
G01X489062Y381947D02*
X491312D01*
G01X481172Y360496D02*
X478922D01*
G01X492442Y356596D02*
X494692D01*
G01X482302Y374146D02*
X484552D01*
G01X481172Y376096D02*
X478922D01*
G01X482302Y381947D02*
X484552D01*
G01X505408Y463515D02*
X518301Y476408D01*
G01X505408Y462595D02*
Y463515D01*
G01X507264Y460739D02*
X505408Y462595D01*
G01X507264Y459896D02*
Y460739D01*
G01X506310Y458942D02*
X507264Y459896D01*
G01X505313Y458942D02*
X506310D01*
G01X503534Y460721D02*
X505313Y458942D01*
G01X502086Y460721D02*
X503534D01*
G01X500194Y458829D02*
X502086Y460721D01*
G01X500194Y455744D02*
Y458829D01*
G01X499658Y455208D02*
X500194Y455744D01*
G01X497804Y455208D02*
X499658D01*
G01X497269Y455743D02*
X497804Y455208D01*
G01X497269Y457485D02*
Y455743D01*
G01X496677Y458077D02*
X497269Y457485D01*
G01X495969Y458077D02*
X496677D01*
G01X483492Y445600D02*
X495969Y458077D01*
G01X538542Y426650D02*
X537342D01*
G01X553353Y441461D02*
X538542Y426650D01*
G01X509924Y464295D02*
X520832Y475203D01*
G01X509924Y458949D02*
Y464295D01*
G01X507355Y456380D02*
X509924Y458949D01*
G01X504580Y456380D02*
X507355D01*
G01X500889Y452689D02*
X504580Y456380D01*
G01X494981Y452689D02*
X500889D01*
G01X485792Y443500D02*
X494981Y452689D01*
G01X483188Y464388D02*
Y465486D01*
G01X482412Y463612D02*
X483188Y464388D01*
G01X481314Y463612D02*
X482412D01*
G01X480408Y464518D02*
X481314Y463612D01*
G01X479310Y464518D02*
X480408D01*
G01X478534Y463742D02*
X479310Y464518D01*
G01X478534Y462644D02*
Y463742D01*
G01X479440Y461738D02*
X478534Y462644D01*
G01X479440Y460640D02*
Y461738D01*
G01X478664Y459864D02*
X479440Y460640D01*
G01X525092Y460100D02*
Y466200D01*
G01X517564Y452572D02*
X525092Y460100D01*
G01X517564Y451474D02*
Y452572D01*
G01X520266Y448772D02*
X517564Y451474D01*
G01X520266Y447674D02*
Y448772D01*
G01X519490Y446898D02*
X520266Y447674D01*
G01X518392Y446898D02*
X519490D01*
G01X515690Y449600D02*
X518392Y446898D01*
G01X514592Y449600D02*
X515690D01*
G01X513092Y448100D02*
X514592Y449600D01*
G01X513092Y445700D02*
Y448100D01*
G01X518192Y440600D02*
X513092Y445700D01*
G01X518192Y437650D02*
Y440600D01*
G01X538392Y423900D02*
X541392D01*
G01X512497Y463288D02*
X523392Y474183D01*
G01X512497Y462103D02*
Y463288D01*
G01X513147Y461453D02*
X512497Y462103D01*
G01X515351Y461453D02*
X513147D01*
G01X516001Y460803D02*
X515351Y461453D01*
G01X516001Y459453D02*
Y460803D01*
G01X515351Y458803D02*
X516001Y459453D01*
G01X513147Y458803D02*
X515351D01*
G01X512497Y458153D02*
X513147Y458803D01*
G01X512497Y456632D02*
Y458153D01*
G01X509723Y453858D02*
X512497Y456632D01*
G01X505663Y453858D02*
X509723D01*
G01X501913Y450108D02*
X505663Y453858D01*
G01X496000Y450108D02*
X501913D01*
G01X487592Y441700D02*
X496000Y450108D01*
G01X539241Y433249D02*
X540941D01*
G01X538217Y432225D02*
X539241Y433249D01*
G01X538217Y430525D02*
Y432225D01*
G01X537092Y429400D02*
X538217Y430525D01*
G01X535560Y429400D02*
X537092D01*
G01X533242Y427082D02*
X535560Y429400D01*
G01X530988Y428996D02*
X548039Y446047D01*
G01X527992Y451501D02*
Y465200D01*
G01X527607Y451116D02*
X527992Y451501D01*
G01X526511Y451116D02*
X527607D01*
G01X523758Y453868D02*
X526511Y451116D01*
G01X522662Y453868D02*
X523758D01*
G01X521884Y453090D02*
X522662Y453868D01*
G01X521884Y451994D02*
Y453090D01*
G01X526692Y447188D02*
X521884Y451994D01*
G01X526692Y445401D02*
Y447188D01*
G01X520792Y439501D02*
X526692Y445401D01*
G01X520792Y438001D02*
Y439501D01*
G01X522392Y461000D02*
Y467499D01*
G01X509892Y448500D02*
X522392Y461000D01*
G01X509892Y445100D02*
Y448500D01*
G01X515592Y439400D02*
X509892Y445100D01*
G01X515592Y438200D02*
Y439400D01*
G01X499441Y461648D02*
X511717Y473924D01*
G01X495940Y461648D02*
X499441D01*
G01X480242Y445950D02*
X495940Y461648D01*
G01X537092Y456750D02*
Y488900D01*
G01X536442Y456100D02*
X537092Y456750D01*
G01X535092Y456100D02*
X536442D01*
G01X534442Y456750D02*
X535092Y456100D01*
G01X534442Y463150D02*
Y456750D01*
G01X533792Y463800D02*
X534442Y463150D01*
G01X532442Y463800D02*
X533792D01*
G01X531792Y463150D02*
X532442Y463800D01*
G01X531792Y445700D02*
Y463150D01*
G01X522792Y436700D02*
X531792Y445700D01*
G01X491430Y486262D02*
Y491144D01*
G01X493031Y484661D02*
X491430Y486262D01*
G01X493031Y481439D02*
Y484661D01*
G01X490492Y478900D02*
X493031Y481439D01*
G01X488804Y478900D02*
X490492D01*
G01X486552Y481152D02*
X488804Y478900D01*
G01X485844Y481152D02*
X486552D01*
G01X484678Y479986D02*
X485844Y481152D01*
G01X484678Y479278D02*
Y479986D01*
G01X485245Y478711D02*
X484678Y479278D01*
G01X485245Y477791D02*
Y478711D01*
G01X484291Y476837D02*
X485245Y477791D01*
G01X483371Y476837D02*
X484291D01*
G01X482676Y477532D02*
X483371Y476837D01*
G01X481756Y477532D02*
X482676D01*
G01X480802Y476578D02*
X481756Y477532D01*
G01X480802Y475658D02*
Y476578D01*
G01X481497Y474963D02*
X480802Y475658D01*
G01X481497Y474043D02*
Y474963D01*
G01X480543Y473089D02*
X481497Y474043D01*
G01X479623Y473089D02*
X480543D01*
G01X478928Y473784D02*
X479623Y473089D01*
G01X516592Y491907D02*
X514755Y493744D01*
G01X516592Y487800D02*
Y491907D01*
G01X518301Y486091D02*
X516592Y487800D01*
G01X518301Y476408D02*
Y486091D01*
G01X488384Y523900D02*
Y528899D01*
G01X531888Y523900D02*
Y528899D01*
G01X519692Y496697D02*
X517902Y498487D01*
G01X519692Y495000D02*
Y496697D01*
G01X519192Y494500D02*
X519692Y495000D01*
G01X519192Y488800D02*
Y494500D01*
G01X520832Y487160D02*
X519192Y488800D01*
G01X520832Y475203D02*
Y487160D01*
G01X481691Y523900D02*
Y528899D01*
G01X488278Y513114D02*
X485037D01*
G01X490492Y510900D02*
X488278Y513114D01*
G01X490492Y507000D02*
Y510900D01*
G01X489161Y505669D02*
X490492Y507000D01*
G01X488241Y505669D02*
X489161D01*
G01X486541Y507369D02*
X488241Y505669D01*
G01X485746Y507369D02*
X486541D01*
G01X484374Y505997D02*
X485746Y507369D01*
G01X484374Y504952D02*
Y505997D01*
G01X485949Y503377D02*
X484374Y504952D01*
G01X485949Y502457D02*
Y503377D01*
G01X484892Y501400D02*
X485949Y502457D01*
G01X484892Y490168D02*
Y501400D01*
G01X511809Y523900D02*
Y528899D01*
G01X498423Y490894D02*
X497723D01*
G01X500317Y489000D02*
X498423Y490894D01*
G01X500317Y485729D02*
Y489000D01*
G01X499492Y484904D02*
X500317Y485729D01*
G01X499492Y480392D02*
Y484904D01*
G01X491596Y472496D02*
X499492Y480392D01*
G01X491296Y472496D02*
X491596D01*
G01X489908Y471108D02*
X491296Y472496D01*
G01X488810Y471108D02*
X489908D01*
G01X487904Y472014D02*
X488810Y471108D01*
G01X486806Y472014D02*
X487904D01*
G01X486030Y471238D02*
X486806Y472014D01*
G01X486030Y470140D02*
Y471238D01*
G01X486936Y469234D02*
X486030Y470140D01*
G01X486936Y468136D02*
Y469234D01*
G01X486160Y467360D02*
X486936Y468136D01*
G01X485062Y467360D02*
X486160D01*
G01X484156Y468266D02*
X485062Y467360D01*
G01X483058Y468266D02*
X484156D01*
G01X482282Y467490D02*
X483058Y468266D01*
G01X482282Y466392D02*
Y467490D01*
G01X483188Y465486D02*
X482282Y466392D01*
G01X496079Y498487D02*
X494777D01*
G01X497077Y499485D02*
X496079Y498487D01*
G01X497077Y501015D02*
Y499485D01*
G01X496392Y501700D02*
X497077Y501015D01*
G01X492892Y501700D02*
X496392D01*
G01X492192Y501000D02*
X492892Y501700D01*
G01X492192Y495500D02*
Y501000D01*
G01X493192Y494500D02*
X492192Y495500D01*
G01X493192Y493200D02*
Y494500D01*
G01X493992Y492400D02*
X493192Y493200D01*
G01X493992Y487900D02*
Y492400D01*
G01X496392Y485500D02*
X493992Y487900D01*
G01X496392Y481000D02*
Y485500D01*
G01X491092Y475700D02*
X496392Y481000D01*
G01X486720Y475700D02*
X491092D01*
G01X530116Y491619D02*
X528191Y493544D01*
G01X530116Y488224D02*
Y491619D01*
G01X529649Y487757D02*
X530116Y488224D01*
G01X529649Y470757D02*
Y487757D01*
G01X525092Y466200D02*
X529649Y470757D01*
G01X522892Y492000D02*
X521048Y493844D01*
G01X522892Y488800D02*
Y492000D01*
G01X523392Y488300D02*
X522892Y488800D01*
G01X523392Y474183D02*
Y488300D01*
G01X480392Y516858D02*
X481691Y518157D01*
G01X480392Y515100D02*
Y516858D01*
G01X484342Y511150D02*
X480392Y515100D01*
G01X484342Y509796D02*
Y511150D01*
G01X482192Y507646D02*
X484342Y509796D01*
G01X482192Y491226D02*
Y507646D01*
G01X479300Y488334D02*
X482192Y491226D01*
G01X478324Y488334D02*
X479300D01*
G01X525195Y523900D02*
Y528899D01*
G01X490192Y496679D02*
X488384Y498487D01*
G01X490192Y495100D02*
Y496679D01*
G01X489592Y494500D02*
X490192Y495100D01*
G01X489592Y492800D02*
Y494500D01*
G01X488892Y492100D02*
X489592Y492800D01*
G01X488892Y484900D02*
Y492100D01*
G01X488092Y484100D02*
X488892Y484900D01*
G01X484570Y484100D02*
X488092D01*
G01X531988Y498387D02*
X530792D01*
G01X532666Y497709D02*
X531988Y498387D01*
G01X532666Y486927D02*
Y497709D01*
G01X534392Y485201D02*
X532666Y486927D01*
G01X534392Y471600D02*
Y485201D01*
G01X527992Y465200D02*
X534392Y471600D01*
G01X526392Y496590D02*
X524595Y498387D01*
G01X526392Y489900D02*
Y496590D01*
G01X526792Y489500D02*
X526392Y489900D01*
G01X526792Y471899D02*
Y489500D01*
G01X522392Y467499D02*
X526792Y471899D01*
G01X513492Y496804D02*
X511809Y498487D01*
G01X513492Y495000D02*
Y496804D01*
G01X512592Y494100D02*
X513492Y495000D01*
G01X512592Y488200D02*
Y494100D01*
G01X515644Y485148D02*
X512592Y488200D01*
G01X515644Y477851D02*
Y485148D01*
G01X514594Y476801D02*
X515644Y477851D01*
G01X513619Y476801D02*
X514594D01*
G01X513095Y477325D02*
X513619Y476801D01*
G01X512119Y477325D02*
X513095D01*
G01X511191Y476397D02*
X512119Y477325D01*
G01X511191Y475423D02*
Y476397D01*
G01X511716Y474898D02*
X511191Y475423D01*
G01X511717Y473924D02*
X511716Y474898D01*
G01X535966Y493394D02*
X534534D01*
G01X536466Y492894D02*
X535966Y493394D01*
G01X536466Y489526D02*
Y492894D01*
G01X537092Y488900D02*
X536466Y489526D01*
G01X495077Y523900D02*
Y528899D01*
G01X479792Y511666D02*
X478344Y513114D01*
G01X479792Y509142D02*
Y511666D01*
G01X480073Y503045D02*
X479448Y503670D01*
G01X480073Y501105D02*
Y503045D01*
G01X479398Y500430D02*
X480073Y501105D01*
G01X478742Y500430D02*
X479398D01*
G01X478942Y496190D02*
X478842D01*
G01X479592Y495540D02*
X478942Y496190D01*
G01X479592Y493600D02*
Y495540D01*
G01X478942Y492950D02*
X479592Y493600D01*
G01X518502Y523900D02*
Y528899D01*
G01X515156Y535101D02*
X515155Y535100D01*
G01X515156Y536300D02*
Y535101D01*
G01X515676Y536820D02*
X515156Y536300D01*
G01X515676Y537680D02*
Y536820D01*
G01X515156Y538200D02*
X515676Y537680D01*
G01X515156Y542010D02*
Y538200D01*
G01X515155Y542010D02*
X515156D01*
G01X528541Y536792D02*
X528155Y534700D01*
G01X528541Y542010D02*
Y536792D01*
G01X488384Y561700D02*
Y566699D01*
G01X478345Y535101D02*
X478344Y535100D01*
G01X478345Y536300D02*
Y535101D01*
G01X478865Y536820D02*
X478345Y536300D01*
G01X478865Y537680D02*
Y536820D01*
G01X478345Y538200D02*
X478865Y537680D01*
G01X478345Y542010D02*
Y538200D01*
G01X478344Y542010D02*
X478345D01*
G01X511809Y561700D02*
Y566699D01*
G01X521848Y573992D02*
Y572900D01*
G01X522366Y574510D02*
X521848Y573992D01*
G01X522366Y575390D02*
Y574510D01*
G01X521848Y575908D02*
X522366Y575390D01*
G01X521848Y579810D02*
Y575908D01*
G01Y536192D02*
Y535100D01*
G01X522366Y536710D02*
X521848Y536192D01*
G01X522366Y537590D02*
Y536710D01*
G01X521848Y538108D02*
X522366Y537590D01*
G01X521848Y542010D02*
Y538108D01*
G01X495077Y561700D02*
Y566699D01*
G01X498423Y579833D02*
X497723Y572500D01*
G01X498423Y579810D02*
Y579833D01*
G01X491730Y536792D02*
X491344Y534700D01*
G01X491730Y542010D02*
Y536792D01*
G01X525195Y561700D02*
Y566699D01*
G01X518502Y561700D02*
Y566699D01*
G01X485037Y536192D02*
Y535100D01*
G01X485555Y536710D02*
X485037Y536192D01*
G01X485555Y537590D02*
Y536710D01*
G01X485037Y538108D02*
X485555Y537590D01*
G01X485037Y542010D02*
Y538108D01*
G01X491730Y574592D02*
X491344Y572500D01*
G01X491730Y579810D02*
Y574592D01*
G01X478345Y572901D02*
X478344Y572900D01*
G01X478345Y574100D02*
Y572901D01*
G01X478865Y574620D02*
X478345Y574100D01*
G01X478865Y575480D02*
Y574620D01*
G01X478345Y576000D02*
X478865Y575480D01*
G01X478345Y579810D02*
Y576000D01*
G01X478344Y579810D02*
X478345D01*
G01X535234Y542033D02*
X534534Y534700D01*
G01X535234Y542010D02*
Y542033D01*
G01Y579833D02*
X534534Y572500D01*
G01X535234Y579810D02*
Y579833D01*
G01X528541Y574592D02*
X528155Y572500D01*
G01X528541Y579810D02*
Y574592D01*
G01X481691Y561700D02*
Y566699D01*
G01X515156Y572901D02*
X515155Y572900D01*
G01X515156Y574100D02*
Y572901D01*
G01X515676Y574620D02*
X515156Y574100D01*
G01X515676Y575480D02*
Y574620D01*
G01X515156Y576000D02*
X515676Y575480D01*
G01X515156Y579810D02*
Y576000D01*
G01X515155Y579810D02*
X515156D01*
G01X485037Y573992D02*
Y572900D01*
G01X485555Y574510D02*
X485037Y573992D01*
G01X485555Y575390D02*
Y574510D01*
G01X485037Y575908D02*
X485555Y575390D01*
G01X485037Y579810D02*
Y575908D01*
G01X531888Y561700D02*
Y566699D01*
G01X498423Y542033D02*
X497723Y534700D01*
G01X498423Y542010D02*
Y542033D01*
G01X521848Y611792D02*
Y610700D01*
G01X522366Y612310D02*
X521848Y611792D01*
G01X522366Y613190D02*
Y612310D01*
G01X521848Y613708D02*
X522366Y613190D01*
G01X521848Y617610D02*
Y613708D01*
G01X525195Y599500D02*
Y604499D01*
G01X495077Y599500D02*
Y604499D01*
G01X535234Y617633D02*
X534534Y610300D01*
G01X535234Y617610D02*
Y617633D01*
G01X511809Y599500D02*
Y604499D01*
G01X515156Y610701D02*
X515155Y610700D01*
G01X515156Y611900D02*
Y610701D01*
G01X515676Y612420D02*
X515156Y611900D01*
G01X515676Y613280D02*
Y612420D01*
G01X515156Y613800D02*
X515676Y613280D01*
G01X515156Y617610D02*
Y613800D01*
G01X515155Y617610D02*
X515156D01*
G01X488384Y599500D02*
Y604499D01*
G01X481691Y599500D02*
Y604499D01*
G01X531888Y599500D02*
Y604499D01*
G01X491730Y611674D02*
X491724Y611668D01*
G01X491730Y617610D02*
Y611674D01*
G01X528541Y612392D02*
X528155Y610300D01*
G01X528541Y617610D02*
Y612392D01*
G01X478345Y610701D02*
X478344Y610700D01*
G01X478345Y611900D02*
Y610701D01*
G01X478865Y612420D02*
X478345Y611900D01*
G01X478865Y613280D02*
Y612420D01*
G01X478345Y613800D02*
X478865Y613280D01*
G01X478345Y617610D02*
Y613800D01*
G01X478344Y617610D02*
X478345D01*
G01X518502Y599500D02*
Y604499D01*
G01X485037Y611792D02*
Y610700D01*
G01X485555Y612310D02*
X485037Y611792D01*
G01X485555Y613190D02*
Y612310D01*
G01X485037Y613708D02*
X485555Y613190D01*
G01X485037Y617610D02*
Y613708D01*
G01X497838Y611507D02*
X498092Y611200D01*
G01X498423Y617633D02*
X497838Y611507D01*
G01X498423Y617610D02*
Y617633D01*
G01X595470Y-2608D02*
Y-3700D01*
G01X595988Y-2090D02*
X595470Y-2608D01*
G01X595988Y-1210D02*
Y-2090D01*
G01X595470Y-692D02*
X595988Y-1210D01*
G01X595470Y3233D02*
Y-692D01*
G01X568699Y-14877D02*
Y-9901D01*
G01X551967Y-3699D02*
X551966Y-3700D01*
G01X551967Y-2500D02*
Y-3699D01*
G01X552487Y-1980D02*
X551967Y-2500D01*
G01X552487Y-1120D02*
Y-1980D01*
G01X551967Y-600D02*
X552487Y-1120D01*
G01X551967Y3232D02*
Y-600D01*
G01X551966Y3233D02*
X551967Y3232D01*
G01X572045Y3233D02*
X571345Y-4100D01*
G01X592124Y-14877D02*
Y-9901D01*
G01X568699Y22923D02*
Y27899D01*
G01X592124Y22923D02*
Y27899D01*
G01X562006Y-14877D02*
Y-9901D01*
G01X548620Y22923D02*
Y27899D01*
G01X585431Y22923D02*
Y27899D01*
G01X548620Y-14877D02*
Y-9901D01*
G01X565352Y-2008D02*
X564966Y-4100D01*
G01X565352Y3233D02*
Y-2008D01*
G01X588778Y-3699D02*
X588777Y-3700D01*
G01X588778Y-2500D02*
Y-3699D01*
G01X589298Y-1980D02*
X588778Y-2500D01*
G01X589298Y-1120D02*
Y-1980D01*
G01X588778Y-600D02*
X589298Y-1120D01*
G01X588778Y3232D02*
Y-600D01*
G01X588777Y3233D02*
X588778Y3232D01*
G01X558659Y-2608D02*
Y-3700D01*
G01X559177Y-2090D02*
X558659Y-2608D01*
G01X559177Y-1210D02*
Y-2090D01*
G01X558659Y-692D02*
X559177Y-1210D01*
G01X558659Y3233D02*
Y-692D01*
G01X562006Y22923D02*
Y27899D01*
G01X585431Y-14877D02*
Y-9901D01*
G01X555313Y-14877D02*
Y-9901D01*
G01Y22923D02*
Y27899D01*
G01X592124Y60723D02*
Y65699D01*
G01X558659Y35192D02*
Y34100D01*
G01X559177Y35710D02*
X558659Y35192D01*
G01X559177Y36590D02*
Y35710D01*
G01X558659Y37108D02*
X559177Y36590D01*
G01X558659Y41033D02*
Y37108D01*
G01X585431Y60723D02*
Y65699D01*
G01X558659Y72992D02*
Y71900D01*
G01X559177Y73510D02*
X558659Y72992D01*
G01X559177Y74390D02*
Y73510D01*
G01X558659Y74908D02*
X559177Y74390D01*
G01X558659Y78833D02*
Y74908D01*
G01X551967Y71901D02*
X551966Y71900D01*
G01X551967Y73100D02*
Y71901D01*
G01X552487Y73620D02*
X551967Y73100D01*
G01X552487Y74480D02*
Y73620D01*
G01X551967Y75000D02*
X552487Y74480D01*
G01X551967Y78832D02*
Y75000D01*
G01X551966Y78833D02*
X551967Y78832D01*
G01X571727Y75500D02*
X571345Y71500D01*
G01X572045Y78833D02*
X571727Y75500D01*
G01X548620Y60723D02*
Y65699D01*
G01X595470Y35192D02*
Y34100D01*
G01X595988Y35710D02*
X595470Y35192D01*
G01X595988Y36590D02*
Y35710D01*
G01X595470Y37108D02*
X595988Y36590D01*
G01X595470Y41033D02*
Y37108D01*
G01Y72992D02*
Y71900D01*
G01X595988Y73510D02*
X595470Y72992D01*
G01X595988Y74390D02*
Y73510D01*
G01X595470Y74908D02*
X595988Y74390D01*
G01X595470Y78833D02*
Y74908D01*
G01X565352Y73592D02*
X564966Y71500D01*
G01X565352Y78833D02*
Y73592D01*
G01X555313Y60723D02*
Y65699D01*
G01X588778Y71901D02*
X588777Y71900D01*
G01X588778Y73100D02*
Y71901D01*
G01X589298Y73620D02*
X588778Y73100D01*
G01X589298Y74480D02*
Y73620D01*
G01X588778Y75000D02*
X589298Y74480D01*
G01X588778Y78832D02*
Y75000D01*
G01X588777Y78833D02*
X588778Y78832D01*
G01X565114Y34500D02*
X564966Y33700D01*
G01X565206Y35000D02*
X565114Y34500D01*
G01X565352Y35792D02*
X565206Y35000D01*
G01X565352Y41033D02*
Y35792D01*
G01X562006Y60723D02*
Y65699D01*
G01X551967Y34101D02*
X551966Y34100D01*
G01X551967Y35300D02*
Y34101D01*
G01X552487Y35820D02*
X551967Y35300D01*
G01X552487Y36680D02*
Y35820D01*
G01X551967Y37200D02*
X552487Y36680D01*
G01X551967Y41032D02*
Y37200D01*
G01X551966Y41033D02*
X551967Y41032D01*
G01X568699Y60723D02*
Y65699D01*
G01X588778Y34101D02*
X588777Y34100D01*
G01X588778Y35300D02*
Y34101D01*
G01X589298Y35820D02*
X588778Y35300D01*
G01X589298Y36680D02*
Y35820D01*
G01X588778Y37200D02*
X589298Y36680D01*
G01X588778Y41032D02*
Y37200D01*
G01X588777Y41033D02*
X588778Y41032D01*
G01X571421Y34500D02*
X571345Y33700D01*
G01X571469Y35000D02*
X571421Y34500D01*
G01X572045Y41033D02*
X571469Y35000D01*
G01X553611Y114059D02*
X555313Y112357D01*
G01X553611Y126062D02*
Y114059D01*
G01X554249Y126700D02*
X553611Y126062D01*
G01X555651Y126700D02*
X554249D01*
G01X556151Y126200D02*
X555651Y126700D01*
G01X556151Y122900D02*
Y126200D01*
G01X556651Y122400D02*
X556151Y122900D01*
G01X558191Y122400D02*
X556651D01*
G01X558691Y122900D02*
X558191Y122400D01*
G01X558691Y129400D02*
Y122900D01*
G01X557692Y130399D02*
X558691Y129400D01*
G01X557692Y133500D02*
Y130399D01*
G01Y146446D02*
Y133500D01*
G01X550171Y109109D02*
X551966Y107314D01*
G01X550171Y110879D02*
Y109109D01*
G01X551092Y111800D02*
X550171Y110879D01*
G01X551092Y127300D02*
Y111800D01*
G01X555147Y131355D02*
X551092Y127300D01*
G01X555147Y139000D02*
Y131355D01*
G01Y145427D02*
Y139000D01*
G01X548620Y113973D02*
Y112357D01*
G01X547328Y115265D02*
X548620Y113973D01*
G01X547328Y120500D02*
Y115265D01*
G01Y137150D02*
Y120500D01*
G01X547978Y137800D02*
X547328Y137150D01*
G01X549328Y137800D02*
X547978D01*
G01X549978Y137150D02*
X549328Y137800D01*
G01X549978Y134350D02*
Y137150D01*
G01X550628Y133700D02*
X549978Y134350D01*
G01X551978Y133700D02*
X550628D01*
G01X552628Y134350D02*
X551978Y133700D01*
G01X552628Y143219D02*
Y134350D01*
G01X551978Y143869D02*
X552628Y143219D01*
G01X547978Y143869D02*
X551978D01*
G01X547328Y144519D02*
X547978Y143869D01*
G01X547328Y149683D02*
Y144519D01*
G01X557020Y107314D02*
X558659D01*
G01X555892Y108442D02*
X557020Y107314D01*
G01X555892Y110201D02*
Y108442D01*
G01X557392Y111701D02*
X555892Y110201D01*
G01X557392Y116383D02*
Y111701D01*
G01X561210Y120201D02*
X557392Y116383D01*
G01X561210Y130444D02*
Y120201D01*
G01X560211Y131443D02*
X561210Y130444D01*
G01X560211Y140500D02*
Y131443D01*
G01Y147491D02*
Y140500D01*
G01X553353Y468161D02*
Y441461D01*
G01X556010Y438518D02*
Y466800D01*
G01X541392Y423900D02*
X556010Y438518D01*
G01X550696Y443004D02*
Y471904D01*
G01X548437Y440745D02*
X550696Y443004D01*
G01X546737Y440745D02*
X548437D01*
G01X545713Y439721D02*
X546737Y440745D01*
G01X545713Y438021D02*
Y439721D01*
G01X544689Y436997D02*
X545713Y438021D01*
G01X542989Y436997D02*
X544689D01*
G01X541965Y435973D02*
X542989Y436997D01*
G01X541965Y434273D02*
Y435973D01*
G01X540941Y433249D02*
X541965Y434273D01*
G01X548039Y446047D02*
Y474947D01*
G01X555313Y523900D02*
Y528899D01*
G01X558180Y472988D02*
X553353Y468161D01*
G01X558180Y491038D02*
Y472988D01*
G01X556792Y492426D02*
X558180Y491038D01*
G01X556792Y496608D02*
Y492426D01*
G01X554913Y498487D02*
X556792Y496608D01*
G01X554792Y498487D02*
X554913D01*
G01X560679Y496144D02*
X558659D01*
G01X562546Y494277D02*
X560679Y496144D01*
G01X562546Y490777D02*
Y494277D01*
G01X560837Y489068D02*
X562546Y490777D01*
G01X560837Y471627D02*
Y489068D01*
G01X556010Y466800D02*
X560837Y471627D01*
G01X592124Y523900D02*
Y528899D01*
G01X585431Y523900D02*
Y528899D01*
G01X553892Y493344D02*
X551366D01*
G01X554392Y492844D02*
X553892Y493344D01*
G01X554392Y489020D02*
Y492844D01*
G01X554892Y488520D02*
X554392Y489020D01*
G01X555022Y488520D02*
X554892D01*
G01X555523Y488019D02*
X555022Y488520D01*
G01X555523Y480502D02*
Y488019D01*
G01X554873Y479852D02*
X555523Y480502D01*
G01X554108Y479852D02*
X554873D01*
G01X553458Y479202D02*
X554108Y479852D01*
G01X553458Y477262D02*
Y479202D01*
G01X554108Y476612D02*
X553458Y477262D01*
G01X554873Y476612D02*
X554108D01*
G01X555651Y475834D02*
X554873Y476612D01*
G01X555651Y474259D02*
Y475834D01*
G01X554120Y472728D02*
X555651Y474259D01*
G01X551520Y472728D02*
X554120D01*
G01X550696Y471904D02*
X551520Y472728D01*
G01X548707Y498400D02*
X548492D01*
G01X550292Y496815D02*
X548707Y498400D01*
G01X550292Y494900D02*
Y496815D01*
G01X549292Y493900D02*
X550292Y494900D01*
G01X549292Y485200D02*
Y493900D01*
G01X550882Y483610D02*
X549292Y485200D01*
G01X550882Y477790D02*
Y483610D01*
G01X548039Y474947D02*
X550882Y477790D01*
G01X568699Y523900D02*
Y528899D01*
G01X548620Y523900D02*
Y528899D01*
G01X562006Y523900D02*
Y528899D01*
G01X565352Y536792D02*
X564966Y534700D01*
G01X565352Y542010D02*
Y536792D01*
G01X568699Y561700D02*
Y566699D01*
G01X595470Y573992D02*
Y572900D01*
G01X595988Y574510D02*
X595470Y573992D01*
G01X595988Y575390D02*
Y574510D01*
G01X595470Y575908D02*
X595988Y575390D01*
G01X595470Y579810D02*
Y575908D01*
G01X558659Y573992D02*
Y572900D01*
G01X559177Y574510D02*
X558659Y573992D01*
G01X559177Y575390D02*
Y574510D01*
G01X558659Y575908D02*
X559177Y575390D01*
G01X558659Y579810D02*
Y575908D01*
G01X588778Y572901D02*
X588777Y572900D01*
G01X588778Y574100D02*
Y572901D01*
G01X589298Y574620D02*
X588778Y574100D01*
G01X589298Y575480D02*
Y574620D01*
G01X588778Y576000D02*
X589298Y575480D01*
G01X588778Y579810D02*
Y576000D01*
G01X588777Y579810D02*
X588778D01*
G01X555313Y561700D02*
Y566699D01*
G01X548620Y561700D02*
Y566699D01*
G01X551967Y572901D02*
X551966Y572900D01*
G01X551967Y574100D02*
Y572901D01*
G01X552487Y574620D02*
X551967Y574100D01*
G01X552487Y575480D02*
Y574620D01*
G01X551967Y576000D02*
X552487Y575480D01*
G01X551967Y579810D02*
Y576000D01*
G01X551966Y579810D02*
X551967D01*
G01X588778Y535101D02*
X588777Y535100D01*
G01X588778Y536300D02*
Y535101D01*
G01X589298Y536820D02*
X588778Y536300D01*
G01X589298Y537680D02*
Y536820D01*
G01X588778Y538200D02*
X589298Y537680D01*
G01X588778Y542010D02*
Y538200D01*
G01X588777Y542010D02*
X588778D01*
G01X595470Y536192D02*
Y535100D01*
G01X595988Y536710D02*
X595470Y536192D01*
G01X595988Y537590D02*
Y536710D01*
G01X595470Y538108D02*
X595988Y537590D01*
G01X595470Y542010D02*
Y538108D01*
G01X572045Y579833D02*
X571345Y572500D01*
G01X572045Y579810D02*
Y579833D01*
G01X558659Y536192D02*
Y535100D01*
G01X559177Y536710D02*
X558659Y536192D01*
G01X559177Y537590D02*
Y536710D01*
G01X558659Y538108D02*
X559177Y537590D01*
G01X558659Y542010D02*
Y538108D01*
G01X562006Y561700D02*
Y566699D01*
G01X592124Y561700D02*
Y566699D01*
G01X551967Y542010D02*
X551966D01*
G01X551967Y538200D02*
Y542010D01*
G01X552487Y537680D02*
X551967Y538200D01*
G01X552487Y536820D02*
Y537680D01*
G01X551967Y536300D02*
X552487Y536820D01*
G01X551967Y535101D02*
Y536300D01*
G01X551966Y535100D02*
X551967Y535101D01*
G01X565352Y574592D02*
X564966Y572500D01*
G01X565352Y579810D02*
Y574592D01*
G01X585431Y561700D02*
Y566699D01*
G01X572045Y542033D02*
X571345Y534700D01*
G01X572045Y542010D02*
Y542033D01*
G01X558659Y611792D02*
Y610700D01*
G01X559177Y612310D02*
X558659Y611792D01*
G01X559177Y613190D02*
Y612310D01*
G01X558659Y613708D02*
X559177Y613190D01*
G01X558659Y617610D02*
Y613708D01*
G01X555313Y599500D02*
Y604499D01*
G01X565352Y612392D02*
X564966Y610300D01*
G01X565352Y617610D02*
Y612392D01*
G01X585431Y599500D02*
Y604499D01*
G01X551967Y617610D02*
X551966D01*
G01X551967Y613800D02*
Y617610D01*
G01X552487Y613280D02*
X551967Y613800D01*
G01X552487Y612420D02*
Y613280D01*
G01X551967Y611900D02*
X552487Y612420D01*
G01X551967Y610701D02*
Y611900D01*
G01X551966Y610700D02*
X551967Y610701D01*
G01X562006Y599500D02*
Y604499D01*
G01X595470Y611792D02*
Y610700D01*
G01X595988Y612310D02*
X595470Y611792D01*
G01X595988Y613190D02*
Y612310D01*
G01X595470Y613708D02*
X595988Y613190D01*
G01X595470Y617610D02*
Y613708D01*
G01X572045Y617633D02*
X571345Y610300D01*
G01X572045Y617610D02*
Y617633D01*
G01X568699Y599500D02*
Y604499D01*
G01X592124Y599500D02*
Y604499D01*
G01X588778Y610701D02*
X588777Y610700D01*
G01X588778Y611900D02*
Y610701D01*
G01X589298Y612420D02*
X588778Y611900D01*
G01X589298Y613280D02*
Y612420D01*
G01X588778Y613800D02*
X589298Y613280D01*
G01X588778Y617610D02*
Y613800D01*
G01X588777Y617610D02*
X588778D01*
G01X548620Y599500D02*
Y604499D01*
G01X608856Y528899D02*
Y523923D01*
G01X612203Y523900D02*
Y528899D01*
G01X608856Y579833D02*
Y579810D01*
G01D02*
Y574857D01*
G01X602163Y579833D02*
Y579810D01*
G01D02*
Y574857D01*
G01X612203Y579833D02*
Y579810D01*
G01D02*
Y574857D01*
G01X615549Y579833D02*
Y579810D01*
G01D02*
Y574857D01*
G01X608856Y542033D02*
Y542010D01*
G01X612203Y542033D02*
Y542010D01*
G01X615549Y542033D02*
Y542010D01*
G01X612203D02*
Y537057D01*
G01X608856Y542010D02*
Y537057D01*
G01X615549Y542010D02*
Y537057D01*
G01X602163Y617633D02*
Y617610D01*
G01X608856Y617633D02*
Y617610D01*
G01X612203Y617633D02*
Y617610D01*
G01X615549D02*
Y617633D01*
G01X612203Y617610D02*
Y612657D01*
G01X608856Y617610D02*
Y612657D01*
G01X602163Y617610D02*
Y612657D01*
G01X615549D02*
Y617610D01*
G01X783267Y3233D02*
X782567Y-4100D01*
G01X783269Y3233D02*
X783267D01*
G01X773228Y22923D02*
Y27899D01*
G01X773230Y22923D02*
X773228D01*
G01X779921Y-14877D02*
Y-9901D01*
G01X779923Y-14877D02*
X779921D01*
G01X776574Y-2008D02*
X776188Y-4100D01*
G01X776574Y3233D02*
Y-2008D01*
G01X776576Y3233D02*
X776574D01*
G01X779921Y22923D02*
Y27899D01*
G01X779923Y22923D02*
X779921D01*
G01X773228Y-14877D02*
Y-9901D01*
G01X773230Y-14877D02*
X773228D01*
G01X782949Y75500D02*
X782567Y71500D01*
G01X783267Y78833D02*
X782949Y75500D01*
G01X783269Y78833D02*
X783267D01*
G01X779921Y60723D02*
Y65699D01*
G01X779923Y60723D02*
X779921D01*
G01X773228D02*
Y65699D01*
G01X773230Y60723D02*
X773228D01*
G01X782643Y34500D02*
X782567Y33700D01*
G01X783267Y41033D02*
X782643Y34500D01*
G01X783269Y41033D02*
X783267D01*
G01X776336Y34500D02*
X776188Y33700D01*
G01X776574Y35792D02*
X776336Y34500D01*
G01X776574Y41033D02*
Y35792D01*
G01X776576Y41033D02*
X776574D01*
G01Y73592D02*
X776188Y71500D01*
G01X776574Y78833D02*
Y73592D01*
G01X776576Y78833D02*
X776574D01*
G01X773228Y523923D02*
Y528899D01*
G01X773230Y523900D02*
X773228Y523923D01*
G01X779921D02*
Y528899D01*
G01X779923Y523900D02*
X779921Y523923D01*
G01Y561723D02*
Y566699D01*
G01X779923Y561700D02*
X779921Y561723D01*
G01X773228D02*
Y566699D01*
G01X773230Y561700D02*
X773228Y561723D01*
G01X776574Y574592D02*
X776188Y572500D01*
G01X776574Y579810D02*
Y574592D01*
G01X776576Y579810D02*
X776574D01*
G01X783267Y542033D02*
X782567Y534700D01*
G01X783269Y542010D02*
X783267Y542033D01*
G01Y579833D02*
X782567Y572500D01*
G01X783269Y579810D02*
X783267Y579833D01*
G01X776574Y536792D02*
X776188Y534700D01*
G01X776574Y542010D02*
Y536792D01*
G01X776576Y542010D02*
X776574D01*
G01X783267Y617633D02*
X782567Y610300D01*
G01X783269Y617610D02*
X783267Y617633D01*
G01X773228Y599523D02*
Y604499D01*
G01X773230Y599500D02*
X773228Y599523D01*
G01X779921D02*
Y604499D01*
G01X779923Y599500D02*
X779921Y599523D01*
G01X776574Y612392D02*
X776188Y610300D01*
G01X776574Y617610D02*
Y612392D01*
G01X776576Y617610D02*
X776574D01*
G01X816732Y22923D02*
Y27899D01*
G01X816734Y22923D02*
X816732D01*
G01X820078Y3233D02*
X819378Y-4100D01*
G01X820080Y3233D02*
X820078D01*
G01X800000Y-3699D02*
X799999Y-3700D01*
G01X800000Y-2500D02*
Y-3699D01*
G01X800520Y-1980D02*
X800000Y-2500D01*
G01X800520Y-1120D02*
Y-1980D01*
G01X800000Y-600D02*
X800520Y-1120D01*
G01X800000Y3233D02*
Y-600D01*
G01X800002Y3233D02*
X800000D01*
G01X796653Y22923D02*
Y27899D01*
G01X796655Y22923D02*
X796653D01*
G01X803346Y-14877D02*
Y-9901D01*
G01X803348Y-14877D02*
X803346D01*
G01X833464Y22923D02*
Y27899D01*
G01X833466Y22923D02*
X833464D01*
G01Y-14877D02*
Y-9901D01*
G01X833466Y-14877D02*
X833464D01*
G01X803346Y22923D02*
Y27899D01*
G01X803348Y22923D02*
X803346D01*
G01X810039Y-14877D02*
Y-9901D01*
G01X810041Y-14877D02*
X810039D01*
G01X840157D02*
Y-9901D01*
G01X840159Y-14877D02*
X840157D01*
G01X816732D02*
Y-9901D01*
G01X816734Y-14877D02*
X816732D01*
G01X813385Y-2008D02*
X812999Y-4100D01*
G01X813385Y3233D02*
Y-2008D01*
G01X813387Y3233D02*
X813385D01*
G01X840157Y22923D02*
Y27899D01*
G01X840159Y22923D02*
X840157D01*
G01X810039D02*
Y27899D01*
G01X810041Y22923D02*
X810039D01*
G01X846850Y-14877D02*
Y-9901D01*
G01X846852Y-14877D02*
X846850D01*
G01X836811Y-3699D02*
X836810Y-3700D01*
G01X836811Y-2500D02*
Y-3699D01*
G01X837331Y-1980D02*
X836811Y-2500D01*
G01X837331Y-1120D02*
Y-1980D01*
G01X836811Y-600D02*
X837331Y-1120D01*
G01X836811Y3233D02*
Y-600D01*
G01X836813Y3233D02*
X836811D01*
G01X796653Y-14877D02*
Y-9901D01*
G01X796655Y-14877D02*
X796653D01*
G01X806692Y-2608D02*
Y-3700D01*
G01X807210Y-2090D02*
X806692Y-2608D01*
G01X807210Y-1210D02*
Y-2090D01*
G01X806692Y-692D02*
X807210Y-1210D01*
G01X806692Y3233D02*
Y-692D01*
G01X806694Y3233D02*
X806692D01*
G01X843503Y-2608D02*
Y-3700D01*
G01X844021Y-2090D02*
X843503Y-2608D01*
G01X844021Y-1210D02*
Y-2090D01*
G01X843506Y-695D02*
X844021Y-1210D01*
G01X843506Y3233D02*
Y-695D01*
G01X846850Y22923D02*
Y27899D01*
G01X846852Y22923D02*
X846850D01*
G01X800000Y34101D02*
X799999Y34100D01*
G01X800000Y35300D02*
Y34101D01*
G01X800520Y35820D02*
X800000Y35300D01*
G01X800520Y36680D02*
Y35820D01*
G01X800000Y37200D02*
X800520Y36680D01*
G01X800000Y41033D02*
Y37200D01*
G01X800002Y41033D02*
X800000D01*
G01X832500Y93721D02*
X833464Y92757D01*
G01X832500Y99250D02*
Y93721D01*
G01X836811Y71901D02*
X836810Y71900D01*
G01X836811Y73100D02*
Y71901D01*
G01X837331Y73620D02*
X836811Y73100D01*
G01X837331Y74480D02*
Y73620D01*
G01X836811Y75000D02*
X837331Y74480D01*
G01X836811Y78833D02*
Y75000D01*
G01X836813Y78833D02*
X836811D01*
G01X803346Y60723D02*
Y65699D01*
G01X803348Y60723D02*
X803346D01*
G01X846850D02*
Y65699D01*
G01X846852Y60723D02*
X846850D01*
G01X817374Y89718D02*
X819378Y87714D01*
G01X817374Y90874D02*
Y89718D01*
G01X818574Y92074D02*
X817374Y90874D01*
G01X818574Y93574D02*
Y92074D01*
G01X817915Y94233D02*
X818574Y93574D01*
G01X817915Y110644D02*
Y94233D01*
G01X816732Y60723D02*
Y65699D01*
G01X816734Y60723D02*
X816732D01*
G01X843503Y35192D02*
Y34100D01*
G01X844021Y35710D02*
X843503Y35192D01*
G01X844021Y36590D02*
Y35710D01*
G01X843503Y37108D02*
X844021Y36590D01*
G01X843504Y37109D02*
X843503Y37108D01*
G01X843504Y41033D02*
Y37109D01*
G01X843506Y41033D02*
X843504D01*
G01X813147Y34500D02*
X812999Y33700D01*
G01X813385Y35792D02*
X813147Y34500D01*
G01X813385Y41033D02*
Y35792D01*
G01X813387Y41033D02*
X813385D01*
G01X806692Y35192D02*
Y34100D01*
G01X807210Y35710D02*
X806692Y35192D01*
G01X807210Y36590D02*
Y35710D01*
G01X806692Y37108D02*
X807210Y36590D01*
G01X806692Y41033D02*
Y37108D01*
G01X806694Y41033D02*
X806692D01*
G01X800000Y71901D02*
X799999Y71900D01*
G01X800000Y73100D02*
Y71901D01*
G01X800520Y73620D02*
X800000Y73100D01*
G01X800520Y74480D02*
Y73620D01*
G01X800000Y75000D02*
X800520Y74480D01*
G01X800000Y78833D02*
Y75000D01*
G01X800002Y78833D02*
X800000D01*
G01X841011Y90206D02*
X843503Y87714D01*
G01X840042Y90206D02*
X841011D01*
G01X838292Y91956D02*
X840042Y90206D01*
G01X838292Y96492D02*
Y91956D01*
G01X840157Y60723D02*
Y65699D01*
G01X840159Y60723D02*
X840157D01*
G01X813385Y73592D02*
X812999Y71500D01*
G01X813385Y78833D02*
Y73592D01*
G01X813387Y78833D02*
X813385D01*
G01X809800Y92996D02*
X810039Y92757D01*
G01X809800Y97175D02*
Y92996D01*
G01X806692Y72992D02*
Y71900D01*
G01X807210Y73510D02*
X806692Y72992D01*
G01X807210Y74390D02*
Y73510D01*
G01X806692Y74908D02*
X807210Y74390D01*
G01X806692Y78833D02*
Y74908D01*
G01X806694Y78833D02*
X806692D01*
G01X819760Y75500D02*
X819378Y71500D01*
G01X820078Y78833D02*
X819760Y75500D01*
G01X820080Y78833D02*
X820078D01*
G01X815192Y94297D02*
Y111688D01*
G01X816732Y92757D02*
X815192Y94297D01*
G01X843503Y72992D02*
Y71900D01*
G01X844021Y73510D02*
X843503Y72992D01*
G01X844021Y74390D02*
Y73510D01*
G01X843506Y74905D02*
X844021Y74390D01*
G01X843506Y78833D02*
Y74905D01*
G01X840157Y92757D02*
X845020Y97620D01*
G01X819454Y34500D02*
X819378Y33700D01*
G01X820078Y41033D02*
X819454Y34500D01*
G01X820080Y41033D02*
X820078D01*
G01X796653Y60723D02*
Y65699D01*
G01X796655Y60723D02*
X796653D01*
G01X836811Y34101D02*
X836810Y34100D01*
G01X836811Y35300D02*
Y34101D01*
G01X837331Y35820D02*
X836811Y35300D01*
G01X837331Y36680D02*
Y35820D01*
G01X836811Y37200D02*
X837331Y36680D01*
G01X836811Y41033D02*
Y37200D01*
G01X836813Y41033D02*
X836811D01*
G01X810039Y60723D02*
Y65699D01*
G01X810041Y60723D02*
X810039D01*
G01X812500Y93800D02*
Y112954D01*
G01X811240Y90720D02*
X812500Y93800D01*
G01X811240Y89559D02*
Y90720D01*
G01X813085Y87714D02*
X811240Y89559D01*
G01X835500Y91900D02*
Y98200D01*
G01X834774Y91174D02*
X835500Y91900D01*
G01X834774Y89750D02*
Y91174D01*
G01X836810Y87714D02*
X834774Y89750D01*
G01X833464Y60723D02*
Y65699D01*
G01X833466Y60723D02*
X833464D01*
G01X834439Y101189D02*
X832500Y99250D01*
G01X834439Y102109D02*
Y101189D01*
G01X831686Y104862D02*
X834439Y102109D01*
G01X831686Y105782D02*
Y104862D01*
G01X832640Y106736D02*
X831686Y105782D01*
G01X833560Y106736D02*
X832640D01*
G01X836313Y103983D02*
X833560Y106736D01*
G01X837233Y103983D02*
X836313D01*
G01X838187Y104937D02*
X837233Y103983D01*
G01X838187Y105857D02*
Y104937D01*
G01X835434Y108610D02*
X838187Y105857D01*
G01X835434Y109530D02*
Y108610D01*
G01X836388Y110484D02*
X835434Y109530D01*
G01X837308Y110484D02*
X836388D01*
G01X840061Y107731D02*
X837308Y110484D01*
G01X840981Y107731D02*
X840061D01*
G01X841935Y108685D02*
X840981Y107731D01*
G01X841935Y109605D02*
Y108685D01*
G01X839182Y112358D02*
X841935Y109605D01*
G01X839182Y113278D02*
Y112358D01*
G01X840136Y114232D02*
X839182Y113278D01*
G01X841056Y114232D02*
X840136D01*
G01X843809Y111479D02*
X841056Y114232D01*
G01X844729Y111479D02*
X843809D01*
G01X847304Y114054D02*
X844729Y111479D01*
G01X847304Y122435D02*
Y114054D01*
G01X846654Y123085D02*
X847304Y122435D01*
G01X844046Y123085D02*
X846654D01*
G01X843396Y123735D02*
X844046Y123085D01*
G01X843396Y125085D02*
Y123735D01*
G01X844046Y125735D02*
X843396Y125085D01*
G01X846654Y125735D02*
X844046D01*
G01X847304Y126385D02*
X846654Y125735D01*
G01X847304Y127735D02*
Y126385D01*
G01X846654Y128385D02*
X847304Y127735D01*
G01X845450Y128385D02*
X846654D01*
G01X844800Y129035D02*
X845450Y128385D01*
G01X844800Y130385D02*
Y129035D01*
G01X845450Y131035D02*
X844800Y130385D01*
G01X846654Y131035D02*
X845450D01*
G01X847304Y131685D02*
X846654Y131035D01*
G01X847304Y138000D02*
Y131685D01*
G01Y156571D02*
Y138000D01*
G01X827147Y119876D02*
X817915Y110644D01*
G01X827147Y122555D02*
Y119876D01*
G01X828200Y123608D02*
X827147Y122555D01*
G01X828200Y125452D02*
Y123608D01*
G01X827147Y126505D02*
X828200Y125452D01*
G01X827147Y132687D02*
Y126505D01*
G01X831951Y137491D02*
X827147Y132687D01*
G01X831951Y155952D02*
Y137491D01*
G01X903855Y227856D02*
X831951Y155952D01*
G01X852863Y111063D02*
X838292Y96492D01*
G01X809150Y97825D02*
X809800Y97175D01*
G01X807350Y97825D02*
X809150D01*
G01X806700Y98475D02*
X807350Y97825D01*
G01X806700Y99825D02*
Y98475D01*
G01X807350Y100475D02*
X806700Y99825D01*
G01X809150Y100475D02*
X807350D01*
G01X809800Y101125D02*
X809150Y100475D01*
G01X809800Y114800D02*
Y101125D01*
G01X818763Y123763D02*
X809800Y114800D01*
G01X818763Y154038D02*
Y123763D01*
G01X900431Y235706D02*
X818763Y154038D01*
G01X829219Y150226D02*
Y156978D01*
G01X828569Y149576D02*
X829219Y150226D01*
G01X826650Y149576D02*
X828569D01*
G01X826000Y148926D02*
X826650Y149576D01*
G01X826000Y147576D02*
Y148926D01*
G01X826650Y146926D02*
X826000Y147576D01*
G01X828569Y146926D02*
X826650D01*
G01X829219Y146276D02*
X828569Y146926D01*
G01X829219Y144926D02*
Y146276D01*
G01X828569Y144276D02*
X829219Y144926D01*
G01X824924Y144276D02*
X828569D01*
G01X824274Y143626D02*
X824924Y144276D01*
G01X824274Y142276D02*
Y143626D01*
G01X824924Y141626D02*
X824274Y142276D01*
G01X828569Y141626D02*
X824924D01*
G01X829219Y140976D02*
X828569Y141626D01*
G01X829219Y138623D02*
Y140976D01*
G01X824320Y133724D02*
X829219Y138623D01*
G01X824320Y120816D02*
Y133724D01*
G01X815192Y111688D02*
X824320Y120816D01*
G01X847814Y100414D02*
X861026Y113626D01*
G01X847814Y99494D02*
Y100414D01*
G01X848768Y98540D02*
X847814Y99494D01*
G01X845940Y97620D02*
X848768Y94792D01*
G01X845020Y97620D02*
X845940D01*
G01X821400Y152917D02*
X841741Y173258D01*
G01X821400Y121854D02*
Y152917D01*
G01X812500Y112954D02*
X821400Y121854D01*
G01X835500Y98200D02*
X850036Y112736D01*
G01X907733Y217000D02*
X847304Y156571D01*
G01X832370Y160129D02*
X902800Y230559D01*
G01X829219Y156978D02*
X832370Y160129D01*
G01X841741Y173258D02*
X901639Y233156D01*
G01X836600Y453990D02*
Y506000D01*
G01X837290Y453300D02*
X836600Y453990D01*
G01X838600Y453300D02*
X837290D01*
G01X839290Y453990D02*
X838600Y453300D01*
G01X839290Y463610D02*
Y453990D01*
G01X839980Y464300D02*
X839290Y463610D01*
G01X841290Y464300D02*
X839980D01*
G01X841980Y463610D02*
X841290Y464300D01*
G01X841980Y448278D02*
Y463610D01*
G01X911498Y378760D02*
X841980Y448278D01*
G01X817300Y450687D02*
Y498999D01*
G01X907487Y360500D02*
X817300Y450687D01*
G01X844637Y449428D02*
Y483810D01*
G01X911222Y382843D02*
X844637Y449428D01*
G01X847332Y450540D02*
Y498710D01*
G01X912479Y385393D02*
X847332Y450540D01*
G01X814600Y449629D02*
Y497800D01*
G01X906920Y357309D02*
X814600Y449629D01*
G01X820000Y451745D02*
Y500600D01*
G01X908585Y363160D02*
X820000Y451745D01*
G01X822797Y464559D02*
X823447Y465209D01*
G01X822797Y463209D02*
Y464559D01*
G01X823447Y462559D02*
X822797Y463209D01*
G01X825050Y462559D02*
X823447D01*
G01X825700Y461909D02*
X825050Y462559D01*
G01X825700Y460559D02*
Y461909D01*
G01X825050Y459909D02*
X825700Y460559D01*
G01X823447Y459909D02*
X825050D01*
G01X822697Y459159D02*
X823447Y459909D01*
G01X822697Y452806D02*
Y459159D01*
G01X909003Y366500D02*
X822697Y452806D01*
G01X833464Y512936D02*
Y518157D01*
G01X835600Y510800D02*
X833464Y512936D01*
G01X835600Y507000D02*
Y510800D01*
G01X836600Y506000D02*
X835600Y507000D01*
G01X814523Y511676D02*
X813085Y513114D01*
G01X814523Y501776D02*
Y511676D01*
G01X817300Y498999D02*
X814523Y501776D01*
G01X810039Y523923D02*
Y528899D01*
G01X810041Y523900D02*
X810039Y523923D01*
G01X846850D02*
Y528899D01*
G01X846852Y523900D02*
X846850Y523923D01*
G01X833464D02*
Y528899D01*
G01X833466Y523900D02*
X833464Y523923D01*
G01X838300Y511624D02*
X836810Y513114D01*
G01X838300Y508000D02*
Y511624D01*
G01X839257Y507043D02*
X838300Y508000D01*
G01X839257Y467647D02*
Y507043D01*
G01X839947Y466957D02*
X839257Y467647D01*
G01X841257Y466957D02*
X839947D01*
G01X841947Y467647D02*
X841257Y466957D01*
G01X841947Y483610D02*
Y467647D01*
G01X842737Y484400D02*
X841947Y483610D01*
G01X844047Y484400D02*
X842737D01*
G01X844637Y483810D02*
X844047Y484400D01*
G01X840157Y513169D02*
Y518157D01*
G01X841952Y511374D02*
X840157Y513169D01*
G01X841952Y487690D02*
Y511374D01*
G01X842642Y487000D02*
X841952Y487690D01*
G01X843952Y487000D02*
X842642D01*
G01X844642Y487690D02*
X843952Y487000D01*
G01X844642Y498710D02*
Y487690D01*
G01X845332Y499400D02*
X844642Y498710D01*
G01X846642Y499400D02*
X845332D01*
G01X847332Y498710D02*
X846642Y499400D01*
G01X803346Y523923D02*
Y528899D01*
G01X803348Y523900D02*
X803346Y523923D01*
G01X810039Y513287D02*
Y518157D01*
G01X811874Y511452D02*
X810039Y513287D01*
G01X811874Y500526D02*
Y511452D01*
G01X814600Y497800D02*
X811874Y500526D01*
G01X816732Y512594D02*
Y518157D01*
G01X818654Y510672D02*
X816732Y512594D01*
G01X818654Y508854D02*
Y510672D01*
G01X817100Y507300D02*
X818654Y508854D01*
G01X817100Y503500D02*
Y507300D01*
G01X820000Y500600D02*
X817100Y503500D01*
G01X840157Y523923D02*
Y528899D01*
G01X840159Y523900D02*
X840157Y523923D01*
G01X844620Y511997D02*
X843503Y513114D01*
G01X844620Y504280D02*
Y511997D01*
G01X846522Y502378D02*
X844620Y504280D01*
G01X854350Y502378D02*
X846522D01*
G01X796653Y523923D02*
Y528899D01*
G01X796655Y523900D02*
X796653Y523923D01*
G01X820686Y513114D02*
X819378D01*
G01X821374Y512426D02*
X820686Y513114D01*
G01X821374Y507574D02*
Y512426D01*
G01X819900Y506100D02*
X821374Y507574D01*
G01X819900Y505001D02*
Y506100D01*
G01X822697Y502204D02*
X819900Y505001D01*
G01X822697Y468609D02*
Y502204D01*
G01X823447Y467859D02*
X822697Y468609D01*
G01X825050Y467859D02*
X823447D01*
G01X825700Y467209D02*
X825050Y467859D01*
G01X825700Y465859D02*
Y467209D01*
G01X825050Y465209D02*
X825700Y465859D01*
G01X823447Y465209D02*
X825050D01*
G01X816732Y523923D02*
Y528899D01*
G01X816734Y523900D02*
X816732Y523923D01*
G01X836811Y542010D02*
X836813D01*
G01X836811Y538200D02*
Y542010D01*
G01X837331Y537680D02*
X836811Y538200D01*
G01X837331Y536820D02*
Y537680D01*
G01X836811Y536300D02*
X837331Y536820D01*
G01X836811Y535101D02*
Y536300D01*
G01X836810Y535100D02*
X836811Y535101D01*
G01X840157Y561723D02*
Y566699D01*
G01X840159Y561700D02*
X840157Y561723D01*
G01X800000Y572901D02*
X799999Y572900D01*
G01X800000Y574100D02*
Y572901D01*
G01X800520Y574620D02*
X800000Y574100D01*
G01X800520Y575480D02*
Y574620D01*
G01X800000Y576000D02*
X800520Y575480D01*
G01X800000Y579810D02*
Y576000D01*
G01X800002Y579810D02*
X800000D01*
G01Y535101D02*
X799999Y535100D01*
G01X800000Y536300D02*
Y535101D01*
G01X800520Y536820D02*
X800000Y536300D01*
G01X800520Y537680D02*
Y536820D01*
G01X800000Y538200D02*
X800520Y537680D01*
G01X800000Y542010D02*
Y538200D01*
G01X800002Y542010D02*
X800000D01*
G01X806692Y573992D02*
Y572900D01*
G01X807210Y574510D02*
X806692Y573992D01*
G01X807210Y575390D02*
Y574510D01*
G01X806692Y575908D02*
X807210Y575390D01*
G01X806692Y579810D02*
Y575908D01*
G01X806694Y579810D02*
X806692D01*
G01X810039Y561723D02*
Y566699D01*
G01X810041Y561700D02*
X810039Y561723D01*
G01X843503Y573992D02*
Y572900D01*
G01X844021Y574510D02*
X843503Y573992D01*
G01X844021Y575390D02*
Y574510D01*
G01X843503Y575908D02*
X844021Y575390D01*
G01X843503Y579810D02*
Y575908D01*
G01X843506Y579810D02*
X843503D01*
G01Y536192D02*
Y535100D01*
G01X844021Y536710D02*
X843503Y536192D01*
G01X844021Y537590D02*
Y536710D01*
G01X843503Y538108D02*
X844021Y537590D01*
G01X843503Y542010D02*
Y538108D01*
G01X843506Y542010D02*
X843503D01*
G01X813385D02*
X813387D01*
G01X813385Y536792D02*
Y542010D01*
G01X812999Y534700D02*
X813385Y536792D01*
G01X820078Y542033D02*
X819378Y534700D01*
G01X820080Y542010D02*
X820078Y542033D01*
G01X836811Y572901D02*
X836810Y572900D01*
G01X836811Y574100D02*
Y572901D01*
G01X837331Y574620D02*
X836811Y574100D01*
G01X837331Y575480D02*
Y574620D01*
G01X836811Y576000D02*
X837331Y575480D01*
G01X836811Y579810D02*
Y576000D01*
G01X836813Y579810D02*
X836811D01*
G01X803346Y561723D02*
Y566699D01*
G01X803348Y561700D02*
X803346Y561723D01*
G01X816732D02*
Y566699D01*
G01X816734Y561700D02*
X816732Y561723D01*
G01X813385Y574592D02*
X812999Y572500D01*
G01X813385Y579810D02*
Y574592D01*
G01X813387Y579810D02*
X813385D01*
G01X796653Y561723D02*
Y566699D01*
G01X796655Y561700D02*
X796653Y561723D01*
G01X833464D02*
Y566699D01*
G01X833466Y561700D02*
X833464Y561723D01*
G01X846850D02*
Y566699D01*
G01X846852Y561700D02*
X846850Y561723D01*
G01X820078Y579833D02*
X819378Y572500D01*
G01X820080Y579810D02*
X820078Y579833D01*
G01X806692Y536192D02*
Y535100D01*
G01X807210Y536710D02*
X806692Y536192D01*
G01X807210Y537590D02*
Y536710D01*
G01X806692Y538108D02*
X807210Y537590D01*
G01X806692Y542010D02*
Y538108D01*
G01X806694Y542010D02*
X806692D01*
G01X840157Y599523D02*
Y604499D01*
G01X840159Y599500D02*
X840157Y599523D01*
G01X833464D02*
Y604499D01*
G01X833466Y599500D02*
X833464Y599523D01*
G01X843503Y611792D02*
Y610700D01*
G01X844021Y612310D02*
X843503Y611792D01*
G01X844021Y613190D02*
Y612310D01*
G01X843503Y613708D02*
X844021Y613190D01*
G01X843503Y617610D02*
Y613708D01*
G01X843506Y617610D02*
X843503D01*
G01X800000Y610701D02*
X799999Y610700D01*
G01X800000Y611900D02*
Y610701D01*
G01X800520Y612420D02*
X800000Y611900D01*
G01X800520Y613280D02*
Y612420D01*
G01X800000Y613800D02*
X800520Y613280D01*
G01X800000Y617610D02*
Y613800D01*
G01X800002Y617610D02*
X800000D01*
G01X836811Y610701D02*
X836810Y610700D01*
G01X836811Y611900D02*
Y610701D01*
G01X837331Y612420D02*
X836811Y611900D01*
G01X837331Y613280D02*
Y612420D01*
G01X836811Y613800D02*
X837331Y613280D01*
G01X836811Y617610D02*
Y613800D01*
G01X836813Y617610D02*
X836811D01*
G01X806692Y611792D02*
Y610700D01*
G01X807210Y612310D02*
X806692Y611792D01*
G01X807210Y613190D02*
Y612310D01*
G01X806692Y613708D02*
X807210Y613190D01*
G01X806692Y617610D02*
Y613708D01*
G01X806694Y617610D02*
X806692D01*
G01X810039Y599523D02*
Y604499D01*
G01X810041Y599500D02*
X810039Y599523D01*
G01X813385Y612392D02*
X812999Y610300D01*
G01X813385Y617610D02*
Y612392D01*
G01X813387Y617610D02*
X813385D01*
G01X796653Y599523D02*
Y604499D01*
G01X796655Y599500D02*
X796653Y599523D01*
G01X816732D02*
Y604499D01*
G01X816734Y599500D02*
X816732Y599523D01*
G01X846850D02*
Y604499D01*
G01X846852Y599500D02*
X846850Y599523D01*
G01X803346D02*
Y604499D01*
G01X803348Y599500D02*
X803346Y599523D01*
G01X820078Y617633D02*
X819378Y610300D01*
G01X820080Y617610D02*
X820078Y617633D01*
G01X853543Y22923D02*
Y27899D01*
G01X853545Y22923D02*
X853543D01*
G01X907086Y-14877D02*
Y-9901D01*
G01X907088Y-14877D02*
X907086D01*
G01X876968Y22923D02*
Y27899D01*
G01X876970Y22923D02*
X876968D01*
G01Y-14877D02*
Y-9901D01*
G01X876970Y-14877D02*
X876968D01*
G01X883661D02*
Y-9901D01*
G01X883663Y-14877D02*
X883661D01*
G01X907086Y22923D02*
Y27899D01*
G01X907088Y22923D02*
X907086D01*
G01X870275D02*
Y27899D01*
G01X870277Y22923D02*
X870275D01*
G01X890354D02*
Y27899D01*
G01X890356Y22923D02*
X890354D01*
G01X856889Y3233D02*
X856189Y-4100D01*
G01X856891Y3233D02*
X856889D01*
G01X850196Y-2008D02*
X849810Y-4100D01*
G01X850196Y3233D02*
Y-2008D01*
G01X850198Y3233D02*
X850196D01*
G01X853543Y-14877D02*
Y-9901D01*
G01X853545Y-14877D02*
X853543D01*
G01X873622Y-3699D02*
X873621Y-3700D01*
G01X873622Y-2500D02*
Y-3699D01*
G01X874142Y-1980D02*
X873622Y-2500D01*
G01X874142Y-1120D02*
Y-1980D01*
G01X873622Y-600D02*
X874142Y-1120D01*
G01X873622Y3233D02*
Y-600D01*
G01X873624Y3233D02*
X873622D01*
G01X883661Y22923D02*
Y27899D01*
G01X883663Y22923D02*
X883661D01*
G01X887007Y-2008D02*
X886621Y-4100D01*
G01X887007Y3233D02*
Y-2008D01*
G01X887009Y3233D02*
X887007D01*
G01X890354Y-14877D02*
Y-9901D01*
G01X890356Y-14877D02*
X890354D01*
G01X870275D02*
Y-9901D01*
G01X870277Y-14877D02*
X870275D01*
G01X880314Y-2608D02*
Y-3700D01*
G01X880832Y-2090D02*
X880314Y-2608D01*
G01X880832Y-1210D02*
Y-2090D01*
G01X880317Y-695D02*
X880832Y-1210D01*
G01X880317Y3233D02*
Y-695D01*
G01X893700Y3233D02*
X893000Y-4100D01*
G01X893702Y3233D02*
X893700D01*
G01X870275Y60723D02*
Y65699D01*
G01X870277Y60723D02*
X870275D01*
G01X873622Y71901D02*
X873621Y71900D01*
G01X873622Y73100D02*
Y71901D01*
G01X874142Y73620D02*
X873622Y73100D01*
G01X874142Y74480D02*
Y73620D01*
G01X873622Y75000D02*
X874142Y74480D01*
G01X873622Y78833D02*
Y75000D01*
G01X873624Y78833D02*
X873622D01*
G01X856265Y34500D02*
X856189Y33700D01*
G01X856889Y41033D02*
X856265Y34500D01*
G01X856891Y41033D02*
X856889D01*
G01X856571Y75500D02*
X856189Y71500D01*
G01X856889Y78833D02*
X856571Y75500D01*
G01X856891Y78833D02*
X856889D01*
G01X893076Y34500D02*
X893000Y33700D01*
G01X893700Y41033D02*
X893076Y34500D01*
G01X893702Y41033D02*
X893700D01*
G01X880317Y71903D02*
X880314Y71900D01*
G01X880317Y78833D02*
Y71903D01*
G01X850196Y73592D02*
X849810Y71500D01*
G01X850196Y78833D02*
Y73592D01*
G01X850198Y78833D02*
X850196D01*
G01X853543Y60723D02*
Y65699D01*
G01X853545Y60723D02*
X853543D01*
G01X887007Y73592D02*
X886621Y71500D01*
G01X887007Y78833D02*
Y73592D01*
G01X887009Y78833D02*
X887007D01*
G01X890354Y60723D02*
Y65699D01*
G01X890356Y60723D02*
X890354D01*
G01X883661D02*
Y65699D01*
G01X883663Y60723D02*
X883661D01*
G01X873622Y34101D02*
X873621Y34100D01*
G01X873622Y35300D02*
Y34101D01*
G01X874142Y35820D02*
X873622Y35300D01*
G01X874142Y36680D02*
Y35820D01*
G01X873622Y37200D02*
X874142Y36680D01*
G01X873622Y41033D02*
Y37200D01*
G01X873624Y41033D02*
X873622D01*
G01X880314Y35192D02*
Y34100D01*
G01X880832Y35710D02*
X880314Y35192D01*
G01X880832Y36590D02*
Y35710D01*
G01X880317Y37105D02*
X880832Y36590D01*
G01X880317Y41033D02*
Y37105D01*
G01X886769Y34500D02*
X886621Y33700D01*
G01X887007Y35792D02*
X886769Y34500D01*
G01X887007Y41033D02*
Y35792D01*
G01X887009Y41033D02*
X887007D01*
G01X876968Y60723D02*
Y65699D01*
G01X876970Y60723D02*
X876968D01*
G01X849958Y34500D02*
X849810Y33700D01*
G01X850196Y35792D02*
X849958Y34500D01*
G01X850196Y41033D02*
Y35792D01*
G01X850198Y41033D02*
X850196D01*
G01X907086Y60723D02*
Y65699D01*
G01X907088Y60723D02*
X907086D01*
G01X893382Y75500D02*
X893000Y71500D01*
G01X893700Y78833D02*
X893382Y75500D01*
G01X893702Y78833D02*
X893700D01*
G01X888810Y150641D02*
Y166834D01*
G01X889500Y149951D02*
X888810Y150641D01*
G01X889500Y135000D02*
Y149951D01*
G01Y132691D02*
Y135000D01*
G01X888850Y132041D02*
X889500Y132691D01*
G01X887450Y132041D02*
X888850D01*
G01X886800Y131391D02*
X887450Y132041D01*
G01X886800Y130041D02*
Y131391D01*
G01X887450Y129391D02*
X886800Y130041D01*
G01X888850Y129391D02*
X887450D01*
G01X889500Y128741D02*
X888850Y129391D01*
G01X889500Y127391D02*
Y128741D01*
G01X888850Y126741D02*
X889500Y127391D01*
G01X887450Y126741D02*
X888850D01*
G01X886800Y126091D02*
X887450Y126741D01*
G01X886800Y124741D02*
Y126091D01*
G01X887450Y124091D02*
X886800Y124741D01*
G01X888850Y124091D02*
X887450D01*
G01X889500Y123441D02*
X888850Y124091D01*
G01X889500Y122091D02*
Y123441D01*
G01X888850Y121441D02*
X889500Y122091D01*
G01X887450Y121441D02*
X888850D01*
G01X886800Y120791D02*
X887450Y121441D01*
G01X886800Y119441D02*
Y120791D01*
G01X887450Y118791D02*
X886800Y119441D01*
G01X888850Y118791D02*
X887450D01*
G01X889500Y118141D02*
X888850Y118791D01*
G01X889500Y113181D02*
Y118141D01*
G01X890354Y112327D02*
X889500Y113181D01*
G01X908757Y114100D02*
Y140500D01*
G01X909300Y113557D02*
X908757Y114100D01*
G01X909300Y111843D02*
Y113557D01*
G01X908600Y111143D02*
X909300Y111843D01*
G01X908600Y109116D02*
Y111143D01*
G01X910432Y107284D02*
X908600Y109116D01*
G01X909447Y147550D02*
X910757D01*
G01X908757Y146860D02*
X909447Y147550D01*
G01X908757Y140500D02*
Y146860D01*
G01X894700Y155978D02*
X895350Y156628D01*
G01X893850Y155978D02*
X894700D01*
G01X893200Y155328D02*
X893850Y155978D01*
G01X893200Y153978D02*
Y155328D01*
G01X893850Y153328D02*
X893200Y153978D01*
G01X894700Y153328D02*
X893850D01*
G01X895350Y152678D02*
X894700Y153328D01*
G01X895350Y151251D02*
Y152678D01*
G01X892200Y148101D02*
X895350Y151251D01*
G01X892200Y142000D02*
Y148101D01*
G01Y111500D02*
Y142000D01*
G01X889374Y108674D02*
X892200Y111500D01*
G01X889374Y107584D02*
Y108674D01*
G01X890024Y106934D02*
X889374Y107584D01*
G01X893000Y106934D02*
X890024D01*
G01X852863Y131633D02*
Y111063D01*
G01X853513Y132283D02*
X852863Y131633D01*
G01X854903Y132283D02*
X853513D01*
G01X855553Y131633D02*
X854903Y132283D01*
G01X855553Y118266D02*
Y131633D01*
G01X856053Y117766D02*
X855553Y118266D01*
G01X857788Y117766D02*
X856053D01*
G01X858337Y118315D02*
X857788Y117766D01*
G01X858337Y125500D02*
Y118315D01*
G01Y160088D02*
Y125500D01*
G01X881100Y114888D02*
Y140500D01*
G01X883661Y112327D02*
X881100Y114888D01*
G01X882550Y156012D02*
X883200Y156662D01*
G01X881050Y156012D02*
X882550D01*
G01X880400Y155362D02*
X881050Y156012D01*
G01X880400Y154012D02*
Y155362D01*
G01X881050Y153362D02*
X880400Y154012D01*
G01X882550Y153362D02*
X881050D01*
G01X883200Y152712D02*
X882550Y153362D01*
G01X883200Y149850D02*
Y152712D01*
G01X881100Y147750D02*
X883200Y149850D01*
G01X881100Y140500D02*
Y147750D01*
G01X906100Y126896D02*
Y130000D01*
G01X905410Y126206D02*
X906100Y126896D01*
G01X905390Y126206D02*
X905410D01*
G01X904700Y125516D02*
X905390Y126206D01*
G01X904700Y124206D02*
Y125516D01*
G01X905390Y123516D02*
X904700Y124206D01*
G01X905410Y123516D02*
X905390D01*
G01X906100Y122826D02*
X905410Y123516D01*
G01X906100Y121516D02*
Y122826D01*
G01X905410Y120826D02*
X906100Y121516D01*
G01X905390Y120826D02*
X905410D01*
G01X904700Y120136D02*
X905390Y120826D01*
G01X904700Y118826D02*
Y120136D01*
G01X905390Y118136D02*
X904700Y118826D01*
G01X905410Y118136D02*
X905390D01*
G01X906100Y117446D02*
X905410Y118136D01*
G01X906100Y113313D02*
Y117446D01*
G01X907086Y112327D02*
X906100Y113313D01*
G01X909290Y155100D02*
X910980D01*
G01X908790Y155600D02*
X909290Y155100D01*
G01X908790Y163350D02*
Y155600D01*
G01X906100Y130000D02*
Y163350D01*
G01X861026Y141000D02*
Y159018D01*
G01Y113626D02*
Y141000D01*
G01X849688Y98540D02*
X848768D01*
G01X862464Y111316D02*
X849688Y98540D01*
G01X863384Y111316D02*
X862464D01*
G01X864338Y110362D02*
X863384Y111316D01*
G01X864338Y109442D02*
Y110362D01*
G01X849688Y94792D02*
X864338Y109442D01*
G01X848768Y94792D02*
X849688D01*
G01X883800Y116050D02*
Y134000D01*
G01X885486Y114364D02*
X883800Y116050D01*
G01X885486Y111486D02*
Y114364D01*
G01X884800Y110800D02*
X885486Y111486D01*
G01X884800Y109159D02*
Y110800D01*
G01X886675Y107284D02*
X884800Y109159D01*
G01X886707Y107284D02*
X886675D01*
G01X886100Y140100D02*
Y167700D01*
G01X883800Y137800D02*
X886100Y140100D01*
G01X883800Y134000D02*
Y137800D01*
G01X850036Y112736D02*
Y128500D01*
G01Y155545D02*
X908991Y214500D01*
G01X850036Y152832D02*
Y155545D01*
G01X850686Y152182D02*
X850036Y152832D01*
G01X854686Y152182D02*
X850686D01*
G01X855336Y151532D02*
X854686Y152182D01*
G01X855336Y139259D02*
Y151532D01*
G01X854686Y138609D02*
X855336Y139259D01*
G01X853336Y138609D02*
X854686D01*
G01X852686Y139259D02*
X853336Y138609D01*
G01X852686Y148882D02*
Y139259D01*
G01X852036Y149532D02*
X852686Y148882D01*
G01X850686Y149532D02*
X852036D01*
G01X850036Y148882D02*
X850686Y149532D01*
G01X850036Y128500D02*
Y148882D01*
G01X908237Y186261D02*
X908238D01*
G01X888810Y166834D02*
X908237Y186261D01*
G01X895350Y169757D02*
X910046Y184453D01*
G01X895350Y161928D02*
Y169757D01*
G01X894700Y161278D02*
X895350Y161928D01*
G01X892250Y161278D02*
X894700D01*
G01X891600Y160628D02*
X892250Y161278D01*
G01X891600Y159278D02*
Y160628D01*
G01X892250Y158628D02*
X891600Y159278D01*
G01X894700Y158628D02*
X892250D01*
G01X895350Y157978D02*
X894700Y158628D01*
G01X895350Y156628D02*
Y157978D01*
G01X910608Y212359D02*
X858337Y160088D01*
G01X904624Y189873D02*
X904626D01*
G01X883200Y168449D02*
X904624Y189873D01*
G01X883200Y161962D02*
Y168449D01*
G01X882550Y161312D02*
X883200Y161962D01*
G01X881050Y161312D02*
X882550D01*
G01X880400Y160662D02*
X881050Y161312D01*
G01X880400Y159312D02*
Y160662D01*
G01X881050Y158662D02*
X880400Y159312D01*
G01X882550Y158662D02*
X881050D01*
G01X883200Y158012D02*
X882550Y158662D01*
G01X883200Y156662D02*
Y158012D01*
G01X908290Y163850D02*
X908790Y163350D01*
G01X906600Y163850D02*
X908290D01*
G01X906100Y163350D02*
X906600Y163850D01*
G01X861026Y159018D02*
X912552Y210544D01*
G01X886100Y167700D02*
X906400Y188000D01*
G01X912391Y227856D02*
X903855D01*
G01X913700Y235706D02*
X900431D01*
G01X902800Y230559D02*
X912600D01*
G01X901639Y233156D02*
X913644D01*
G01X915128Y360500D02*
X907487D01*
G01X915103Y357309D02*
X906920D01*
G01X915213Y363160D02*
X908585D01*
G01X913757Y387943D02*
X850000Y451700D01*
G01X915308Y366500D02*
X909003D01*
G01X883700Y463700D02*
X885779Y465779D01*
G01X883700Y462100D02*
Y463700D01*
G01X885779Y460021D02*
X883700Y462100D01*
G01X885779Y458579D02*
Y460021D01*
G01X883700Y456500D02*
X885779Y458579D01*
G01X883700Y454900D02*
Y456500D01*
G01X885600Y453000D02*
X883700Y454900D01*
G01X885600Y450300D02*
Y453000D01*
G01X883700Y448400D02*
X885600Y450300D01*
G01X883700Y446111D02*
Y448400D01*
G01X889097Y433081D02*
X883700Y446111D01*
G01X917279Y404899D02*
X889097Y433081D01*
G01X903203Y464649D02*
Y473250D01*
G01X905653Y462199D02*
X903203Y464649D01*
G01X906837Y462199D02*
X905653D01*
G01X907666Y461370D02*
X906837Y462199D01*
G01X907666Y455282D02*
Y461370D01*
G01X907036Y454652D02*
X907666Y455282D01*
G01X906363Y454652D02*
X907036D01*
G01X905812Y454101D02*
X906363Y454652D01*
G01X905812Y452462D02*
Y454101D01*
G01X906312Y451962D02*
X905812Y452462D01*
G01X907036Y451962D02*
X906312D01*
G01X907536Y451462D02*
X907036Y451962D01*
G01X907536Y448286D02*
Y451462D01*
G01X906846Y447596D02*
X907536Y448286D01*
G01X905486Y447596D02*
X906846D01*
G01X904783Y446893D02*
X905486Y447596D01*
G01X904783Y445583D02*
Y446893D01*
G01X905460Y444906D02*
X904783Y445583D01*
G01X906846Y444906D02*
X905460D01*
G01X907640Y444112D02*
X906846Y444906D01*
G01X907640Y440709D02*
Y444112D01*
G01X928400Y419949D02*
X907640Y440709D01*
G01X881100Y445593D02*
Y497100D01*
G01X887417Y430344D02*
X881100Y445593D01*
G01X915412Y402349D02*
X887417Y430344D01*
G01X892900Y457686D02*
Y467406D01*
G01X892184Y456970D02*
X892900Y457686D01*
G01X892184Y455964D02*
Y456970D01*
G01X892900Y455248D02*
X892184Y455964D01*
G01X892900Y445108D02*
Y455248D01*
G01X892250Y444458D02*
X892900Y445108D01*
G01X891472Y444458D02*
X892250D01*
G01X890822Y443808D02*
X891472Y444458D01*
G01X890822Y442458D02*
Y443808D01*
G01X891472Y441808D02*
X890822Y442458D01*
G01X892250Y441808D02*
X891472D01*
G01X892900Y441158D02*
X892250Y441808D01*
G01X892900Y437509D02*
Y441158D01*
G01X920410Y409999D02*
X892900Y437509D01*
G01X850000Y451700D02*
Y487878D01*
G01X906564Y464856D02*
X905849Y465571D01*
G01X910193Y464166D02*
X909503Y464856D01*
G01X910994Y455458D02*
X910193Y456259D01*
G01Y453586D02*
X910994Y454387D01*
G01X909468Y446634D02*
X910193Y447359D01*
G01X909468Y445864D02*
Y446634D01*
G01X910193Y445139D02*
X909468Y445864D01*
G01X929452Y422499D02*
X910193Y441758D01*
G01X890352Y463629D02*
Y464929D01*
G01X889676Y462953D02*
X890352Y463629D01*
G01X888950Y462953D02*
X889676D01*
G01X888300Y462303D02*
X888950Y462953D01*
G01X888300Y461003D02*
Y462303D01*
G01X888950Y460353D02*
X888300Y461003D01*
G01X889450Y460353D02*
X888950D01*
G01X890100Y459703D02*
X889450Y460353D01*
G01X890100Y458403D02*
Y459703D01*
G01X889450Y457753D02*
X890100Y458403D01*
G01X888950Y457753D02*
X889450D01*
G01X888300Y457103D02*
X888950Y457753D01*
G01X888300Y455803D02*
Y457103D01*
G01X888950Y455153D02*
X888300Y455803D01*
G01X889450Y455153D02*
X888950D01*
G01X890100Y454503D02*
X889450Y455153D01*
G01X890100Y453203D02*
Y454503D01*
G01X889450Y452553D02*
X890100Y453203D01*
G01X888950Y452553D02*
X889450D01*
G01X888300Y451903D02*
X888950Y452553D01*
G01X888300Y450603D02*
Y451903D01*
G01X888950Y449953D02*
X888300Y450603D01*
G01X889450Y449953D02*
X888950D01*
G01X890100Y449303D02*
X889450Y449953D01*
G01X890100Y448003D02*
Y449303D01*
G01X889450Y447353D02*
X890100Y448003D01*
G01X888950Y447353D02*
X889450D01*
G01X888300Y446703D02*
X888950Y447353D01*
G01X888300Y441679D02*
Y446703D01*
G01X890517Y436328D02*
X888300Y441679D01*
G01X919396Y407449D02*
X890517Y436328D01*
G01X885100Y489400D02*
X886500Y490800D01*
G01X885100Y485401D02*
Y489400D01*
G01X883700Y484001D02*
X885100Y485401D01*
G01X883700Y482301D02*
Y484001D01*
G01X885400Y480601D02*
X883700Y482301D01*
G01X885400Y479300D02*
Y480601D01*
G01X883700Y477600D02*
X885400Y479300D01*
G01X883700Y476000D02*
Y477600D01*
G01X885779Y473921D02*
X883700Y476000D01*
G01X885779Y472779D02*
Y473921D01*
G01X883700Y470700D02*
X885779Y472779D01*
G01X883700Y469200D02*
Y470700D01*
G01X885779Y467121D02*
X883700Y469200D01*
G01X885779Y465779D02*
Y467121D01*
G01X890354Y523923D02*
Y528899D01*
G01X890356Y523900D02*
X890354Y523923D01*
G01X876968D02*
Y528899D01*
G01X876970Y523900D02*
X876968Y523923D01*
G01X909000Y496573D02*
X907086Y498487D01*
G01X909000Y495100D02*
Y496573D01*
G01X908600Y494700D02*
X909000Y495100D01*
G01X908600Y489200D02*
Y494700D01*
G01X905500Y486100D02*
X908600Y489200D01*
G01X905500Y475547D02*
Y486100D01*
G01X903203Y473250D02*
X905500Y475547D01*
G01X882500Y498500D02*
X882900D01*
G01X881100Y497100D02*
X882500Y498500D01*
G01X853543Y523923D02*
Y528899D01*
G01X853545Y523900D02*
X853543Y523923D01*
G01X883661D02*
Y528899D01*
G01X883663Y523900D02*
X883661Y523923D01*
G01X894422Y495694D02*
X893000D01*
G01X895000Y495116D02*
X894422Y495694D01*
G01X895000Y491791D02*
Y495116D01*
G01X894500Y491291D02*
X895000Y491791D01*
G01X891719Y491291D02*
X894500D01*
G01X890900Y490472D02*
X891719Y491291D01*
G01X890900Y489250D02*
Y490472D01*
G01X891400Y488750D02*
X890900Y489250D01*
G01X892400Y488750D02*
X891400D01*
G01X893040Y488110D02*
X892400Y488750D01*
G01X893040Y486700D02*
Y488110D01*
G01X892540Y486200D02*
X893040Y486700D01*
G01X891500Y486200D02*
X892540D01*
G01X890900Y485600D02*
X891500Y486200D01*
G01X890900Y484229D02*
Y485600D01*
G01X891473Y483656D02*
X890900Y484229D01*
G01X892351Y483656D02*
X891473D01*
G01X893051Y482956D02*
X892351Y483656D01*
G01X893051Y481656D02*
Y482956D01*
G01X892451Y481056D02*
X893051Y481656D01*
G01X891473Y481056D02*
X892451D01*
G01X890823Y480406D02*
X891473Y481056D01*
G01X890823Y479106D02*
Y480406D01*
G01X891473Y478456D02*
X890823Y479106D01*
G01X892427Y478456D02*
X891473D01*
G01X893077Y477806D02*
X892427Y478456D01*
G01X893077Y476506D02*
Y477806D01*
G01X892427Y475856D02*
X893077Y476506D01*
G01X891474Y475856D02*
X892427D01*
G01X890824Y475206D02*
X891474Y475856D01*
G01X890824Y473906D02*
Y475206D01*
G01X891474Y473256D02*
X890824Y473906D01*
G01X892426Y473256D02*
X891474D01*
G01X893076Y472606D02*
X892426Y473256D01*
G01X893076Y471306D02*
Y472606D01*
G01X892426Y470656D02*
X893076Y471306D01*
G01X891474Y470656D02*
X892426D01*
G01X890824Y470006D02*
X891474Y470656D01*
G01X890824Y468706D02*
Y470006D01*
G01X891474Y468056D02*
X890824Y468706D01*
G01X892250Y468056D02*
X891474D01*
G01X892900Y467406D02*
X892250Y468056D01*
G01X855300Y501428D02*
X854350Y502378D01*
G01X855300Y475250D02*
Y501428D01*
G01X854650Y474600D02*
X855300Y475250D01*
G01X853300Y474600D02*
X854650D01*
G01X852650Y475250D02*
X853300Y474600D01*
G01X852650Y487878D02*
Y475250D01*
G01X852000Y488528D02*
X852650Y487878D01*
G01X850650Y488528D02*
X852000D01*
G01X850000Y487878D02*
X850650Y488528D01*
G01X907086Y523923D02*
Y528899D01*
G01X907088Y523900D02*
X907086Y523923D01*
G01X910193Y487193D02*
X912300Y489300D01*
G01X909503Y483686D02*
X910193Y484376D01*
G01X908790Y483686D02*
X909503D01*
G01X908100Y482996D02*
X908790Y483686D01*
G01X908100Y481686D02*
Y482996D01*
G01X908790Y480996D02*
X908100Y481686D01*
G01X909731Y480996D02*
X908790D01*
G01X910395Y480332D02*
X909731Y480996D01*
G01X909679Y478306D02*
X910395Y479022D01*
G01X908790Y478306D02*
X909679D01*
G01X908100Y477616D02*
X908790Y478306D01*
G01X908100Y476306D02*
Y477616D01*
G01X908790Y475616D02*
X908100Y476306D01*
G01X909754Y475616D02*
X908790D01*
G01X910393Y474977D02*
X909754Y475616D01*
G01X909652Y472926D02*
X910393Y473667D01*
G01X906489Y472926D02*
X909652D01*
G01X905773Y472210D02*
X906489Y472926D01*
G01X905773Y470900D02*
Y472210D01*
G01X906437Y470236D02*
X905773Y470900D01*
G01X909755Y470236D02*
X906437D01*
G01X910395Y469596D02*
X909755Y470236D01*
G01X909793Y467546D02*
X910395Y468148D01*
G01X906514Y467546D02*
X909793D01*
G01X905849Y466881D02*
X906514Y467546D01*
G01X905849Y465571D02*
Y466881D01*
G01X909503Y464856D02*
X906564D01*
G01X870275Y523923D02*
Y528899D01*
G01X870277Y523900D02*
X870275Y523923D01*
G01X888300Y495000D02*
X889200Y495900D01*
G01X888300Y466203D02*
Y495000D01*
G01X888950Y465553D02*
X888300Y466203D01*
G01X889728Y465553D02*
X888950D01*
G01X890352Y464929D02*
X889728Y465553D01*
G01X883661Y561723D02*
Y566699D01*
G01X883663Y561700D02*
X883661Y561723D01*
G01X873622Y535101D02*
X873621Y535100D01*
G01X873622Y536300D02*
Y535101D01*
G01X874142Y536820D02*
X873622Y536300D01*
G01X874142Y537680D02*
Y536820D01*
G01X873622Y538200D02*
X874142Y537680D01*
G01X873622Y542010D02*
Y538200D01*
G01X873624Y542010D02*
X873622D01*
G01X876968Y561723D02*
Y566699D01*
G01X876970Y561700D02*
X876968Y561723D01*
G01X853543D02*
Y566699D01*
G01X853545Y561700D02*
X853543Y561723D01*
G01X893700Y542033D02*
X893000Y534700D01*
G01X893702Y542010D02*
X893700Y542033D01*
G01X887007Y574592D02*
X886621Y572500D01*
G01X887007Y579810D02*
Y574592D01*
G01X887009Y579810D02*
X887007D01*
G01X870275Y561723D02*
Y566699D01*
G01X870277Y561700D02*
X870275Y561723D01*
G01X880314Y573992D02*
Y572900D01*
G01X880832Y574510D02*
X880314Y573992D01*
G01X880832Y575390D02*
Y574510D01*
G01X880314Y575908D02*
X880832Y575390D01*
G01X880314Y579810D02*
Y575908D01*
G01X880317Y579810D02*
X880314D01*
G01X850196Y536792D02*
X849810Y534700D01*
G01X850196Y542010D02*
Y536792D01*
G01X850198Y542010D02*
X850196D01*
G01X856889Y579833D02*
X856189Y572500D01*
G01X856891Y579810D02*
X856889Y579833D01*
G01X850196Y574592D02*
X849810Y572500D01*
G01X850196Y579810D02*
Y574592D01*
G01X850198Y579810D02*
X850196D01*
G01X890354Y561723D02*
Y566699D01*
G01X890356Y561700D02*
X890354Y561723D01*
G01X873622Y572901D02*
X873621Y572900D01*
G01X873622Y574100D02*
Y572901D01*
G01X874142Y574620D02*
X873622Y574100D01*
G01X874142Y575480D02*
Y574620D01*
G01X873622Y576000D02*
X874142Y575480D01*
G01X873622Y579810D02*
Y576000D01*
G01X873624Y579810D02*
X873622D01*
G01X907086Y561723D02*
Y566699D01*
G01X907088Y561700D02*
X907086Y561723D01*
G01X880314Y536192D02*
Y535100D01*
G01X880832Y536710D02*
X880314Y536192D01*
G01X880832Y537590D02*
Y536710D01*
G01X880314Y538108D02*
X880832Y537590D01*
G01X880314Y542010D02*
Y538108D01*
G01X880317Y542010D02*
X880314D01*
G01X893700Y579833D02*
X893000Y572500D01*
G01X893702Y579810D02*
X893700Y579833D01*
G01X856889Y542033D02*
X856189Y534700D01*
G01X856891Y542010D02*
X856889Y542033D01*
G01X887007Y536792D02*
X886621Y534700D01*
G01X887007Y542010D02*
Y536792D01*
G01X887009Y542010D02*
X887007D01*
G01X853543Y599523D02*
Y604499D01*
G01X853545Y599500D02*
X853543Y599523D01*
G01X873622Y617610D02*
X873624D01*
G01X873622Y613800D02*
Y617610D01*
G01X874142Y613280D02*
X873622Y613800D01*
G01X874142Y612420D02*
Y613280D01*
G01X873622Y611900D02*
X874142Y612420D01*
G01X873622Y610701D02*
Y611900D01*
G01X873621Y610700D02*
X873622Y610701D01*
G01X907086Y599523D02*
Y604499D01*
G01X907088Y599500D02*
X907086Y599523D01*
G01X870275D02*
Y604499D01*
G01X870277Y599500D02*
X870275Y599523D01*
G01X876968D02*
Y604499D01*
G01X876970Y599500D02*
X876968Y599523D01*
G01X883661D02*
Y604499D01*
G01X883663Y599500D02*
X883661Y599523D01*
G01X890354D02*
Y604499D01*
G01X890356Y599500D02*
X890354Y599523D01*
G01X850196Y612392D02*
X849810Y610300D01*
G01X850196Y617610D02*
Y612392D01*
G01X850198Y617610D02*
X850196D01*
G01X856889Y617633D02*
X856189Y610300D01*
G01X856891Y617610D02*
X856889Y617633D01*
G01X887007Y617610D02*
X887009D01*
G01X887007Y612392D02*
Y617610D01*
G01X886621Y610300D02*
X887007Y612392D01*
G01X880314Y617610D02*
X880317D01*
G01X880314Y613708D02*
Y617610D01*
G01X880832Y613190D02*
X880314Y613708D01*
G01X880832Y612310D02*
Y613190D01*
G01X880314Y611792D02*
X880832Y612310D01*
G01X880314Y610700D02*
Y611792D01*
G01X893700Y617633D02*
X893000Y610300D01*
G01X893702Y617610D02*
X893700Y617633D01*
G01X923818Y-2008D02*
X923432Y-4100D01*
G01X923818Y3233D02*
Y-2008D01*
G01X923820Y3233D02*
X923818D01*
G01X927165Y-14877D02*
Y-9901D01*
G01X927167Y-14877D02*
X927165D01*
G01X910433Y-3699D02*
X910432Y-3700D01*
G01X910433Y-2500D02*
Y-3699D01*
G01X910953Y-1980D02*
X910433Y-2500D01*
G01X910953Y-1120D02*
Y-1980D01*
G01X910433Y-600D02*
X910953Y-1120D01*
G01X910433Y3233D02*
Y-600D01*
G01X910435Y3233D02*
X910433D01*
G01X953936Y-2608D02*
Y-3700D01*
G01X954454Y-2090D02*
X953936Y-2608D01*
G01X954454Y-1210D02*
Y-2090D01*
G01X953936Y-692D02*
X954454Y-1210D01*
G01X953936Y3230D02*
Y-692D01*
G01X953939Y3233D02*
X953936Y3230D01*
G01X950592Y27897D02*
X950590Y27899D01*
G01X950592Y22923D02*
Y27897D01*
G01X963976Y22923D02*
Y28014D01*
G01X963978Y22923D02*
X963976D01*
G01X947244Y-3699D02*
X947243Y-3700D01*
G01X947244Y-2500D02*
Y-3699D01*
G01X947764Y-1980D02*
X947244Y-2500D01*
G01X947764Y-1120D02*
Y-1980D01*
G01X947244Y-600D02*
X947764Y-1120D01*
G01X947244Y3233D02*
Y-600D01*
G01X947246Y3233D02*
X947244D01*
G01X913779Y22923D02*
Y27899D01*
G01X913781Y22923D02*
X913779D01*
G01X920472D02*
Y27899D01*
G01X920474Y22923D02*
X920472D01*
G01Y-14877D02*
Y-9901D01*
G01X920474Y-14877D02*
X920472D01*
G01X943897Y22923D02*
Y27899D01*
G01X943899Y22923D02*
X943897D01*
G01X970669Y-14877D02*
Y-7108D01*
G01X970671Y-14877D02*
X970669D01*
G01X927165Y22923D02*
Y27899D01*
G01X927167Y22923D02*
X927165D01*
G01X970669D02*
Y28014D01*
G01X970671Y22923D02*
X970669D01*
G01X913779Y-14877D02*
Y-9901D01*
G01X913781Y-14877D02*
X913779D01*
G01X930511Y3233D02*
X929811Y-4100D01*
G01X930513Y3233D02*
X930511D01*
G01X960629D02*
Y-4536D01*
G01X960631Y3233D02*
X960629D01*
G01X963976Y-14877D02*
Y-7108D01*
G01X963978Y-14877D02*
X963976D01*
G01X943897D02*
Y-9901D01*
G01X943899Y-14877D02*
X943897D01*
G01X950590D02*
Y-9901D01*
G01X950592Y-14877D02*
X950590D01*
G01X917125Y-2608D02*
Y-3700D01*
G01X917643Y-2090D02*
X917125Y-2608D01*
G01X917643Y-1210D02*
Y-2090D01*
G01X917125Y-692D02*
X917643Y-1210D01*
G01X917125Y3230D02*
Y-692D01*
G01X917128Y3233D02*
X917125Y3230D01*
G01X947244Y34101D02*
X947243Y34100D01*
G01X947244Y35300D02*
Y34101D01*
G01X947764Y35820D02*
X947244Y35300D01*
G01X947764Y36680D02*
Y35820D01*
G01X947244Y37200D02*
X947764Y36680D01*
G01X947244Y41033D02*
Y37200D01*
G01X947246Y41033D02*
X947244D01*
G01X917125Y72992D02*
Y71900D01*
G01X917643Y73510D02*
X917125Y72992D01*
G01X917643Y74390D02*
Y73510D01*
G01X917125Y74908D02*
X917643Y74390D01*
G01X917125Y78830D02*
Y74908D01*
G01X917128Y78833D02*
X917125Y78830D01*
G01X959800Y91900D02*
Y99500D01*
G01X958600Y90700D02*
X959800Y91900D01*
G01X958600Y89400D02*
Y90700D01*
G01X959600Y88400D02*
X958600Y89400D01*
G01X959600Y86600D02*
Y88400D01*
G01X958300Y85300D02*
X959600Y86600D01*
G01X958300Y84100D02*
Y85300D01*
G01X960629Y81771D02*
X958300Y84100D01*
G01X960629Y78833D02*
Y81771D01*
G01X960631Y78833D02*
X960629D01*
G01X963976Y92657D02*
Y97176D01*
G01X953936Y72992D02*
Y71900D01*
G01X954454Y73510D02*
X953936Y72992D01*
G01X954454Y74390D02*
Y73510D01*
G01X953936Y74908D02*
X954454Y74390D01*
G01X953939Y74911D02*
X953936Y74908D01*
G01X953939Y78833D02*
Y74911D01*
G01X917125Y35192D02*
Y34100D01*
G01X917643Y35710D02*
X917125Y35192D01*
G01X917643Y36590D02*
Y35710D01*
G01X917125Y37108D02*
X917643Y36590D01*
G01X917125Y41030D02*
Y37108D01*
G01X917128Y41033D02*
X917125Y41030D01*
G01X923580Y34500D02*
X923432Y33700D01*
G01X923818Y35792D02*
X923580Y34500D01*
G01X923818Y41033D02*
Y35792D01*
G01X923820Y41033D02*
X923818D01*
G01X953936Y35192D02*
Y34100D01*
G01X954454Y35710D02*
X953936Y35192D01*
G01X954454Y36590D02*
Y35710D01*
G01X953939Y37105D02*
X954454Y36590D01*
G01X953939Y41033D02*
Y37105D01*
G01X913779Y60723D02*
Y65699D01*
G01X913781Y60723D02*
X913779D01*
G01X923818Y73592D02*
X923432Y71500D01*
G01X923818Y78833D02*
Y73592D01*
G01X923820Y78833D02*
X923818D01*
G01X960629Y41033D02*
Y35957D01*
G01X960631Y41033D02*
X960629D01*
G01X970669Y60723D02*
Y65814D01*
G01X970671Y60723D02*
X970669D01*
G01Y96269D02*
Y92757D01*
G01X961800Y91500D02*
Y98599D01*
G01X962600Y90700D02*
X961800Y91500D01*
G01X962600Y89200D02*
Y90700D01*
G01X961900Y88500D02*
X962600Y89200D01*
G01X961900Y85985D02*
Y88500D01*
G01X960629Y84714D02*
X961900Y85985D01*
G01X929887Y34500D02*
X929811Y33700D01*
G01X930511Y41033D02*
X929887Y34500D01*
G01X930513Y41033D02*
X930511D01*
G01X963976Y60723D02*
Y65814D01*
G01X963978Y60723D02*
X963976D01*
G01X950590D02*
Y65699D01*
G01X950592Y60723D02*
X950590D01*
G01X930193Y75500D02*
X929811Y71500D01*
G01X930511Y78833D02*
X930193Y75500D01*
G01X930513Y78833D02*
X930511D01*
G01X910433Y34101D02*
X910432Y34100D01*
G01X910433Y35300D02*
Y34101D01*
G01X910953Y35820D02*
X910433Y35300D01*
G01X910953Y36680D02*
Y35820D01*
G01X910433Y37200D02*
X910953Y36680D01*
G01X910433Y41033D02*
Y37200D01*
G01X910435Y41033D02*
X910433D01*
G01X920472Y60723D02*
Y65699D01*
G01X920474Y60723D02*
X920472D01*
G01X910433Y71901D02*
X910432Y71900D01*
G01X910433Y73100D02*
Y71901D01*
G01X910953Y73620D02*
X910433Y73100D01*
G01X910953Y74480D02*
Y73620D01*
G01X910433Y75000D02*
X910953Y74480D01*
G01X910433Y78833D02*
Y75000D01*
G01X910435Y78833D02*
X910433D01*
G01X947244Y71901D02*
X947243Y71900D01*
G01X947244Y73100D02*
Y71901D01*
G01X947764Y73620D02*
X947244Y73100D01*
G01X947764Y74480D02*
Y73620D01*
G01X947244Y75000D02*
X947764Y74480D01*
G01X947244Y78833D02*
Y75000D01*
G01X947246Y78833D02*
X947244D01*
G01X927165Y60723D02*
Y65699D01*
G01X927167Y60723D02*
X927165D01*
G01X943897D02*
Y65699D01*
G01X943899Y60723D02*
X943897D01*
G01X954350Y126000D02*
X951175Y122825D01*
G01X954350Y140800D02*
Y126000D01*
G01X954850Y141300D02*
X954350Y140800D01*
G01X956500Y141300D02*
X954850D01*
G01X957000Y140800D02*
X956500Y141300D01*
G01X957000Y136350D02*
Y140800D01*
G01X957650Y135700D02*
X957000Y136350D01*
G01X959000Y135700D02*
X957650D01*
G01X959650Y136350D02*
X959000Y135700D01*
G01X959650Y144000D02*
Y136350D01*
G01X959150Y144500D02*
X959650Y144000D01*
G01X955301Y144500D02*
X959150D01*
G01X951550Y148251D02*
X955301Y144500D01*
G01X951550Y163795D02*
Y148251D01*
G01X944497Y116147D02*
Y110927D01*
G01X951175Y122825D02*
X944497Y116147D01*
G01X965500Y106500D02*
X967478Y108478D01*
G01X965500Y105200D02*
Y106500D01*
G01X959800Y99500D02*
X965500Y105200D01*
G01X967478Y108478D02*
X972300Y113300D01*
G01X969650Y104150D02*
X972825Y107325D01*
G01X969650Y102850D02*
Y104150D01*
G01X963976Y97176D02*
X969650Y102850D01*
G01X914137Y144650D02*
Y170836D01*
G01X913487Y144000D02*
X914137Y144650D01*
G01X912097Y144000D02*
X913487D01*
G01X911447Y144650D02*
X912097Y144000D01*
G01X911447Y146860D02*
Y144650D01*
G01X910757Y147550D02*
X911447Y146860D01*
G01X916794Y141000D02*
Y169877D01*
G01Y128604D02*
Y141000D01*
G01X916090Y127900D02*
X916794Y128604D01*
G01X914780Y127900D02*
X916090D01*
G01X914190Y128490D02*
X914780Y127900D01*
G01X914190Y135450D02*
Y128490D01*
G01X913540Y136100D02*
X914190Y135450D01*
G01X912150Y136100D02*
X913540D01*
G01X911500Y135450D02*
X912150Y136100D01*
G01X911500Y120759D02*
Y135450D01*
G01X912190Y120069D02*
X911500Y120759D01*
G01X912190Y117379D02*
Y120069D01*
G01X911500Y116689D02*
X912190Y117379D01*
G01X911500Y114606D02*
Y116689D01*
G01X913779Y112327D02*
X911500Y114606D01*
G01X955434Y107684D02*
X962875Y115125D01*
G01X953786Y107684D02*
X955434D01*
G01X960700Y155700D02*
X959996Y156404D01*
G01X961800Y155700D02*
X960700D01*
G01X962800Y156700D02*
X961800Y155700D01*
G01X965800Y155000D02*
Y160050D01*
G01X972800Y148000D02*
X965800Y155000D01*
G01X964100Y124050D02*
X972800Y132750D01*
G01X964100Y116350D02*
Y124050D01*
G01X962875Y115125D02*
X964100Y116350D01*
G01X926300Y140465D02*
Y142500D01*
G01X925524Y139689D02*
X926300Y140465D01*
G01X924426Y139689D02*
X925524D01*
G01X923650Y138913D02*
X924426Y139689D01*
G01X923650Y137815D02*
Y138913D01*
G01X924426Y137039D02*
X923650Y137815D01*
G01X925524Y137039D02*
X924426D01*
G01X926300Y136263D02*
X925524Y137039D01*
G01X926300Y135165D02*
Y136263D01*
G01X925524Y134389D02*
X926300Y135165D01*
G01X924426Y134389D02*
X925524D01*
G01X923650Y133613D02*
X924426Y134389D01*
G01X923650Y132515D02*
Y133613D01*
G01X924426Y131739D02*
X923650Y132515D01*
G01X925524Y131739D02*
X924426D01*
G01X926300Y130963D02*
X925524Y131739D01*
G01X926300Y127449D02*
Y130963D01*
G01X920472Y121621D02*
X926300Y127449D01*
G01X920472Y112327D02*
Y121621D01*
G01X926300Y142500D02*
Y163709D01*
G01X953050Y109700D02*
X955425Y112075D01*
G01X950590Y109700D02*
X953050D01*
G01X957300Y152450D02*
Y160497D01*
G01X959250Y150500D02*
X957300Y152450D01*
G01X961477Y150500D02*
X959250D01*
G01X965600Y146377D02*
X961477Y150500D01*
G01X969600Y146377D02*
X965600D01*
G01X970250Y145727D02*
X969600Y146377D01*
G01X970250Y137750D02*
Y145727D01*
G01X969600Y137100D02*
X970250Y137750D01*
G01X968250Y137100D02*
X969600D01*
G01X967600Y137750D02*
X968250Y137100D01*
G01X967600Y141600D02*
Y137750D01*
G01X966950Y142250D02*
X967600Y141600D01*
G01X965600Y142250D02*
X966950D01*
G01X964950Y141600D02*
X965600Y142250D01*
G01X964950Y134000D02*
Y141600D01*
G01X960600Y129650D02*
X964950Y134000D01*
G01X960600Y117250D02*
Y129650D01*
G01X955425Y112075D02*
X960600Y117250D01*
G01X920112Y126113D02*
Y136000D01*
G01X915600Y121601D02*
X920112Y126113D01*
G01X915600Y111000D02*
Y121601D01*
G01X914800Y110200D02*
X915600Y111000D01*
G01X914800Y109609D02*
Y110200D01*
G01X917125Y107284D02*
X914800Y109609D01*
G01X920091Y156205D02*
Y157555D01*
G01X920741Y155555D02*
X920091Y156205D01*
G01X922150Y155555D02*
X920741D01*
G01X922800Y154905D02*
X922150Y155555D01*
G01X922800Y153555D02*
Y154905D01*
G01X922150Y152905D02*
X922800Y153555D01*
G01X920741Y152905D02*
X922150D01*
G01X920091Y152255D02*
X920741Y152905D01*
G01X920091Y150905D02*
Y152255D01*
G01X920741Y150255D02*
X920091Y150905D01*
G01X922150Y150255D02*
X920741D01*
G01X922800Y149605D02*
X922150Y150255D01*
G01X922800Y148255D02*
Y149605D01*
G01X922150Y147605D02*
X922800Y148255D01*
G01X920741Y147605D02*
X922150D01*
G01X920091Y146955D02*
X920741Y147605D01*
G01X920091Y145605D02*
Y146955D01*
G01X920741Y144955D02*
X920091Y145605D01*
G01X922150Y144955D02*
X920741D01*
G01X922800Y144305D02*
X922150Y144955D01*
G01X922800Y142955D02*
Y144305D01*
G01X922150Y142305D02*
X922800Y142955D01*
G01X920741Y142305D02*
X922150D01*
G01X920091Y141655D02*
X920741Y142305D01*
G01X920091Y140921D02*
Y141655D01*
G01X920112Y140900D02*
X920091Y140921D01*
G01X920112Y136000D02*
Y140900D01*
G01X929100Y126351D02*
Y137500D01*
G01X923700Y120951D02*
X929100Y126351D01*
G01X923700Y112700D02*
Y120951D01*
G01X920627Y109627D02*
X923700Y112700D01*
G01X920627Y107934D02*
Y109627D01*
G01X921277Y107284D02*
X920627Y107934D01*
G01X923518Y107284D02*
X921277D01*
G01X929100Y137500D02*
Y162902D01*
G01X973400Y99000D02*
X970669Y96269D01*
G01X967500Y105500D02*
X974300Y112300D01*
G01X967500Y104299D02*
Y105500D01*
G01X961800Y98599D02*
X967500Y104299D01*
G01X926400Y113092D02*
X927165Y112327D01*
G01X926400Y119749D02*
Y113092D01*
G01X934200Y127549D02*
X926400Y119749D01*
G01X934200Y128743D02*
Y127549D01*
G01X933550Y129393D02*
X934200Y128743D01*
G01X932350Y129393D02*
X933550D01*
G01X931700Y130043D02*
X932350Y129393D01*
G01X931700Y131393D02*
Y130043D01*
G01X932350Y132043D02*
X931700Y131393D01*
G01X933550Y132043D02*
X932350D01*
G01X934200Y132693D02*
X933550Y132043D01*
G01X934200Y134043D02*
Y132693D01*
G01X933550Y134693D02*
X934200Y134043D01*
G01X932350Y134693D02*
X933550D01*
G01X931700Y135343D02*
X932350Y134693D01*
G01X931700Y136693D02*
Y135343D01*
G01X932350Y137343D02*
X931700Y136693D01*
G01X933550Y137343D02*
X932350D01*
G01X934200Y137993D02*
X933550Y137343D01*
G01X934200Y139343D02*
Y137993D01*
G01X933550Y139993D02*
X934200Y139343D01*
G01X932350Y139993D02*
X933550D01*
G01X931700Y140643D02*
X932350Y139993D01*
G01X931700Y141993D02*
Y140643D01*
G01X932350Y142643D02*
X931700Y141993D01*
G01X933550Y142643D02*
X932350D01*
G01X934200Y143293D02*
X933550Y142643D01*
G01X934200Y144643D02*
Y143293D01*
G01X933550Y145293D02*
X934200Y144643D01*
G01X932350Y145293D02*
X933550D01*
G01X931700Y145943D02*
X932350Y145293D01*
G01X931700Y147293D02*
Y145943D01*
G01X932350Y147943D02*
X931700Y147293D01*
G01X933550Y147943D02*
X932350D01*
G01X934200Y148593D02*
X933550Y147943D01*
G01X934200Y149943D02*
Y148593D01*
G01X933550Y150593D02*
X934200Y149943D01*
G01X932350Y150593D02*
X933550D01*
G01X931700Y151243D02*
X932350Y150593D01*
G01X931700Y152593D02*
Y151243D01*
G01X932350Y153243D02*
X931700Y152593D01*
G01X933550Y153243D02*
X932350D01*
G01X934200Y153893D02*
X933550Y153243D01*
G01X934200Y164196D02*
Y153893D01*
G01X954200Y149700D02*
Y162854D01*
G01X956600Y147300D02*
X954200Y149700D01*
G01X960200Y147300D02*
X956600D01*
G01X962350Y145150D02*
X960200Y147300D01*
G01X962350Y135150D02*
Y145150D01*
G01X957350Y130150D02*
X962350Y135150D01*
G01X957350Y125200D02*
Y130150D01*
G01X955657Y123507D02*
X957350Y125200D01*
G01X955657Y122587D02*
Y123507D01*
G01X956612Y121632D02*
X955657Y122587D01*
G01X956612Y120712D02*
Y121632D01*
G01X955658Y119758D02*
X956612Y120712D01*
G01X954738Y119758D02*
X955658D01*
G01X953783Y120713D02*
X954738Y119758D01*
G01X952863Y120713D02*
X953783D01*
G01X951909Y119759D02*
X952863Y120713D01*
G01X951909Y118009D02*
Y119759D01*
G01X950865Y116965D02*
X951909Y118009D01*
G01X949115Y116965D02*
X950865D01*
G01X947200Y115050D02*
X949115Y116965D01*
G01X947200Y110600D02*
Y115050D01*
G01X944080Y107480D02*
X947200Y110600D01*
G01X944080Y105558D02*
Y107480D01*
G01X944554Y105084D02*
X944080Y105558D01*
G01X947243Y105084D02*
X944554D01*
G01X911480Y155600D02*
Y171787D01*
G01X910980Y155100D02*
X911480Y155600D01*
G01X936900Y130950D02*
Y135000D01*
G01X938450Y129400D02*
X936900Y130950D01*
G01X938450Y127901D02*
Y129400D01*
G01X929100Y118551D02*
X938450Y127901D01*
G01X929100Y111500D02*
Y118551D01*
G01X927900Y110300D02*
X929100Y111500D01*
G01X926800Y110300D02*
X927900D01*
G01X925500Y109000D02*
X926800Y110300D01*
G01X925500Y106400D02*
Y109000D01*
G01X924900Y105800D02*
X925500Y106400D01*
G01X924900Y103000D02*
Y105800D01*
G01X925600Y102300D02*
X924900Y103000D01*
G01X929160Y102300D02*
X925600D01*
G01X929811Y102951D02*
X929160Y102300D01*
G01X929811Y106934D02*
Y102951D01*
G01X936900Y142250D02*
Y163289D01*
G01X937850Y141300D02*
X936900Y142250D01*
G01X937850Y139150D02*
Y141300D01*
G01X936900Y138200D02*
X937850Y139150D01*
G01X936900Y135000D02*
Y138200D01*
G01X952866Y165111D02*
X951550Y163795D01*
G01X914137Y170836D02*
X918899Y175598D01*
G01X916794Y169877D02*
X920707Y173790D01*
G01X959996Y156404D02*
Y160796D01*
G01X962800Y160050D02*
Y156700D01*
G01X963300Y160550D02*
X962800Y160050D01*
G01X965300Y160550D02*
X963300D01*
G01X965800Y160050D02*
X965300Y160550D01*
G01X931491Y168900D02*
X940583Y177992D01*
G01X930393Y168900D02*
X931491D01*
G01X929121Y170172D02*
X930393Y168900D01*
G01X928023Y170172D02*
X929121D01*
G01X927247Y169396D02*
X928023Y170172D01*
G01X927247Y168298D02*
Y169396D01*
G01X928519Y167026D02*
X927247Y168298D01*
G01X928519Y165928D02*
Y167026D01*
G01X926300Y163709D02*
X928519Y165928D01*
G01X957300Y160497D02*
X957576Y160773D01*
G01X920091Y169566D02*
X922511Y171986D01*
G01X920091Y161505D02*
Y169566D01*
G01X920741Y160855D02*
X920091Y161505D01*
G01X920850Y160855D02*
X920741D01*
G01X921500Y160205D02*
X920850Y160855D01*
G01X921500Y158855D02*
Y160205D01*
G01X920850Y158205D02*
X921500Y158855D01*
G01X920741Y158205D02*
X920850D01*
G01X920091Y157555D02*
X920741Y158205D01*
G01X929100Y162902D02*
X942431Y176233D01*
G01X944226Y174222D02*
X934200Y164196D01*
G01X954200Y162854D02*
X954966Y163620D01*
G01X911480Y171787D02*
X917095Y177402D01*
G01X936900Y163289D02*
X945934Y172323D01*
G01X923097Y261760D02*
X920847D01*
G01X963656Y331960D02*
X961406D01*
G01X936617Y339760D02*
X934367D01*
G01X933237Y330009D02*
X930987D01*
G01X956897Y339760D02*
X954647D01*
G01X916337Y331960D02*
X913787D01*
G01X936617Y328060D02*
X934367D01*
G01X963656D02*
X961406D01*
G01X967036Y333909D02*
X964786D01*
G01X939997Y330009D02*
X937747D01*
G01X953517Y333909D02*
X951267D01*
G01X973796Y326110D02*
X971546D01*
G01X950137Y335860D02*
X947887D01*
G01X967036Y326110D02*
X964786D01*
G01X973796Y333909D02*
X971546D01*
G01X916337Y335860D02*
X913787D01*
G01X923097D02*
X920847D01*
G01X929857Y339760D02*
X927607D01*
G01X939997Y333909D02*
X937747D01*
G01X929857Y335860D02*
X927607D01*
G01X923097Y331960D02*
X920847D01*
G01X956897Y335860D02*
X954647D01*
G01X916273Y378760D02*
X911498D01*
G01X950137Y367060D02*
X947887D01*
G01X933237Y361209D02*
X930987D01*
G01X936617Y367060D02*
X934367D01*
G01X946757Y365109D02*
X944507D01*
G01X973796Y353409D02*
X971546D01*
G01X916337Y347560D02*
X913787D01*
G01X950137Y382660D02*
X947887D01*
G01X936617Y378760D02*
X934367D01*
G01X916133Y382843D02*
X911222D01*
G01X933237Y341709D02*
X930987D01*
G01X929857Y378760D02*
X927607D01*
G01X963656Y367060D02*
X961406D01*
G01X936617Y347560D02*
X934367D01*
G01X936617Y359260D02*
X934367D01*
G01X956897Y374860D02*
X954647D01*
G01X973796Y369010D02*
X971546D01*
G01X953517Y365109D02*
X951267D01*
G01X953517Y345609D02*
X951267D01*
G01X946757Y361209D02*
X944507D01*
G01X950137Y347560D02*
X947887D01*
G01X916092Y385393D02*
X912479D01*
G01X946757Y392410D02*
X944507D01*
G01X960276Y376809D02*
X958026D01*
G01X936617Y394359D02*
X934367D01*
G01X923097Y351460D02*
X920847D01*
G01X953517Y353409D02*
X951267D01*
G01X956897Y355360D02*
X954647D01*
G01X950137Y374860D02*
X947887D01*
G01X930264Y402349D02*
X915412D01*
G01X943377Y394359D02*
X941127D01*
G01X946757Y388509D02*
X944507D01*
G01X939997Y369010D02*
X937747D01*
G01X946757Y341709D02*
X944507D01*
G01X967036Y372909D02*
X964786D01*
G01X936617Y386560D02*
X934367D01*
G01X929857Y355360D02*
X927607D01*
G01X933237Y369010D02*
X930987D01*
G01X946757Y380709D02*
X944507D01*
G01X970416Y374860D02*
X968166D01*
G01X933237Y388509D02*
X930987D01*
G01X943377Y386560D02*
X941127D01*
G01X933237Y349509D02*
X930987D01*
G01X939997D02*
X937747D01*
G01X950137Y355360D02*
X947887D01*
G01X929857Y359260D02*
X927607D01*
G01X967036Y361209D02*
X964786D01*
G01X933237Y392410D02*
X930987D01*
G01X970416Y363160D02*
X968166D01*
G01X915642Y387943D02*
X913757D01*
G01X939997Y353409D02*
X937747D01*
G01X963656Y363160D02*
X961406D01*
G01X946757Y345609D02*
X944507D01*
G01X956897Y382660D02*
X954647D01*
G01X956897Y359260D02*
X954647D01*
G01X923097Y347560D02*
X920847D01*
G01X929857Y374860D02*
X927607D01*
G01X973796Y357309D02*
X971546D01*
G01X933237Y380709D02*
X930987D01*
G01X973796Y372909D02*
X971546D01*
G01X960276Y380709D02*
X958026D01*
G01X916337Y351460D02*
X913787D01*
G01X939997Y372909D02*
X937747D01*
G01X946757Y376809D02*
X944507D01*
G01X929782Y404899D02*
X917279D01*
G01X947300Y446027D02*
Y476403D01*
G01X960779Y432548D02*
X947300Y446027D01*
G01X952500Y461484D02*
Y491500D01*
G01X953117Y460867D02*
X952500Y461484D01*
G01X954467Y460867D02*
X953117D01*
G01X955117Y461517D02*
X954467Y460867D01*
G01X955117Y464200D02*
Y461517D01*
G01X955617Y464700D02*
X955117Y464200D01*
G01X957267Y464700D02*
X955617D01*
G01X957767Y464200D02*
X957267Y464700D01*
G01X957767Y442736D02*
Y464200D01*
G01X963690Y436813D02*
X957767Y442736D01*
G01X912935Y462218D02*
Y486343D01*
G01X913750Y461403D02*
X912935Y462218D01*
G01X915550Y461403D02*
X913750D01*
G01X916200Y460753D02*
X915550Y461403D01*
G01X916200Y459453D02*
Y460753D01*
G01X915550Y458803D02*
X916200Y459453D01*
G01X913750Y458803D02*
X915550D01*
G01X913100Y458153D02*
X913750Y458803D01*
G01X913100Y456853D02*
Y458153D01*
G01X913750Y456203D02*
X913100Y456853D01*
G01X915550Y456203D02*
X913750D01*
G01X916200Y455553D02*
X915550Y456203D01*
G01X916200Y454253D02*
Y455553D01*
G01X915550Y453603D02*
X916200Y454253D01*
G01X913750Y453603D02*
X915550D01*
G01X913100Y452953D02*
X913750Y453603D01*
G01X913100Y451653D02*
Y452953D01*
G01X913750Y451003D02*
X913100Y451653D01*
G01X915150Y451003D02*
X913750D01*
G01X915800Y450353D02*
X915150Y451003D01*
G01X915800Y449053D02*
Y450353D01*
G01X915150Y448403D02*
X915800Y449053D01*
G01X913850Y448403D02*
X915150D01*
G01X913061Y447614D02*
X913850Y448403D01*
G01X913061Y442690D02*
Y447614D01*
G01X930702Y425049D02*
X913061Y442690D01*
G01X934156Y425049D02*
X930702D01*
G01X925174Y459958D02*
Y488374D01*
G01X925849Y459283D02*
X925174Y459958D01*
G01X927187Y459283D02*
X925849D01*
G01X927837Y458633D02*
X927187Y459283D01*
G01X927837Y457283D02*
Y458633D01*
G01X927187Y456633D02*
X927837Y457283D01*
G01X926200Y456633D02*
X927187D01*
G01X925700Y456133D02*
X926200Y456633D01*
G01X925700Y454483D02*
Y456133D01*
G01X926200Y453983D02*
X925700Y454483D01*
G01X927187Y453983D02*
X926200D01*
G01X927837Y453333D02*
X927187Y453983D01*
G01X927837Y451983D02*
Y453333D01*
G01X927187Y451333D02*
X927837Y451983D01*
G01X925849Y451333D02*
X927187D01*
G01X925174Y450658D02*
X925849Y451333D01*
G01X925174Y446120D02*
Y450658D01*
G01X950355Y420939D02*
X925174Y446120D01*
G01X927700Y462341D02*
Y487300D01*
G01X930484Y459557D02*
X927700Y462341D01*
G01X930484Y449772D02*
Y459557D01*
G01X929834Y449122D02*
X930484Y449772D01*
G01X928700Y449122D02*
X929834D01*
G01X928200Y448622D02*
X928700Y449122D01*
G01X928200Y446972D02*
Y448622D01*
G01X928700Y446472D02*
X928200Y446972D01*
G01X929834Y446472D02*
X928700D01*
G01X930484Y445822D02*
X929834Y446472D01*
G01X930484Y444374D02*
Y445822D01*
G01X951600Y423258D02*
X930484Y444374D01*
G01X935849Y419949D02*
X928400D01*
G01X931851Y427599D02*
X933456D01*
G01X919100Y440350D02*
X931851Y427599D01*
G01X919100Y442318D02*
Y440350D01*
G01X918450Y442968D02*
X919100Y442318D01*
G01X916510Y442968D02*
X918450D01*
G01X915860Y443618D02*
X916510Y442968D01*
G01X915860Y444968D02*
Y443618D01*
G01X916510Y445618D02*
X915860Y444968D01*
G01X918450Y445618D02*
X916510D01*
G01X919100Y446268D02*
X918450Y445618D01*
G01X919100Y448999D02*
Y446268D01*
G01X918400Y449699D02*
X919100Y448999D01*
G01X918400Y452239D02*
Y449699D01*
G01X919100Y452939D02*
X918400Y452239D01*
G01X919100Y456200D02*
Y452939D01*
G01X918500Y456800D02*
X919100Y456200D01*
G01X918500Y458400D02*
Y456800D01*
G01X919100Y459000D02*
X918500Y458400D01*
G01X919100Y463099D02*
Y459000D01*
G01X918299Y463900D02*
X919100Y463099D01*
G01X916000Y463900D02*
X918299D01*
G01X915500Y464400D02*
X916000Y463900D01*
G01X915500Y465881D02*
Y464400D01*
G01X949848Y447116D02*
Y488152D01*
G01X950548Y446416D02*
X949848Y447116D01*
G01X951898Y446416D02*
X950548D01*
G01X952498Y447016D02*
X951898Y446416D01*
G01X952498Y455300D02*
Y447016D01*
G01X952998Y455800D02*
X952498Y455300D01*
G01X954648Y455800D02*
X952998D01*
G01X955148Y455300D02*
X954648Y455800D01*
G01X955148Y441750D02*
Y455300D01*
G01X962091Y434807D02*
X955148Y441750D01*
G01X930843Y409999D02*
X920410D01*
G01X960337Y443735D02*
Y479500D01*
G01X965229Y438843D02*
X960337Y443735D01*
G01X922424Y445173D02*
Y489776D01*
G01X948931Y418666D02*
X922424Y445173D01*
G01X910193Y456259D02*
Y464166D01*
G01X910994Y454387D02*
Y455458D01*
G01X910193Y447359D02*
Y453586D01*
G01Y441758D02*
Y445139D01*
G01X934756Y422499D02*
X929452D01*
G01X932600Y464745D02*
X933175Y465320D01*
G01X931700Y464745D02*
X932600D01*
G01X931200Y464245D02*
X931700Y464745D01*
G01X931200Y462595D02*
Y464245D01*
G01X931700Y462095D02*
X931200Y462595D01*
G01X932450Y462095D02*
X931700D01*
G01X933100Y461445D02*
X932450Y462095D01*
G01X933100Y445408D02*
Y461445D01*
G01X954196Y424312D02*
X933100Y445408D01*
G01X930843Y407449D02*
X919396D01*
G01X946142Y490958D02*
X944000Y493100D01*
G01X946142Y488158D02*
Y490958D01*
G01X947300Y487000D02*
X946142Y488158D01*
G01X947300Y485653D02*
Y487000D01*
G01X946650Y485003D02*
X947300Y485653D01*
G01X945128Y485003D02*
X946650D01*
G01X944478Y484353D02*
X945128Y485003D01*
G01X944478Y483003D02*
Y484353D01*
G01X945128Y482353D02*
X944478Y483003D01*
G01X946650Y482353D02*
X945128D01*
G01X947300Y481703D02*
X946650Y482353D01*
G01X947300Y480353D02*
Y481703D01*
G01X946650Y479703D02*
X947300Y480353D01*
G01X945128Y479703D02*
X946650D01*
G01X944478Y479053D02*
X945128Y479703D01*
G01X944478Y477703D02*
Y479053D01*
G01X945128Y477053D02*
X944478Y477703D01*
G01X946650Y477053D02*
X945128D01*
G01X947300Y476403D02*
X946650Y477053D01*
G01X943897Y523923D02*
Y528899D01*
G01X943899Y523900D02*
X943897Y523923D01*
G01X950590D02*
Y528899D01*
G01X950592Y523900D02*
X950590Y523923D01*
G01X952500Y491500D02*
X950700Y493300D01*
G01X960629Y505613D02*
Y510114D01*
G01X972294Y493948D02*
X960629Y505613D01*
G01X914692Y499400D02*
X913779Y498487D01*
G01X916100Y499400D02*
X914692D01*
G01X917000Y498500D02*
X916100Y499400D01*
G01X917000Y496500D02*
Y498500D01*
G01X915300Y494800D02*
X917000Y496500D01*
G01X915300Y493100D02*
Y494800D01*
G01X914900Y492700D02*
X915300Y493100D01*
G01X914900Y488308D02*
Y492700D01*
G01X912935Y486343D02*
X914900Y488308D01*
G01X924300Y493744D02*
X923600D01*
G01X925400Y492644D02*
X924300Y493744D01*
G01X925400Y488600D02*
Y492644D01*
G01X925174Y488374D02*
X925400Y488600D01*
G01X929000Y496809D02*
X927165Y498644D01*
G01X929000Y495000D02*
Y496809D01*
G01X927974Y493974D02*
X929000Y495000D01*
G01X927974Y487574D02*
Y493974D01*
G01X927700Y487300D02*
X927974Y487574D01*
G01X962800Y516881D02*
X963976Y518057D01*
G01X962800Y514300D02*
Y516881D01*
G01X961700Y513200D02*
X962800Y514300D01*
G01X961700Y511800D02*
Y513200D01*
G01X962600Y510900D02*
X961700Y511800D01*
G01X962600Y506682D02*
Y510900D01*
G01X974392Y494890D02*
X962600Y506682D01*
G01X916150Y466531D02*
X915500Y465881D01*
G01X918450Y466531D02*
X916150D01*
G01X919100Y467181D02*
X918450Y466531D01*
G01X919100Y468531D02*
Y467181D01*
G01X918450Y469181D02*
X919100Y468531D01*
G01X916150Y469181D02*
X918450D01*
G01X915500Y469831D02*
X916150Y469181D01*
G01X915500Y471181D02*
Y469831D01*
G01X916150Y471831D02*
X915500Y471181D01*
G01X918450Y471831D02*
X916150D01*
G01X919100Y472481D02*
X918450Y471831D01*
G01X919100Y473831D02*
Y472481D01*
G01X918450Y474481D02*
X919100Y473831D01*
G01X916150Y474481D02*
X918450D01*
G01X915500Y475131D02*
X916150Y474481D01*
G01X915500Y476481D02*
Y475131D01*
G01X916150Y477131D02*
X915500Y476481D01*
G01X918450Y477131D02*
X916150D01*
G01X919100Y477781D02*
X918450Y477131D01*
G01X919100Y479131D02*
Y477781D01*
G01X918450Y479781D02*
X919100Y479131D01*
G01X916150Y479781D02*
X918450D01*
G01X915500Y480431D02*
X916150Y479781D01*
G01X915500Y481800D02*
Y480431D01*
G01X916030Y482330D02*
X915500Y481800D01*
G01X918400Y482330D02*
X916030D01*
G01X919100Y483030D02*
X918400Y482330D01*
G01X919100Y484330D02*
Y483030D01*
G01X918500Y484930D02*
X919100Y484330D01*
G01X917861Y484930D02*
X918500D01*
G01X917100Y485691D02*
X917861Y484930D01*
G01X917100Y487080D02*
Y485691D01*
G01X917900Y487880D02*
X917100Y487080D01*
G01X918600Y487880D02*
X917900D01*
G01X919100Y488380D02*
X918600Y487880D01*
G01X919100Y493700D02*
Y488380D01*
G01X918600Y494200D02*
X919100Y493700D01*
G01X917473Y494200D02*
X918600D01*
G01X917192Y493919D02*
X917473Y494200D01*
G01X948674Y493713D02*
X947443Y494944D01*
G01X948674Y489326D02*
Y493713D01*
G01X949848Y488152D02*
X948674Y489326D01*
G01X963976Y523900D02*
X963978D01*
G01X963976Y520623D02*
Y523900D01*
G01X965900Y518699D02*
X963976Y520623D01*
G01X965900Y517242D02*
Y518699D01*
G01X965200Y516542D02*
X965900Y517242D01*
G01X965200Y514600D02*
Y516542D01*
G01X967750Y512050D02*
X965200Y514600D01*
G01X968150Y512050D02*
X967750D01*
G01X969900Y510300D02*
X968150Y512050D01*
G01X969900Y509800D02*
Y510300D01*
G01X974800Y504900D02*
X969900Y509800D01*
G01X970669Y523923D02*
Y529014D01*
G01X970671Y523900D02*
X970669Y523923D01*
G01Y516025D02*
Y518157D01*
G01X976350Y510344D02*
X970669Y516025D01*
G01X927165Y523923D02*
Y528899D01*
G01X927167Y523900D02*
X927165Y523923D01*
G01X954000Y493500D02*
Y494700D01*
G01X955037Y492463D02*
X954000Y493500D01*
G01X955037Y469888D02*
Y492463D01*
G01X955687Y469238D02*
X955037Y469888D01*
G01X957037Y469238D02*
X955687D01*
G01X957687Y469888D02*
X957037Y469238D01*
G01X957687Y479500D02*
Y469888D01*
G01X958187Y480000D02*
X957687Y479500D01*
G01X959837Y480000D02*
X958187D01*
G01X960337Y479500D02*
X959837Y480000D01*
G01X921455Y498644D02*
X920700D01*
G01X922500Y497599D02*
X921455Y498644D01*
G01X922500Y495201D02*
Y497599D01*
G01X921700Y494401D02*
X922500Y495201D01*
G01X921700Y490500D02*
Y494401D01*
G01X922424Y489776D02*
X921700Y490500D01*
G01X911800Y493744D02*
X910432D01*
G01X912300Y493244D02*
X911800Y493744D01*
G01X912300Y489300D02*
Y493244D01*
G01X910193Y484376D02*
Y487193D01*
G01X910395Y479022D02*
Y480332D01*
G01X910393Y473667D02*
Y474977D01*
G01X910395Y468148D02*
Y469596D01*
G01X931774Y491281D02*
X929811Y493244D01*
G01X931774Y489658D02*
Y491281D01*
G01X932628Y488804D02*
X931774Y489658D01*
G01X932628Y487242D02*
Y488804D01*
G01X931978Y486592D02*
X932628Y487242D01*
G01X931110Y486592D02*
X931978D01*
G01X930460Y485942D02*
X931110Y486592D01*
G01X930460Y484592D02*
Y485942D01*
G01X931110Y483942D02*
X930460Y484592D01*
G01X931978Y483942D02*
X931110D01*
G01X932628Y483292D02*
X931978Y483942D01*
G01X932628Y481942D02*
Y483292D01*
G01X931978Y481292D02*
X932628Y481942D01*
G01X931110Y481292D02*
X931978D01*
G01X930460Y480642D02*
X931110Y481292D01*
G01X930460Y479292D02*
Y480642D01*
G01X931110Y478642D02*
X930460Y479292D01*
G01X932174Y478642D02*
X931110D01*
G01X933100Y477716D02*
X932174Y478642D01*
G01X933100Y475995D02*
Y477716D01*
G01X932450Y475345D02*
X933100Y475995D01*
G01X931084Y475345D02*
X932450D01*
G01X930434Y474695D02*
X931084Y475345D01*
G01X930434Y473345D02*
Y474695D01*
G01X931084Y472695D02*
X930434Y473345D01*
G01X932526Y472695D02*
X931084D01*
G01X933201Y472020D02*
X932526Y472695D01*
G01X933201Y470670D02*
Y472020D01*
G01X932576Y470045D02*
X933201Y470670D01*
G01X931084Y470045D02*
X932576D01*
G01X930434Y469395D02*
X931084Y470045D01*
G01X930434Y468045D02*
Y469395D01*
G01X931084Y467395D02*
X930434Y468045D01*
G01X932450Y467395D02*
X931084D01*
G01X933175Y466670D02*
X932450Y467395D01*
G01X933175Y465320D02*
Y466670D01*
G01X920472Y523923D02*
Y528899D01*
G01X920474Y523900D02*
X920472Y523923D01*
G01X913779D02*
Y528899D01*
G01X913781Y523900D02*
X913779Y523923D01*
G01X947244Y572901D02*
X947243Y572900D01*
G01X947244Y574100D02*
Y572901D01*
G01X947764Y574620D02*
X947244Y574100D01*
G01X947764Y575480D02*
Y574620D01*
G01X947244Y576000D02*
X947764Y575480D01*
G01X947244Y579810D02*
Y576000D01*
G01X947246Y579810D02*
X947244D01*
G01X930511Y542033D02*
X929811Y534700D01*
G01X930513Y542010D02*
X930511Y542033D01*
G01X960629Y542010D02*
Y536957D01*
G01X960631Y542010D02*
X960629D01*
G01X953936Y573992D02*
Y572900D01*
G01X954454Y574510D02*
X953936Y573992D01*
G01X954454Y575390D02*
Y574510D01*
G01X953936Y575908D02*
X954454Y575390D01*
G01X953936Y579810D02*
Y575908D01*
G01X953939Y579810D02*
X953936D01*
G01X923818Y536792D02*
X923432Y534700D01*
G01X923818Y542010D02*
Y536792D01*
G01X923820Y542010D02*
X923818D01*
G01X910433Y535101D02*
X910432Y535100D01*
G01X910433Y536300D02*
Y535101D01*
G01X910953Y536820D02*
X910433Y536300D01*
G01X910953Y537680D02*
Y536820D01*
G01X910433Y538200D02*
X910953Y537680D01*
G01X910433Y542010D02*
Y538200D01*
G01X910435Y542010D02*
X910433D01*
G01X917125Y573992D02*
Y572900D01*
G01X917643Y574510D02*
X917125Y573992D01*
G01X917643Y575390D02*
Y574510D01*
G01X917125Y575908D02*
X917643Y575390D01*
G01X917125Y579810D02*
Y575908D01*
G01X917128Y579810D02*
X917125D01*
G01X920472Y561723D02*
Y566699D01*
G01X920474Y561700D02*
X920472Y561723D01*
G01X930511Y579833D02*
X929811Y572500D01*
G01X930513Y579810D02*
X930511Y579833D01*
G01X963976Y561723D02*
Y566814D01*
G01X963978Y561700D02*
X963976Y561723D01*
G01X917125Y536192D02*
Y535100D01*
G01X917643Y536710D02*
X917125Y536192D01*
G01X917643Y537590D02*
Y536710D01*
G01X917125Y538108D02*
X917643Y537590D01*
G01X917125Y542010D02*
Y538108D01*
G01X917128Y542010D02*
X917125D01*
G01X910433Y579810D02*
X910435D01*
G01X910433Y576000D02*
Y579810D01*
G01X910953Y575480D02*
X910433Y576000D01*
G01X910953Y574620D02*
Y575480D01*
G01X910433Y574100D02*
X910953Y574620D01*
G01X910433Y572901D02*
Y574100D01*
G01X910432Y572900D02*
X910433Y572901D01*
G01X970669Y561723D02*
Y566814D01*
G01X970671Y561700D02*
X970669Y561723D01*
G01X960629Y579810D02*
Y574757D01*
G01X960631Y579810D02*
X960629D01*
G01X913779Y561723D02*
Y566699D01*
G01X913781Y561700D02*
X913779Y561723D01*
G01X943897D02*
Y566699D01*
G01X943899Y561700D02*
X943897Y561723D01*
G01X947244Y535101D02*
X947243Y535100D01*
G01X947244Y536300D02*
Y535101D01*
G01X947764Y536820D02*
X947244Y536300D01*
G01X947764Y537680D02*
Y536820D01*
G01X947244Y538200D02*
X947764Y537680D01*
G01X947244Y542010D02*
Y538200D01*
G01X947246Y542010D02*
X947244D01*
G01X950590Y561723D02*
Y566699D01*
G01X950592Y561700D02*
X950590Y561723D01*
G01X923818Y574592D02*
X923432Y572500D01*
G01X923818Y579810D02*
Y574592D01*
G01X923820Y579810D02*
X923818D01*
G01X927165Y561723D02*
Y566699D01*
G01X927167Y561700D02*
X927165Y561723D01*
G01X953936Y542010D02*
X953939D01*
G01X953936Y538108D02*
Y542010D01*
G01X954454Y537590D02*
X953936Y538108D01*
G01X954454Y536710D02*
Y537590D01*
G01X953936Y536192D02*
X954454Y536710D01*
G01X953936Y535100D02*
Y536192D01*
G01X950590Y599523D02*
Y604499D01*
G01X950592Y599500D02*
X950590Y599523D01*
G01X920472D02*
Y604499D01*
G01X920474Y599500D02*
X920472Y599523D01*
G01X913779D02*
Y604499D01*
G01X913781Y599500D02*
X913779Y599523D01*
G01X960629Y617610D02*
X960631D01*
G01X960629Y609864D02*
Y617610D01*
G01X923818Y612392D02*
X923432Y610300D01*
G01X923818Y617610D02*
Y612392D01*
G01X923820Y617610D02*
X923818D01*
G01X927165Y599523D02*
Y604499D01*
G01X927167Y599500D02*
X927165Y599523D01*
G01X947244Y610701D02*
X947243Y610700D01*
G01X947244Y611500D02*
Y610701D01*
G01X947764Y612020D02*
X947244Y611500D01*
G01X947764Y612880D02*
Y612020D01*
G01X947244Y613400D02*
X947764Y612880D01*
G01X947244Y617610D02*
Y613400D01*
G01X947246Y617610D02*
X947244D01*
G01X970669Y599523D02*
Y607292D01*
G01X970671Y599500D02*
X970669Y599523D01*
G01X930511Y617633D02*
X929811Y610300D01*
G01X930513Y617610D02*
X930511Y617633D01*
G01X943897Y599523D02*
Y604499D01*
G01X943899Y599500D02*
X943897Y599523D01*
G01X963976D02*
Y607292D01*
G01X963978Y599500D02*
X963976Y599523D01*
G01X917125Y617610D02*
X917128D01*
G01X917125Y613708D02*
Y617610D01*
G01X917643Y613190D02*
X917125Y613708D01*
G01X917643Y612310D02*
Y613190D01*
G01X917125Y611792D02*
X917643Y612310D01*
G01X917125Y610700D02*
Y611792D01*
G01X910433Y610701D02*
X910432Y610700D01*
G01X910433Y611900D02*
Y610701D01*
G01X910953Y612420D02*
X910433Y611900D01*
G01X910953Y613280D02*
Y612420D01*
G01X910433Y613800D02*
X910953Y613280D01*
G01X910433Y617610D02*
Y613800D01*
G01X910435Y617610D02*
X910433D01*
G01X953936Y611792D02*
Y610700D01*
G01X954454Y612310D02*
X953936Y611792D01*
G01X954454Y613190D02*
Y612310D01*
G01X953936Y613708D02*
X954454Y613190D01*
G01X953936Y617610D02*
Y613708D01*
G01X953939Y617610D02*
X953936D01*
G01X997441Y3233D02*
Y-1743D01*
G01X997443Y3233D02*
X997441D01*
G01X1004133D02*
Y-1742D01*
G01X1004135Y3233D02*
X1004133D01*
G01X984055D02*
Y-1743D01*
G01X984057Y3233D02*
X984055D01*
G01X980708Y22923D02*
Y28014D01*
G01X980710Y22923D02*
X980708D01*
G01X984055Y28013D02*
X984054Y28014D01*
G01X984055Y22923D02*
Y28013D01*
G01X984057Y22923D02*
X984055D01*
G01X974015Y3233D02*
Y-4536D01*
G01X974017Y3233D02*
X974015D01*
G01X994094Y-14877D02*
Y-9786D01*
G01X994096Y-14877D02*
X994094D01*
G01X990748D02*
Y-7108D01*
G01X990750Y-14877D02*
X990748D01*
G01X994094Y3233D02*
Y-4536D01*
G01X994096Y3233D02*
X994094D01*
G01X990748Y22923D02*
Y28022D01*
G01X990750Y22923D02*
X990748D01*
G01X987401Y3233D02*
Y-4536D01*
G01X987403Y3233D02*
X987401D01*
G01X1004134Y-14876D02*
X1004135Y-14877D01*
G01X1004134Y-7108D02*
Y-14876D01*
G01X1004133Y22923D02*
Y28022D01*
G01X1004135Y22923D02*
X1004133D01*
G01X980708Y-14877D02*
Y-9786D01*
G01X980710Y-14877D02*
X980708D01*
G01X1000787Y22923D02*
Y28022D01*
G01X1000789Y22923D02*
X1000787D01*
G01X984055Y-14877D02*
Y-7108D01*
G01X984057Y-14877D02*
X984055D01*
G01X974015Y22923D02*
Y28014D01*
G01X974017Y22923D02*
X974015D01*
G01X994094D02*
Y28022D01*
G01X994096Y22923D02*
X994094D01*
G01X977362Y3233D02*
Y-1743D01*
G01X977364Y3233D02*
X977362D01*
G01X1000787Y-14877D02*
Y-9901D01*
G01X1000789Y-14877D02*
X1000787D01*
G01X974015D02*
Y-9901D01*
G01X974017Y-14877D02*
X974015D01*
G01X1004134Y36057D02*
Y35957D01*
G01X1004133Y36058D02*
X1004134Y36057D01*
G01X1004133Y41033D02*
Y36058D01*
G01X1004135Y41033D02*
X1004133D01*
G01X974015Y78833D02*
Y73757D01*
G01X974017Y78833D02*
X974015D01*
G01X993290Y89160D02*
X994094Y89964D01*
G01X992369Y89160D02*
X993290D01*
G01X991573Y89956D02*
X992369Y89160D01*
G01X991573Y91055D02*
Y89956D01*
G01X992900Y92382D02*
X991573Y91055D01*
G01X992900Y93627D02*
Y92382D01*
G01X995100Y95827D02*
X992900Y93627D01*
G01X994094Y60723D02*
Y65822D01*
G01X994096Y60723D02*
X994094D01*
G01X980708D02*
Y65814D01*
G01X980710Y60723D02*
X980708D01*
G01X994094Y41033D02*
Y35957D01*
G01X994096Y41033D02*
X994094D01*
G01X984055D02*
Y35957D01*
G01X984057Y41033D02*
X984055D01*
G01X1004023Y94785D02*
Y92757D01*
G01X1004133Y60723D02*
Y65822D01*
G01X1004135Y60723D02*
X1004133D01*
G01X987500Y93100D02*
Y113956D01*
G01X985400Y91000D02*
X987500Y93100D01*
G01X985400Y89300D02*
Y91000D01*
G01X987401Y87299D02*
X985400Y89300D01*
G01X987401Y84599D02*
Y87299D01*
G01Y78833D02*
Y73757D01*
G01X987403Y78833D02*
X987401D01*
G01X984055D02*
Y73757D01*
G01X984057Y78833D02*
X984055D01*
G01Y65813D02*
X984054Y65814D01*
G01X984055Y60723D02*
Y65813D01*
G01X984057Y60723D02*
X984055D01*
G01X990748D02*
Y65822D01*
G01X990750Y60723D02*
X990748D01*
G01Y94568D02*
Y92757D01*
G01X991398Y95218D02*
X990748Y94568D01*
G01X998374Y88325D02*
X997441Y87392D01*
G01X998374Y90674D02*
Y88325D01*
G01X999300Y91600D02*
X998374Y90674D01*
G01X999300Y108743D02*
Y91600D01*
G01X997441Y78833D02*
Y73757D01*
G01X997443Y78833D02*
X997441D01*
G01X977362Y41033D02*
Y35957D01*
G01X977364Y41033D02*
X977362D01*
G01X987401D02*
Y35957D01*
G01X987403Y41033D02*
X987401D01*
G01X974015D02*
Y35957D01*
G01X974017Y41033D02*
X974015D01*
G01X997441D02*
Y35957D01*
G01X997443Y41033D02*
X997441D01*
G01X1000787Y60723D02*
Y65822D01*
G01X1000789Y60723D02*
X1000787D01*
G01X1002248Y93890D02*
X1001285Y94853D01*
G01X1002248Y90521D02*
Y93890D01*
G01X1001691Y89964D02*
X1002248Y90521D01*
G01X1000787Y89964D02*
X1001691D01*
G01X974015Y94982D02*
Y89964D01*
G01Y60723D02*
Y65814D01*
G01X974017Y60723D02*
X974015D01*
G01X1004134Y73857D02*
Y73757D01*
G01X1004133Y73858D02*
X1004134Y73857D01*
G01X1004133Y78833D02*
Y73858D01*
G01X1004135Y78833D02*
X1004133D01*
G01X1005088Y87392D02*
X1004023D01*
G01X1005738Y88042D02*
X1005088Y87392D01*
G01X1005738Y88962D02*
Y88042D01*
G01X1005100Y89600D02*
X1005738Y88962D01*
G01X1005100Y90567D02*
Y89600D01*
G01X1005798Y91265D02*
X1005100Y90567D01*
G01X1005798Y93933D02*
Y91265D01*
G01X1006951Y95086D02*
X1005798Y93933D01*
G01X977362Y89804D02*
X985400Y97842D01*
G01X977362Y87392D02*
Y89804D01*
G01Y78833D02*
Y73757D01*
G01X977364Y78833D02*
X977362D01*
G01X995616Y93514D02*
X997200Y95098D01*
G01X995616Y92052D02*
Y93514D01*
G01X995919Y91749D02*
X995616Y92052D01*
G01X995919Y88719D02*
Y91749D01*
G01X994094Y86894D02*
X995919Y88719D01*
G01X994094Y84714D02*
Y86894D01*
G01Y78833D02*
Y73757D01*
G01X994096Y78833D02*
X994094D01*
G01X1030015Y107285D02*
Y181141D01*
G01X1033546Y103754D02*
X1030015Y107285D01*
G01X1044290Y93010D02*
X1033546Y103754D01*
G01X987700Y138156D02*
Y182563D01*
G01X986520Y136976D02*
X987700Y138156D01*
G01X985811Y136976D02*
X986520D01*
G01X984538Y138249D02*
X985811Y136976D01*
G01X983593Y138249D02*
X984538D01*
G01X982639Y137295D02*
X983593Y138249D01*
G01X982639Y136400D02*
Y137295D01*
G01X984315Y134724D02*
X982639Y136400D01*
G01X984315Y134015D02*
Y134724D01*
G01X972300Y122000D02*
X984315Y134015D01*
G01X972300Y113300D02*
Y122000D01*
G01X995100Y112669D02*
Y95827D01*
G01Y114492D02*
Y112669D01*
G01X997896Y117288D02*
X995100Y114492D01*
G01X997896Y118206D02*
Y117288D01*
G01X997009Y119093D02*
X997896Y118206D01*
G01X997009Y120012D02*
Y119093D01*
G01X997930Y120933D02*
X997009Y120012D01*
G01X998848Y120933D02*
X997930D01*
G01X999736Y120045D02*
X998848Y120933D01*
G01X1000653Y120045D02*
X999736D01*
G01X1001574Y120966D02*
X1000653Y120045D01*
G01X1001574Y121885D02*
Y120966D01*
G01X1000634Y122825D02*
X1001574Y121885D01*
G01X1000634Y123907D02*
Y122825D01*
G01X1001472Y124745D02*
X1000634Y123907D01*
G01X1002392Y124745D02*
X1001472D01*
G01X1003414Y123723D02*
X1002392Y124745D01*
G01X1004331Y123723D02*
X1003414D01*
G01X1005252Y124644D02*
X1004331Y123723D01*
G01X1005252Y125562D02*
Y124644D01*
G01X1004365Y126449D02*
X1005252Y125562D01*
G01X1004365Y127368D02*
Y126449D01*
G01X1005565Y128568D02*
X1004365Y127368D01*
G01X1005565Y185958D02*
Y128568D01*
G01X991670Y135371D02*
Y182619D01*
G01X976400Y120101D02*
X991670Y135371D01*
G01X976400Y110900D02*
Y120101D01*
G01X972825Y107325D02*
X976400Y110900D01*
G01X972800Y132750D02*
Y148000D01*
G01X1003322Y96478D02*
X1004023Y94785D01*
G01X1003322Y103936D02*
Y96478D01*
G01Y111479D02*
Y103936D01*
G01X1013505Y121662D02*
X1003322Y111479D01*
G01X1013505Y188142D02*
Y121662D01*
G01X1001595Y130485D02*
Y186312D01*
G01X987500Y116390D02*
X1001595Y130485D01*
G01X987500Y113956D02*
Y116390D01*
G01X1003580Y186457D02*
Y138417D01*
G01X991952Y95218D02*
X991398D01*
G01X992784Y96050D02*
X991952Y95218D01*
G01X992784Y97191D02*
Y96050D01*
G01X992046Y97929D02*
X992784Y97191D01*
G01X990011Y97929D02*
X992046D01*
G01X989511Y98429D02*
X990011Y97929D01*
G01X989511Y99807D02*
Y98429D01*
G01X990208Y100504D02*
X989511Y99807D01*
G01X992394Y100504D02*
X990208D01*
G01X993044Y101154D02*
X992394Y100504D01*
G01X993044Y102454D02*
Y101154D01*
G01X992394Y103104D02*
X993044Y102454D01*
G01X990384Y103104D02*
X992394D01*
G01X989809Y103679D02*
X990384Y103104D01*
G01X989809Y104979D02*
Y103679D01*
G01X990534Y105704D02*
X989809Y104979D01*
G01X992333Y105704D02*
X990534D01*
G01X992983Y106354D02*
X992333Y105704D01*
G01X992983Y107614D02*
Y106354D01*
G01X992275Y108322D02*
X992983Y107614D01*
G01X989985Y108322D02*
X992275D01*
G01X989485Y108822D02*
X989985Y108322D01*
G01X989485Y110258D02*
Y108822D01*
G01X990135Y110908D02*
X989485Y110258D01*
G01X991491Y110908D02*
X990135D01*
G01X992126Y111543D02*
X991491Y110908D01*
G01X992126Y112893D02*
Y111543D01*
G01X991461Y113558D02*
X992126Y112893D01*
G01X990444Y113558D02*
X991461D01*
G01X989838Y114164D02*
X990444Y113558D01*
G01X989838Y115920D02*
Y114164D01*
G01X1003580Y129662D02*
X989838Y115920D01*
G01X1003580Y138417D02*
Y129662D01*
G01X999300Y113075D02*
Y108743D01*
G01X1009535Y123310D02*
X999300Y113075D01*
G01X1009535Y189913D02*
Y123310D01*
G01X1032000Y110422D02*
Y180801D01*
G01Y108201D02*
Y110422D01*
G01X1045797Y94404D02*
X1032000Y108201D01*
G01X981200Y118979D02*
Y115148D01*
G01X995640Y133419D02*
X981200Y118979D01*
G01X995640Y186625D02*
Y133419D01*
G01X975500Y99000D02*
X973400D01*
G01X981200Y104700D02*
X975500Y99000D01*
G01X981200Y115148D02*
Y104700D01*
G01X974300Y112300D02*
Y115182D01*
G01X989685Y136385D02*
Y182436D01*
G01X974300Y121000D02*
X989685Y136385D01*
G01X974300Y115182D02*
Y121000D01*
G01X979181Y105502D02*
X976700Y103021D01*
G01X979181Y107022D02*
Y105502D01*
G01Y119923D02*
Y107022D01*
G01X993655Y134397D02*
X979181Y119923D01*
G01X993655Y186736D02*
Y134397D01*
G01X1011520Y122486D02*
Y188639D01*
G01X1004250Y115216D02*
X1011520Y122486D01*
G01X1001285Y112251D02*
X1004250Y115216D01*
G01X1001285Y94853D02*
Y112251D01*
G01X975025Y95992D02*
X974015Y94982D01*
G01X976366Y95992D02*
X975025D01*
G01X977212Y95146D02*
X976366Y95992D01*
G01X977920Y95146D02*
X977212D01*
G01X979051Y96277D02*
X977920Y95146D01*
G01X979051Y96985D02*
Y96277D01*
G01X978176Y97860D02*
X979051Y96985D01*
G01X978176Y98780D02*
Y97860D01*
G01X979095Y99699D02*
X978176Y98780D01*
G01X980015Y99699D02*
X979095D01*
G01X981039Y98675D02*
X980015Y99699D01*
G01X981747Y98675D02*
X981039D01*
G01X982878Y99806D02*
X981747Y98675D01*
G01X982878Y100514D02*
Y99806D01*
G01X981854Y101538D02*
X982878Y100514D01*
G01X981854Y102458D02*
Y101538D01*
G01X983300Y103904D02*
X981854Y102458D01*
G01X983300Y110390D02*
Y103904D01*
G01Y118116D02*
Y110390D01*
G01X997625Y132441D02*
X983300Y118116D01*
G01X997625Y186310D02*
Y132441D01*
G01X1006951Y97014D02*
Y95086D01*
G01X1005307Y98658D02*
X1006951Y97014D01*
G01X1005307Y100129D02*
Y98658D01*
G01X1005957Y100779D02*
X1005307Y100129D01*
G01X1006365Y100779D02*
X1005957D01*
G01X1007015Y101429D02*
X1006365Y100779D01*
G01X1007015Y102779D02*
Y101429D01*
G01X1006365Y103429D02*
X1007015Y102779D01*
G01X1005957Y103429D02*
X1006365D01*
G01X1005307Y104079D02*
X1005957Y103429D01*
G01X1005307Y105429D02*
Y104079D01*
G01X1005957Y106079D02*
X1005307Y105429D01*
G01X1006590Y106079D02*
X1005957D01*
G01X1007090Y106579D02*
X1006590Y106079D01*
G01X1007090Y108229D02*
Y106579D01*
G01X1006590Y108729D02*
X1007090Y108229D01*
G01X1005957Y108729D02*
X1006590D01*
G01X1005307Y109379D02*
X1005957Y108729D01*
G01X1005307Y110656D02*
Y109379D01*
G01X1015490Y120839D02*
X1005307Y110656D01*
G01X1015490Y188215D02*
Y120839D01*
G01X985400Y97842D02*
Y104069D01*
G01X999610Y131463D02*
Y186360D01*
G01X985400Y117253D02*
X999610Y131463D01*
G01X985400Y104069D02*
Y117253D01*
G01X997200Y95098D02*
Y103793D01*
G01X1007550Y124134D02*
Y189634D01*
G01X997200Y113784D02*
X1007550Y124134D01*
G01X997200Y103793D02*
Y113784D01*
G01X990696Y210239D02*
X991826Y209109D01*
G01X990696Y211060D02*
Y210239D01*
G01X1025625Y213009D02*
X1027875D01*
G01X997456Y230559D02*
X995206D01*
G01X1027875Y228610D02*
X1025625D01*
G01X994076Y224709D02*
X991826D01*
G01X1031255Y234460D02*
X1029005D01*
G01X977176Y331960D02*
X974926D01*
G01X994076Y337809D02*
X991826D01*
G01X990696Y335860D02*
X988446D01*
G01X983936D02*
X981686D01*
G01X977176Y328060D02*
X974926D01*
G01X991508Y396309D02*
X991500Y396301D01*
G01X994076Y396309D02*
X991508D01*
G01X983936Y359260D02*
X981686D01*
G01X977176Y351460D02*
X974926D01*
G01X994076Y341709D02*
X991826D01*
G01X987316Y357309D02*
X985066D01*
G01X990604Y402882D02*
Y447473D01*
G01X1000836Y380709D02*
X998586D01*
G01X997456Y386560D02*
X995206D01*
G01X1025625Y384609D02*
X1027875D01*
G01X992699Y402909D02*
Y449049D01*
G01X1000836Y392410D02*
X998586Y388509D01*
G01X997456Y378760D02*
X995206D01*
G01X990696Y343660D02*
X988446D01*
G01X1000836Y402764D02*
X1000800Y402800D01*
G01X1000836Y400209D02*
Y402764D01*
G01X1022245Y390460D02*
X1024495D01*
G01X997456Y355360D02*
X995206D01*
G01X994076Y380709D02*
X991826D01*
G01X1000836Y357309D02*
X998586D01*
G01X1027875Y369010D02*
X1025625D01*
G01X980556Y341709D02*
X978306D01*
G01X983936Y351460D02*
X981686D01*
G01X983936Y343660D02*
X981686D01*
G01X977176Y359260D02*
X974926D01*
G01X1022245Y386560D02*
X1024495D01*
G01X987316Y353409D02*
X985066D01*
G01X1011752Y457319D02*
X996887Y472184D01*
G01X1011752Y410009D02*
Y457319D01*
G01X1009657Y456451D02*
X994734Y471374D01*
G01X1009657Y409566D02*
Y456451D01*
G01X994992Y450211D02*
X976530Y468673D01*
G01X994992Y403714D02*
Y450211D01*
G01X1013847Y458094D02*
Y410143D01*
G01X998872Y473069D02*
X1013847Y458094D01*
G01X990604Y447473D02*
X972294Y465783D01*
G01X1005467Y454367D02*
X990629Y469205D01*
G01X1005467Y408774D02*
Y454367D01*
G01X1018037Y459994D02*
X1004981Y473050D01*
G01X1018037Y410774D02*
Y459994D01*
G01X1003372Y453532D02*
X988049Y468855D01*
G01X1003372Y408372D02*
Y453532D01*
G01X992699Y449049D02*
X974392Y467356D01*
G01X1001277Y452727D02*
X983538Y470466D01*
G01X1001277Y407377D02*
Y452727D01*
G01X997087Y451016D02*
X979338Y468765D01*
G01X997087Y405432D02*
Y451016D01*
G01X999182Y451922D02*
X981438Y469666D01*
G01X999182Y406130D02*
Y451922D01*
G01X1033375Y410585D02*
Y497821D01*
G01X1007562Y455549D02*
X992664Y470447D01*
G01X1007562Y408976D02*
Y455549D01*
G01X1015942Y458934D02*
X1001273Y473603D01*
G01X1015942Y410519D02*
Y458934D01*
G01X996887Y512238D02*
X997441Y512792D01*
G01X996887Y472184D02*
Y512238D01*
G01X994734Y509474D02*
X994094Y510114D01*
G01X994734Y471374D02*
Y509474D01*
G01X976530Y468673D02*
Y497170D01*
G01X1000787Y523923D02*
Y529022D01*
G01X1000789Y523900D02*
X1000787Y523923D01*
G01X998872Y508697D02*
Y473069D01*
G01X998635Y508934D02*
X998872Y508697D01*
G01X998635Y511275D02*
Y508934D01*
G01X999654Y512294D02*
X998635Y511275D01*
G01X999654Y514231D02*
Y512294D01*
G01X1000787Y515364D02*
X999654Y514231D01*
G01X972294Y465783D02*
Y493948D01*
G01X990748Y523923D02*
Y529022D01*
G01X990750Y523900D02*
X990748Y523923D01*
G01Y515527D02*
Y518157D01*
G01X988900Y513679D02*
X990748Y515527D01*
G01X988900Y511400D02*
Y513679D01*
G01X989800Y510500D02*
X988900Y511400D01*
G01X989800Y496400D02*
Y510500D01*
G01X990629Y495571D02*
X989800Y496400D01*
G01X990629Y469205D02*
Y495571D01*
G01X1003915Y506766D02*
Y512792D01*
G01X1004416Y506265D02*
X1003915Y506766D01*
G01X1004416Y499770D02*
Y506265D01*
G01X1003347Y498701D02*
X1004416Y499770D01*
G01X1003347Y494543D02*
Y498701D01*
G01X1004602Y493288D02*
X1003347Y494543D01*
G01X1004602Y489168D02*
Y493288D01*
G01X1003347Y487913D02*
X1004602Y489168D01*
G01X1003347Y484273D02*
Y487913D01*
G01X1004981Y482639D02*
X1003347Y484273D01*
G01X1004981Y473050D02*
Y482639D01*
G01X987401Y495330D02*
Y509999D01*
G01X988591Y494140D02*
X987401Y495330D01*
G01X988591Y491135D02*
Y494140D01*
G01X987585Y490129D02*
X988591Y491135D01*
G01X987021Y490129D02*
X987585D01*
G01X986371Y489479D02*
X987021Y490129D01*
G01X986371Y488129D02*
Y489479D01*
G01X987021Y487479D02*
X986371Y488129D01*
G01X987971Y487479D02*
X987021D01*
G01X988621Y486829D02*
X987971Y487479D01*
G01X988621Y485479D02*
Y486829D01*
G01X987971Y484829D02*
X988621Y485479D01*
G01X986774Y484829D02*
X987971D01*
G01X986124Y484179D02*
X986774Y484829D01*
G01X986124Y482830D02*
Y484179D01*
G01X986775Y482179D02*
X986124Y482830D01*
G01X987971Y482179D02*
X986775D01*
G01X988621Y481529D02*
X987971Y482179D01*
G01X988621Y480104D02*
Y481529D01*
G01X987971Y479454D02*
X988621Y480104D01*
G01X987246Y479454D02*
X987971D01*
G01X986596Y478804D02*
X987246Y479454D01*
G01X986596Y477454D02*
Y478804D01*
G01X987246Y476804D02*
X986596Y477454D01*
G01X987971Y476804D02*
X987246D01*
G01X988621Y476154D02*
X987971Y476804D01*
G01X988621Y474804D02*
Y476154D01*
G01X988049Y474232D02*
X988621Y474804D01*
G01X988049Y468855D02*
Y474232D01*
G01X974392Y467356D02*
Y494890D01*
G01X984055Y523923D02*
Y529013D01*
G01X984057Y523900D02*
X984055Y523923D01*
G01X974015D02*
Y529014D01*
G01X974017Y523900D02*
X974015Y523923D01*
G01X977360Y515364D02*
X974015D01*
G01X979254Y513470D02*
X977360Y515364D01*
G01X979254Y511654D02*
Y513470D01*
G01X978700Y511100D02*
X979254Y511654D01*
G01X978700Y509400D02*
Y511100D01*
G01X979838Y508262D02*
X978700Y509400D01*
G01X982999Y508262D02*
X979838D01*
G01X984447Y506814D02*
X982999Y508262D01*
G01X984447Y504643D02*
Y506814D01*
G01X983538Y503734D02*
X984447Y504643D01*
G01X983538Y494655D02*
Y503734D01*
G01X984188Y494005D02*
X983538Y494655D01*
G01X985387Y494005D02*
X984188D01*
G01X986021Y493371D02*
X985387Y494005D01*
G01X986021Y492021D02*
Y493371D01*
G01X985355Y491355D02*
X986021Y492021D01*
G01X984188Y491355D02*
X985355D01*
G01X983538Y490705D02*
X984188Y491355D01*
G01X983538Y476107D02*
Y490705D01*
G01X984188Y475457D02*
X983538Y476107D01*
G01X985154Y475457D02*
X984188D01*
G01X985820Y474791D02*
X985154Y475457D01*
G01X985820Y473441D02*
Y474791D01*
G01X985186Y472807D02*
X985820Y473441D01*
G01X984188Y472807D02*
X985186D01*
G01X983538Y472157D02*
X984188Y472807D01*
G01X983538Y470466D02*
Y472157D01*
G01X980708Y523923D02*
Y529014D01*
G01X980710Y523900D02*
X980708Y523923D01*
G01X979338Y468765D02*
Y490843D01*
G01X976500Y504900D02*
X974800D01*
G01X979338Y502062D02*
X976500Y504900D01*
G01X979338Y490843D02*
Y502062D01*
G01X976350Y508250D02*
Y510344D01*
G01X981438Y503162D02*
X976350Y508250D01*
G01X981438Y469666D02*
Y503162D01*
G01X1033375Y497821D02*
X1038618Y503064D01*
G01X994094Y523923D02*
Y529022D01*
G01X994096Y523900D02*
X994094Y523923D01*
G01X994555Y514903D02*
X994094Y515364D01*
G01X994555Y513455D02*
Y514903D01*
G01X991964Y510864D02*
X994555Y513455D01*
G01X991964Y508534D02*
Y510864D01*
G01X992664Y507834D02*
X991964Y508534D01*
G01X992664Y505704D02*
Y507834D01*
G01X991721Y504761D02*
X992664Y505704D01*
G01X991721Y503054D02*
Y504761D01*
G01X992664Y502111D02*
X991721Y503054D01*
G01X992664Y500404D02*
Y502111D01*
G01X991834Y499574D02*
X992664Y500404D01*
G01X991834Y497641D02*
Y499574D01*
G01X992664Y496811D02*
X991834Y497641D01*
G01X992664Y470447D02*
Y496811D01*
G01X1004133Y523923D02*
Y529022D01*
G01X1004135Y523900D02*
X1004133Y523923D01*
G01X1002782Y516805D02*
X1004134Y518157D01*
G01X1002782Y514606D02*
Y516805D01*
G01X1001830Y513654D02*
X1002782Y514606D01*
G01X1001830Y511970D02*
Y513654D01*
G01X1002265Y511535D02*
X1001830Y511970D01*
G01X1002265Y508327D02*
Y511535D01*
G01X1001303Y507365D02*
X1002265Y508327D01*
G01X1001303Y504862D02*
Y507365D01*
G01X1002700Y503465D02*
X1001303Y504862D01*
G01X1002700Y501172D02*
Y503465D01*
G01X1001273Y499745D02*
X1002700Y501172D01*
G01X1001273Y473603D02*
Y499745D01*
G01X994094Y561723D02*
Y566822D01*
G01X994096Y561700D02*
X994094Y561723D01*
G01X997441Y542010D02*
X997443D01*
G01X997441Y536957D02*
Y542010D01*
G01X977362D02*
Y536957D01*
G01X977364Y542010D02*
X977362D01*
G01X994094D02*
Y536957D01*
G01X994096Y542010D02*
X994094D01*
G01X984055Y566813D02*
X984054Y566814D01*
G01X984055Y561723D02*
Y566813D01*
G01X984057Y561700D02*
X984055Y561723D01*
G01X1004134Y574857D02*
Y574757D01*
G01X1004133Y574858D02*
X1004134Y574857D01*
G01X1004133Y579810D02*
Y574858D01*
G01X1004135Y579810D02*
X1004133D01*
G01X977362D02*
Y574757D01*
G01X977364Y579810D02*
X977362D01*
G01X987401D02*
Y574757D01*
G01X987403Y579810D02*
X987401D01*
G01X974015Y542010D02*
Y536957D01*
G01X974017Y542010D02*
X974015D01*
G01X1000787Y561723D02*
Y566822D01*
G01X1000789Y561700D02*
X1000787Y561723D01*
G01X1004134Y537057D02*
Y536957D01*
G01X1004133Y537058D02*
X1004134Y537057D01*
G01X1004133Y542010D02*
Y537058D01*
G01X1004135Y542010D02*
X1004133D01*
G01X987401D02*
X987403D01*
G01X987401Y536957D02*
Y542010D01*
G01X984055D02*
X984057D01*
G01X984055Y536957D02*
Y542010D01*
G01Y529013D02*
X984054Y529014D01*
G01X994094Y579810D02*
Y574757D01*
G01X994096Y579810D02*
X994094D01*
G01X980708Y561723D02*
Y566814D01*
G01X980710Y561700D02*
X980708Y561723D01*
G01X997441Y579810D02*
Y574757D01*
G01X997443Y579810D02*
X997441D01*
G01X974015D02*
Y574757D01*
G01X974017Y579810D02*
X974015D01*
G01X984055D02*
Y574757D01*
G01X984057Y579810D02*
X984055D01*
G01X990748Y561723D02*
Y566822D01*
G01X990750Y561700D02*
X990748Y561723D01*
G01X974015D02*
Y566814D01*
G01X974017Y561700D02*
X974015Y561723D01*
G01X1004133D02*
Y566822D01*
G01X1004135Y561700D02*
X1004133Y561723D01*
G01Y617610D02*
X1004135D01*
G01X1004133Y612358D02*
Y617610D01*
G01X1004134Y599524D02*
Y607292D01*
G01X1004133Y599523D02*
X1004134Y599524D01*
G01X1004135Y599500D02*
X1004133Y599523D01*
G01X994094D02*
Y604614D01*
G01X994096Y599500D02*
X994094Y599523D01*
G01X984055D02*
Y607292D01*
G01X984057Y599500D02*
X984055Y599523D01*
G01X994094Y617610D02*
X994096D01*
G01X994094Y609864D02*
Y617610D01*
G01X997441D02*
X997443D01*
G01X997441Y612357D02*
Y617610D01*
G01X990748Y599523D02*
Y607292D01*
G01X990750Y599500D02*
X990748Y599523D01*
G01X1000787D02*
Y604499D01*
G01X1000789Y599500D02*
X1000787Y599523D01*
G01X977362Y617610D02*
Y612457D01*
G01X977364Y617610D02*
X977362D01*
G01X980708Y599523D02*
Y604614D01*
G01X980710Y599500D02*
X980708Y599523D01*
G01X984055Y617610D02*
X984057D01*
G01X984055Y612457D02*
Y617610D01*
G01X974015Y599523D02*
Y604499D01*
G01X974017Y599500D02*
X974015Y599523D01*
G01Y617610D02*
X974017D01*
G01X974015Y609864D02*
Y617610D01*
G01X987401D02*
X987403D01*
G01X987401Y609864D02*
Y617610D01*
G01X1081102Y-14877D02*
Y-9901D01*
G01X1081104Y-14877D02*
X1081102D01*
G01X1094488D02*
Y-9786D01*
G01X1094490Y-14877D02*
X1094488D01*
G01X1077755Y3233D02*
Y-1743D01*
G01X1077757Y3233D02*
X1077755D01*
G01X1057677Y22923D02*
Y28007D01*
G01X1057679Y22923D02*
X1057677D01*
G01X1087795Y28020D02*
X1087797Y28022D01*
G01X1087795Y22923D02*
Y28020D01*
G01X1087797Y22923D02*
X1087795D01*
G01X1054330Y-14877D02*
Y-9901D01*
G01X1054332Y-14877D02*
X1054330D01*
G01X1050984Y-1742D02*
X1050983Y-1743D01*
G01X1050984Y3233D02*
Y-1742D01*
G01X1050986Y3233D02*
X1050984D01*
G01X1071063Y28021D02*
X1071064Y28022D01*
G01X1071063Y22923D02*
Y28021D01*
G01X1071065Y22923D02*
X1071063D01*
G01X1087795Y3233D02*
Y-4536D01*
G01X1087797Y3233D02*
X1087795D01*
G01X1094488D02*
Y-4536D01*
G01X1094490Y3233D02*
X1094488D01*
G01X1047637Y-14877D02*
Y-9901D01*
G01X1047639Y-14877D02*
X1047637D01*
G01X1087795D02*
Y-9786D01*
G01X1087797Y-14877D02*
X1087795D01*
G01X1074409Y22923D02*
Y28007D01*
G01X1074411Y22923D02*
X1074409D01*
G01X1084448Y3233D02*
Y-1743D01*
G01X1084450Y3233D02*
X1084448D01*
G01X1071065Y-7111D02*
X1071062Y-7108D01*
G01X1071065Y-14877D02*
Y-7111D01*
G01X1081102Y22923D02*
Y28007D01*
G01X1081104Y22923D02*
X1081102D01*
G01X1047637D02*
Y28007D01*
G01X1047639Y22923D02*
X1047637D01*
G01X1044291Y3233D02*
Y-2200D01*
G01X1044293Y3233D02*
X1044291D01*
G01X1054330Y28021D02*
X1054331Y28022D01*
G01X1054330Y22923D02*
Y28021D01*
G01X1054332Y22923D02*
X1054330D01*
G01X1064370Y-7109D02*
X1064369Y-7108D01*
G01X1064370Y-14877D02*
Y-7109D01*
G01X1064372Y-14877D02*
X1064370D01*
G01Y-1742D02*
X1064369Y-1743D01*
G01X1064370Y3233D02*
Y-1742D01*
G01X1064372Y3233D02*
X1064370D01*
G01X1057677Y-7109D02*
X1057676Y-7108D01*
G01X1057677Y-14877D02*
Y-7109D01*
G01X1057679Y-14877D02*
X1057677D01*
G01X1064370Y28021D02*
X1064371Y28022D01*
G01X1064370Y22923D02*
Y28021D01*
G01X1064372Y22923D02*
X1064370D01*
G01X1054330Y3233D02*
Y-4536D01*
G01X1054332Y3233D02*
X1054330D01*
G01X1074409Y-14877D02*
Y-9786D01*
G01X1074411Y-14877D02*
X1074409D01*
G01X1094488Y22923D02*
Y28022D01*
G01X1094490Y22923D02*
X1094488D01*
G01X1054330Y73758D02*
X1054331Y73757D01*
G01X1054330Y78833D02*
Y73758D01*
G01X1054332Y78833D02*
X1054330D01*
G01X1064370Y65821D02*
X1064371Y65822D01*
G01X1064370Y60723D02*
Y65821D01*
G01X1064372Y60723D02*
X1064370D01*
G01X1094488D02*
Y65822D01*
G01X1094490Y60723D02*
X1094488D01*
G01X1077755Y73759D02*
X1077757Y73757D01*
G01X1077755Y78833D02*
Y73759D01*
G01X1077757Y78833D02*
X1077755D01*
G01X1044291Y87391D02*
X1044290Y87392D01*
G01X1044291Y78833D02*
Y87391D01*
G01X1044293Y78833D02*
X1044291D01*
G01X1044290Y87392D02*
Y93010D01*
G01X1054330Y65821D02*
X1054331Y65822D01*
G01X1054330Y60723D02*
Y65821D01*
G01X1054332Y60723D02*
X1054330D01*
G01X1048972Y94128D02*
X1042800Y100300D01*
G01X1048972Y91412D02*
Y94128D01*
G01X1051126Y89258D02*
X1048972Y91412D01*
G01X1053624Y89258D02*
X1051126D01*
G01X1054330Y89964D02*
X1053624Y89258D01*
G01X1086300Y91459D02*
X1087795Y89964D01*
G01X1086300Y93900D02*
Y91459D01*
G01X1079900Y100300D02*
X1086300Y93900D01*
G01X1062900Y91288D02*
X1064369Y92757D01*
G01X1062900Y88710D02*
Y91288D01*
G01X1061572Y87382D02*
X1062900Y88710D01*
G01X1060474Y87382D02*
X1061572D01*
G01X1058516Y89340D02*
X1060474Y87382D01*
G01X1058516Y90516D02*
Y89340D01*
G01X1060214Y92214D02*
X1058516Y90516D01*
G01X1060214Y93714D02*
Y92214D01*
G01X1061600Y95100D02*
X1060214Y93714D01*
G01X1074409Y92711D02*
X1071481Y95639D01*
G01X1074409Y89964D02*
Y92711D01*
G01X1044292Y36057D02*
Y35957D01*
G01X1044291Y36058D02*
X1044292Y36057D01*
G01X1044291Y41033D02*
Y36058D01*
G01X1044293Y41033D02*
X1044291D01*
G01X1084448Y35959D02*
X1084450Y35957D01*
G01X1084448Y41033D02*
Y35959D01*
G01X1084450Y41033D02*
X1084448D01*
G01X1089200Y93900D02*
X1081732Y101368D01*
G01X1089200Y91700D02*
Y93900D01*
G01X1091700Y89200D02*
X1089200Y91700D01*
G01X1092000Y89200D02*
X1091700D01*
G01X1093000Y88200D02*
X1092000Y89200D01*
G01X1093000Y86500D02*
Y88200D01*
G01X1092400Y85900D02*
X1093000Y86500D01*
G01X1092400Y83901D02*
Y85900D01*
G01X1094488Y81813D02*
X1092400Y83901D01*
G01X1094488Y78833D02*
Y81813D01*
G01X1094490Y78833D02*
X1094488D01*
G01X1047637Y60723D02*
Y65807D01*
G01X1047639Y60723D02*
X1047637D01*
G01Y89964D02*
X1045797Y94404D01*
G01X1081102Y60723D02*
Y65807D01*
G01X1081104Y60723D02*
X1081102D01*
G01X1084448Y73759D02*
X1084450Y73757D01*
G01X1084448Y78833D02*
Y73759D01*
G01X1084450Y78833D02*
X1084448D01*
G01X1050984Y35958D02*
X1050985Y35957D01*
G01X1050984Y41033D02*
Y35958D01*
G01X1050986Y41033D02*
X1050984D01*
G01X1057677Y60723D02*
Y65807D01*
G01X1057679Y60723D02*
X1057677D01*
G01X1052607Y93693D02*
Y94712D01*
G01X1054298Y92002D02*
X1052607Y93693D01*
G01X1056921Y92002D02*
X1054298D01*
G01X1057676Y92757D02*
X1056921Y92002D01*
G01X1074409Y60723D02*
Y65807D01*
G01X1074411Y60723D02*
X1074409D01*
G01X1054331Y36057D02*
Y35957D01*
G01X1054330Y36058D02*
X1054331Y36057D01*
G01X1054330Y41033D02*
Y36058D01*
G01X1054332Y41033D02*
X1054330D01*
G01X1077755Y35959D02*
X1077757Y35957D01*
G01X1077755Y41033D02*
Y35959D01*
G01X1077757Y41033D02*
X1077755D01*
G01X1071063Y65821D02*
X1071064Y65822D01*
G01X1071063Y60723D02*
Y65821D01*
G01X1071065Y60723D02*
X1071063D01*
G01X1095601Y85827D02*
X1094488Y84714D01*
G01X1093700Y90752D02*
X1094488Y89964D01*
G01X1093700Y97980D02*
Y90752D01*
G01X1094488Y35959D02*
X1094490Y35957D01*
G01X1094488Y41033D02*
Y35959D01*
G01X1094490Y41033D02*
X1094488D01*
G01X1080000Y93000D02*
Y97301D01*
G01X1081102Y91898D02*
X1080000Y93000D01*
G01X1081102Y89964D02*
Y91898D01*
G01X1064370Y35958D02*
X1064371Y35957D01*
G01X1064370Y41033D02*
Y35958D01*
G01X1064372Y41033D02*
X1064370D01*
G01X1087795Y65820D02*
X1087797Y65822D01*
G01X1087795Y60723D02*
Y65820D01*
G01X1087797Y60723D02*
X1087795D01*
G01X1064370Y73758D02*
X1064371Y73757D01*
G01X1064370Y78833D02*
Y73758D01*
G01X1064372Y78833D02*
X1064370D01*
G01X1065900Y88923D02*
X1064369Y87392D01*
G01X1065900Y91100D02*
Y88923D01*
G01X1066621Y91821D02*
X1065900Y91100D01*
G01X1066621Y94315D02*
Y91821D01*
G01X1061253Y99683D02*
X1066621Y94315D01*
G01X1050984Y73758D02*
X1050985Y73757D01*
G01X1050984Y78833D02*
Y73758D01*
G01X1050986Y78833D02*
X1050984D01*
G01X1073182Y146943D02*
Y158900D01*
G01X1102952Y117173D02*
X1073182Y146943D01*
G01X1048016Y106083D02*
X1050983Y103116D01*
G01X1045292Y108807D02*
X1048016Y106083D01*
G01X1042157Y113499D02*
X1045292Y108807D01*
G01X1037955Y119788D02*
X1042157Y113499D01*
G01X1037955Y179613D02*
Y119788D01*
G01X1055820Y129824D02*
X1074425Y111219D01*
G01X1055820Y190701D02*
Y129824D01*
G01X1079136Y104932D02*
X1077304Y103100D01*
G01X1079136Y106508D02*
Y104932D01*
G01X1074425Y111219D02*
X1079136Y106508D01*
G01X1068144Y144461D02*
Y159100D01*
G01X1078300Y134305D02*
X1068144Y144461D01*
G01X1078300Y126695D02*
Y134305D01*
G01X1103750Y101245D02*
X1078300Y126695D01*
G01X1033985Y115181D02*
Y180486D01*
G01Y109115D02*
Y115181D01*
G01X1040162Y102938D02*
X1033985Y109115D01*
G01X1041762Y102938D02*
X1040162D01*
G01X1042800Y101900D02*
X1041762Y102938D01*
G01X1042800Y100300D02*
Y101900D01*
G01X1077300Y100300D02*
X1079900D01*
G01X1075100Y102500D02*
X1077300Y100300D01*
G01X1075100Y104812D02*
Y102500D01*
G01Y107313D02*
Y104812D01*
G01X1053835Y128578D02*
X1075100Y107313D01*
G01X1053835Y189513D02*
Y128578D01*
G01X1088077Y157269D02*
X1126453Y118893D01*
G01X1039940Y120753D02*
X1045884Y114809D01*
G01X1039940Y186892D02*
Y120753D01*
G01X1061600Y96168D02*
Y95100D01*
G01X1060443Y97325D02*
X1061600Y96168D01*
G01X1059255Y97325D02*
X1060443D01*
G01X1058375Y96445D02*
X1059255Y97325D01*
G01X1057455Y96445D02*
X1058375D01*
G01X1052800Y101100D02*
X1057455Y96445D01*
G01X1052800Y107893D02*
Y101100D01*
G01X1051903Y108790D02*
X1052800Y107893D01*
G01X1050930Y108790D02*
X1051903D01*
G01X1050080Y107940D02*
X1050930Y108790D01*
G01X1049160Y107940D02*
X1050080D01*
G01X1047910Y109190D02*
X1049160Y107940D01*
G01X1047910Y110210D02*
Y109190D01*
G01X1048736Y111036D02*
X1047910Y110210D01*
G01X1048736Y111957D02*
Y111036D01*
G01X1045884Y114809D02*
X1048736Y111957D01*
G01X1062400Y102400D02*
Y104568D01*
G01X1064100Y100700D02*
X1062400Y102400D01*
G01X1066590Y100700D02*
X1064100D01*
G01X1068399Y98891D02*
X1066590Y100700D01*
G01X1068399Y97605D02*
Y98891D01*
G01X1070365Y95639D02*
X1068399Y97605D01*
G01X1071481Y95639D02*
X1070365D01*
G01X1045895Y123668D02*
Y186770D01*
G01X1062400Y107163D02*
X1045895Y123668D01*
G01X1062400Y104568D02*
Y107163D01*
G01X1057805Y130802D02*
Y193595D01*
G01X1081732Y106875D02*
X1057805Y130802D01*
G01X1081732Y104117D02*
Y106875D01*
G01Y101368D02*
Y104117D01*
G01X1083039Y155179D02*
X1119700Y118518D01*
G01X1083039Y159100D02*
Y155179D01*
G01X1085916Y122839D02*
X1104128Y104627D01*
G01X1085916Y123915D02*
Y122839D01*
G01X1086743Y124742D02*
X1085916Y123915D01*
G01X1087820Y124742D02*
X1086743D01*
G01X1090771Y121791D02*
X1087820Y124742D01*
G01X1091691Y121791D02*
X1090771D01*
G01X1092673Y122773D02*
X1091691Y121791D01*
G01X1092673Y123693D02*
Y122773D01*
G01X1070663Y145703D02*
X1092673Y123693D01*
G01X1070663Y159000D02*
Y145703D01*
G01X1066300Y106468D02*
X1060718Y112050D01*
G01X1066300Y104989D02*
Y106468D01*
G01X1064427Y103116D02*
X1066300Y104989D01*
G01X1047880Y124888D02*
Y187498D01*
G01X1060718Y112050D02*
X1047880Y124888D01*
G01X1035970Y115131D02*
Y180000D01*
G01X1038756Y112345D02*
X1035970Y115131D01*
G01X1042353Y108748D02*
X1038756Y112345D01*
G01X1042353Y107161D02*
Y108748D01*
G01X1041756Y106564D02*
X1042353Y107161D01*
G01X1041756Y105646D02*
Y106564D01*
G01X1042677Y104725D02*
X1041756Y105646D01*
G01X1043594Y104725D02*
X1042677D01*
G01X1044192Y105323D02*
X1043594Y104725D01*
G01X1045380Y105323D02*
X1044192D01*
G01X1046031Y104672D02*
X1045380Y105323D01*
G01X1046031Y103484D02*
Y104672D01*
G01X1044834Y102286D02*
X1046031Y103484D01*
G01X1044834Y101368D02*
Y102286D01*
G01X1045755Y100447D02*
X1044834Y101368D01*
G01X1046672Y100447D02*
X1045755D01*
G01X1048099Y101874D02*
X1046672Y100447D01*
G01X1049019Y101874D02*
X1048099D01*
G01X1049938Y100955D02*
X1049019Y101874D01*
G01X1049938Y100035D02*
Y100955D01*
G01X1048512Y98609D02*
X1049938Y100035D01*
G01X1048512Y97688D02*
Y98609D01*
G01X1049431Y96769D02*
X1048512Y97688D01*
G01X1050351Y96769D02*
X1049431D01*
G01X1051549Y97967D02*
X1050351Y96769D01*
G01X1053055Y97967D02*
X1051549D01*
G01X1053705Y97317D02*
X1053055Y97967D01*
G01X1053705Y95810D02*
Y97317D01*
G01X1052607Y94712D02*
X1053705Y95810D01*
G01X1043910Y122690D02*
X1053630Y112970D01*
G01X1043910Y187013D02*
Y122690D01*
G01X1059650Y103116D02*
X1057734D01*
G01X1060300Y103766D02*
X1059650Y103116D01*
G01X1060300Y106300D02*
Y103766D01*
G01X1053630Y112970D02*
X1060300Y106300D01*
G01X1090596Y158314D02*
X1128972Y119938D01*
G01X1090500Y104033D02*
X1096400Y98133D01*
G01X1061775Y132758D02*
X1090500Y104033D01*
G01X1061775Y195724D02*
Y132758D01*
G01X1059790Y131780D02*
X1081142Y110428D01*
G01X1059790Y194610D02*
Y131780D01*
G01X1092715Y98965D02*
X1093700Y97980D01*
G01X1091795Y98965D02*
X1092715D01*
G01X1090025Y97195D02*
X1091795Y98965D01*
G01X1089105Y97195D02*
X1090025D01*
G01X1088186Y98114D02*
X1089105Y97195D01*
G01X1088186Y99034D02*
Y98114D01*
G01X1089956Y100804D02*
X1088186Y99034D01*
G01X1089956Y101724D02*
Y100804D01*
G01X1089026Y102654D02*
X1089956Y101724D01*
G01X1088106Y102654D02*
X1089026D01*
G01X1086348Y100896D02*
X1088106Y102654D01*
G01X1085428Y100896D02*
X1086348D01*
G01X1084509Y101815D02*
X1085428Y100896D01*
G01X1084509Y102735D02*
Y101815D01*
G01X1086212Y104438D02*
X1084509Y102735D01*
G01X1086212Y105358D02*
Y104438D01*
G01X1081142Y110428D02*
X1086212Y105358D01*
G01X1068700Y102500D02*
Y104697D01*
G01X1070400Y100800D02*
X1068700Y102500D01*
G01X1073001Y100800D02*
X1070400D01*
G01X1074446Y99355D02*
X1073001Y100800D01*
G01X1074446Y95699D02*
Y99355D01*
G01X1075219Y94926D02*
X1074446Y95699D01*
G01X1076550Y94926D02*
X1075219D01*
G01X1077200Y95576D02*
X1076550Y94926D01*
G01X1077200Y97472D02*
Y95576D01*
G01X1077851Y98123D02*
X1077200Y97472D01*
G01X1079178Y98123D02*
X1077851D01*
G01X1080000Y97301D02*
X1079178Y98123D01*
G01X1049865Y125866D02*
Y187877D01*
G01X1068700Y107031D02*
X1049865Y125866D01*
G01X1068700Y104697D02*
Y107031D01*
G01X1073000Y106450D02*
X1066798Y112652D01*
G01X1073000Y104996D02*
Y106450D01*
G01X1071120Y103116D02*
X1073000Y104996D01*
G01X1051850Y127600D02*
Y188251D01*
G01X1066798Y112652D02*
X1051850Y127600D01*
G01X1085558Y156224D02*
X1123934Y117848D01*
G01X1085558Y159100D02*
Y156224D01*
G01X1055341Y108259D02*
Y104472D01*
G01X1041925Y121675D02*
X1055341Y108259D01*
G01X1041925Y187013D02*
Y121675D01*
G01X1057217Y99683D02*
X1061253D01*
G01X1055341Y101559D02*
X1057217Y99683D01*
G01X1055341Y104472D02*
Y101559D01*
G01X1065625Y143222D02*
Y159300D01*
G01X1075113Y133734D02*
X1065625Y143222D01*
G01X1075113Y132814D02*
Y133734D01*
G01X1074130Y131831D02*
X1075113Y132814D01*
G01X1073210Y131831D02*
X1074130D01*
G01X1071675Y133366D02*
X1073210Y131831D01*
G01X1070967Y133366D02*
X1071675D01*
G01X1069773Y132172D02*
X1070967Y133366D01*
G01X1069773Y131464D02*
Y132172D01*
G01X1101131Y100106D02*
X1069773Y131464D01*
G01X1088077Y159300D02*
Y157269D01*
G01X1048155Y205211D02*
X1048154Y205210D01*
G01X1051989Y205211D02*
X1048155D01*
G01X1054037Y203163D02*
X1051989Y205211D01*
G01X1055363Y203163D02*
X1054037D01*
G01X1056800Y201726D02*
X1055363Y203163D01*
G01X1056800Y194600D02*
Y201726D01*
G01X1057805Y193595D02*
X1056800Y194600D01*
G01X1090596Y159600D02*
Y158314D01*
G01X1061100Y196399D02*
X1061775Y195724D01*
G01X1061100Y208400D02*
Y196399D01*
G01X1056491Y213009D02*
X1061100Y208400D01*
G01X1054914Y213009D02*
X1056491D01*
G01X1058900Y195500D02*
X1059790Y194610D01*
G01X1058900Y204360D02*
Y195500D01*
G01X1058050Y205210D02*
X1058900Y204360D01*
G01X1054914Y205210D02*
X1058050D01*
G01X1067692Y216196D02*
X1065242D01*
G01X1067692Y231797D02*
X1065242D01*
G01X1074452Y247396D02*
X1072202D01*
G01X1067692Y220096D02*
X1065242D01*
G01X1067692Y227896D02*
X1065242D01*
G01X1060850Y402684D02*
X1060200Y403334D01*
G01X1060850Y397350D02*
Y402684D01*
G01X1060000Y396500D02*
X1060850Y397350D01*
G01X1057432Y396500D02*
X1060000D01*
G01X1054914Y393982D02*
X1057432Y396500D01*
G01X1054914Y392410D02*
Y393982D01*
G01X1071072Y378047D02*
X1073322D01*
G01X1081212Y364396D02*
X1083462D01*
G01X1071072Y393647D02*
X1073322D01*
G01X1051534Y390460D02*
X1049284D01*
G01X1081212Y387796D02*
X1083462D01*
G01X1091351Y362447D02*
X1093601D01*
G01X1077832Y381947D02*
X1080082D01*
G01X1071072Y389747D02*
X1073322D01*
G01X1048154Y384609D02*
X1045904D01*
G01X1091351Y354647D02*
X1093601D01*
G01X1087971Y387796D02*
X1090221D01*
G01X1081212Y383896D02*
X1083462D01*
G01X1091351Y389747D02*
X1093601D01*
G01X1071072Y370247D02*
X1073322D01*
G01X1044774Y386560D02*
X1042524D01*
G01X1084591Y366347D02*
X1086841D01*
G01X1087971Y356596D02*
X1090221D01*
G01X1077832Y389747D02*
X1080082D01*
G01X1063250Y396123D02*
Y407549D01*
G01X1081212Y372197D02*
X1083462D01*
G01X1061625Y412025D02*
X1051800Y402200D01*
G01X1071072Y381947D02*
X1073322D01*
G01X1084591Y374146D02*
X1086841D01*
G01X1081212Y376096D02*
X1083462D01*
G01X1081212Y368296D02*
X1083462D01*
G01X1087971D02*
X1090221D01*
G01X1041395Y384609D02*
X1039145D01*
G01X1074452Y364396D02*
X1076702D01*
G01X1084591Y370247D02*
X1086841D01*
G01X1091351Y381947D02*
X1093601D01*
G01X1087971Y383896D02*
X1090221D01*
G01X1087971Y360496D02*
X1090221D01*
G01X1071072Y366347D02*
X1073322D01*
G01X1063610Y411110D02*
Y473054D01*
G01X1060850Y408350D02*
X1063610Y411110D01*
G01X1060850Y406634D02*
Y408350D01*
G01X1060200Y405984D02*
X1060850Y406634D01*
G01X1058274Y405984D02*
X1060200D01*
G01X1057561Y405271D02*
X1058274Y405984D01*
G01X1057561Y403921D02*
Y405271D01*
G01X1058148Y403334D02*
X1057561Y403921D01*
G01X1060200Y403334D02*
X1058148D01*
G01X1090650Y448150D02*
X1095800Y453300D01*
G01X1047730Y470954D02*
Y414698D01*
G01X1045745Y413983D02*
X1045975Y413753D01*
G01X1045745Y484901D02*
Y413983D01*
G01X1051700Y476126D02*
Y416028D01*
G01X1041775Y487420D02*
Y411853D01*
G01X1057655Y418266D02*
Y478055D01*
G01X1083844Y464378D02*
Y465476D01*
G01X1083068Y463602D02*
X1083844Y464378D01*
G01X1081276Y463602D02*
X1083068D01*
G01X1080500Y462826D02*
X1081276Y463602D01*
G01X1080500Y461728D02*
Y462826D01*
G01X1081276Y460952D02*
X1080500Y461728D01*
G01X1083068Y460952D02*
X1081276D01*
G01X1083844Y460176D02*
X1083068Y460952D01*
G01X1083844Y458771D02*
Y460176D01*
G01X1077081Y452008D02*
X1083844Y458771D01*
G01X1077081Y446981D02*
Y452008D01*
G01X1077900Y456601D02*
Y470964D01*
G01X1074562Y453263D02*
X1077900Y456601D01*
G01X1074562Y443937D02*
Y453263D01*
G01X1075300Y457800D02*
Y471928D01*
G01X1072043Y454543D02*
X1075300Y457800D01*
G01X1072043Y443457D02*
Y454543D01*
G01X1049715Y482816D02*
Y415513D01*
G01X1043760Y413168D02*
Y485823D01*
G01X1043875Y413053D02*
X1043760Y413168D01*
G01X1065595Y409894D02*
Y471347D01*
G01X1063250Y407549D02*
X1065595Y409894D01*
G01X1055670Y464870D02*
Y417690D01*
G01X1053685Y480286D02*
Y417443D01*
G01X1094100Y443500D02*
X1090901D01*
G01X1101000Y450400D02*
X1094100Y443500D01*
G01X1061625Y476185D02*
Y412025D01*
G01X1039675Y494857D02*
Y410927D01*
G01X1035475Y496814D02*
Y410585D01*
G01X1072700Y458900D02*
Y472892D01*
G01X1069500Y455700D02*
X1072700Y458900D01*
G01X1069500Y443500D02*
Y455700D01*
G01X1037575Y495863D02*
Y411056D01*
G01X1059640Y413141D02*
X1051471Y404972D01*
G01X1059640Y474572D02*
Y413141D01*
G01X1092400Y446000D02*
X1098400Y452000D01*
G01X1090700Y440900D02*
X1095600D01*
G01X1094488Y508289D02*
Y510114D01*
G01X1087549Y501350D02*
X1094488Y508289D01*
G01X1087549Y496149D02*
Y501350D01*
G01X1082248Y490848D02*
X1087549Y496149D01*
G01X1081328Y490848D02*
X1082248D01*
G01X1080766Y491410D02*
X1081328Y490848D01*
G01X1079694Y491410D02*
X1080766D01*
G01X1078781Y490497D02*
X1079694Y491410D01*
G01X1078781Y489647D02*
Y490497D01*
G01X1079454Y488974D02*
X1078781Y489647D01*
G01X1079454Y488054D02*
Y488974D01*
G01X1078500Y487100D02*
X1079454Y488054D01*
G01X1077580Y487100D02*
X1078500D01*
G01X1076937Y487743D02*
X1077580Y487100D01*
G01X1076002Y487743D02*
X1076937D01*
G01X1075048Y486789D02*
X1076002Y487743D01*
G01X1075048Y485884D02*
Y486789D01*
G01X1075706Y485226D02*
X1075048Y485884D01*
G01X1075706Y484306D02*
Y485226D01*
G01X1074752Y483352D02*
X1075706Y484306D01*
G01X1073832Y483352D02*
X1074752D01*
G01X1073189Y483995D02*
X1073832Y483352D01*
G01X1072254Y483995D02*
X1073189D01*
G01X1071300Y483041D02*
X1072254Y483995D01*
G01X1071300Y482136D02*
Y483041D01*
G01X1071958Y481478D02*
X1071300Y482136D01*
G01X1071958Y480558D02*
Y481478D01*
G01X1070562Y479162D02*
X1071958Y480558D01*
G01X1069642Y479162D02*
X1070562D01*
G01X1069012Y479792D02*
X1069642Y479162D01*
G01X1068092Y479792D02*
X1069012D01*
G01X1067138Y478838D02*
X1068092Y479792D01*
G01X1067138Y477918D02*
Y478838D01*
G01X1067768Y477288D02*
X1067138Y477918D01*
G01X1067768Y476368D02*
Y477288D01*
G01X1065498Y474098D02*
X1067768Y476368D01*
G01X1064654Y474098D02*
X1065498D01*
G01X1063610Y473054D02*
X1064654Y474098D01*
G01X1074409Y523923D02*
X1074411Y523900D01*
G01X1073900Y523414D02*
X1074409Y523923D01*
G01X1073900Y518100D02*
Y523414D01*
G01X1071900Y516100D02*
X1073900Y518100D01*
G01X1071900Y514700D02*
Y516100D01*
G01X1072900Y513700D02*
X1071900Y514700D01*
G01X1072900Y512100D02*
Y513700D01*
G01X1072300Y511500D02*
X1072900Y512100D01*
G01X1072300Y509300D02*
Y511500D01*
G01X1066884Y503884D02*
X1072300Y509300D01*
G01X1062596Y503884D02*
X1066884D01*
G01X1059091Y500379D02*
X1062596Y503884D01*
G01X1059091Y495247D02*
Y500379D01*
G01X1047730Y483886D02*
X1059091Y495247D01*
G01X1047730Y470954D02*
Y483886D01*
G01X1056656Y495812D02*
X1045745Y484901D01*
G01X1056656Y501686D02*
Y495812D01*
G01X1061070Y506100D02*
X1056656Y501686D01*
G01X1066400Y506100D02*
X1061070D01*
G01X1069528Y509228D02*
X1066400Y506100D01*
G01X1069528Y511072D02*
Y509228D01*
G01X1069100Y511500D02*
X1069528Y511072D01*
G01X1069100Y513800D02*
Y511500D01*
G01X1069600Y514300D02*
X1069100Y513800D01*
G01X1069600Y516200D02*
Y514300D01*
G01X1067643Y518157D02*
X1069600Y516200D01*
G01X1064369Y518157D02*
X1067643D01*
G01X1081091Y523912D02*
X1081104Y523900D01*
G01X1080900Y523721D02*
X1081091Y523912D01*
G01X1080900Y517900D02*
Y523721D01*
G01X1079200Y516200D02*
X1080900Y517900D01*
G01X1079200Y514500D02*
Y516200D01*
G01X1079554Y514146D02*
X1079200Y514500D01*
G01X1079554Y511754D02*
Y514146D01*
G01X1078100Y510300D02*
X1079554Y511754D01*
G01X1078100Y508300D02*
Y510300D01*
G01X1051700Y481900D02*
X1078100Y508300D01*
G01X1051700Y476126D02*
Y481900D01*
G01X1043155Y488800D02*
X1041775Y487420D01*
G01X1043155Y490064D02*
Y488800D01*
G01X1042028Y491191D02*
X1043155Y490064D01*
G01X1042028Y492676D02*
Y491191D01*
G01X1043992Y494640D02*
X1042028Y492676D01*
G01X1045368Y494640D02*
X1043992D01*
G01X1047565Y496837D02*
X1045368Y494640D01*
G01X1047565Y498173D02*
Y496837D01*
G01X1046737Y499001D02*
X1047565Y498173D01*
G01X1046737Y499921D02*
Y499001D01*
G01X1048640Y501824D02*
X1046737Y499921D01*
G01X1049624Y501824D02*
X1048640D01*
G01X1060592Y512792D02*
X1049624Y501824D01*
G01X1064369Y512792D02*
X1060592D01*
G01X1089600Y511006D02*
X1087795Y515364D01*
G01X1089600Y509300D02*
Y511006D01*
G01X1088925Y508625D02*
X1089600Y509300D01*
G01X1087730Y508130D02*
X1088925Y508625D01*
G01X1057655Y478055D02*
X1087730Y508130D01*
G01X1095168Y482043D02*
X1096540Y483415D01*
G01X1094349Y482043D02*
X1095168D01*
G01X1093906Y482486D02*
X1094349Y482043D01*
G01X1092986Y482486D02*
X1093906D01*
G01X1091614Y481114D02*
X1092986Y482486D01*
G01X1091614Y480194D02*
Y481114D01*
G01X1091957Y479851D02*
X1091614Y480194D01*
G01X1091957Y478830D02*
Y479851D01*
G01X1090585Y477458D02*
X1091957Y478830D01*
G01X1089766Y477458D02*
X1090585D01*
G01X1089322Y477902D02*
X1089766Y477458D01*
G01X1088402Y477902D02*
X1089322D01*
G01X1087030Y476530D02*
X1088402Y477902D01*
G01X1087030Y475610D02*
Y476530D01*
G01X1087448Y475192D02*
X1087030Y475610D01*
G01X1087448Y474297D02*
Y475192D01*
G01X1086076Y472925D02*
X1087448Y474297D01*
G01X1084494Y472925D02*
X1086076D01*
G01X1083844Y472275D02*
X1084494Y472925D01*
G01X1083844Y469678D02*
Y472275D01*
G01X1083068Y468902D02*
X1083844Y469678D01*
G01X1081276Y468902D02*
X1083068D01*
G01X1080500Y468126D02*
X1081276Y468902D01*
G01X1080500Y467028D02*
Y468126D01*
G01X1081276Y466252D02*
X1080500Y467028D01*
G01X1083068Y466252D02*
X1081276D01*
G01X1083844Y465476D02*
X1083068Y466252D01*
G01X1077900Y470964D02*
X1098736Y491800D01*
G01X1075300Y471928D02*
X1097498Y494126D01*
G01X1062164Y495265D02*
X1049715Y482816D01*
G01X1062164Y497243D02*
Y495265D01*
G01X1065573Y500652D02*
X1062164Y497243D01*
G01X1067551Y500652D02*
X1065573D01*
G01X1076200Y509301D02*
X1067551Y500652D01*
G01X1076200Y511901D02*
Y509301D01*
G01X1075600Y512501D02*
X1076200Y511901D01*
G01X1075600Y514173D02*
Y512501D01*
G01X1074409Y515364D02*
X1075600Y514173D01*
G01X1052800Y495065D02*
Y498443D01*
G01X1051816Y494081D02*
X1052800Y495065D01*
G01X1050815Y494081D02*
X1051816D01*
G01X1050080Y494816D02*
X1050815Y494081D01*
G01X1049160Y494816D02*
X1050080D01*
G01X1047910Y493566D02*
X1049160Y494816D01*
G01X1047910Y492546D02*
Y493566D01*
G01X1048578Y491878D02*
X1047910Y492546D01*
G01X1048578Y490641D02*
Y491878D01*
G01X1043760Y485823D02*
X1048578Y490641D01*
G01X1064370Y523900D02*
X1064372D01*
G01X1064370Y520971D02*
Y523900D01*
G01X1062500Y519101D02*
X1064370Y520971D01*
G01X1062500Y517400D02*
Y519101D01*
G01X1066200Y513700D02*
X1062500Y517400D01*
G01X1066200Y512000D02*
Y513700D01*
G01X1062400Y508200D02*
X1066200Y512000D01*
G01X1059200Y508200D02*
X1062400D01*
G01X1052800Y501800D02*
X1059200Y508200D01*
G01X1052800Y498443D02*
Y501800D01*
G01X1095500Y512920D02*
X1094488Y515364D01*
G01X1089564Y501008D02*
X1096400Y507844D01*
G01X1089564Y495316D02*
Y501008D01*
G01X1065595Y471347D02*
X1089564Y495316D01*
G01X1055670Y479070D02*
Y464870D01*
G01X1086000Y509400D02*
X1055670Y479070D01*
G01X1086000Y511000D02*
Y509400D01*
G01X1086500Y511500D02*
X1086000Y511000D01*
G01X1086500Y513566D02*
Y511500D01*
G01X1085735Y514331D02*
X1086500Y513566D01*
G01X1085735Y515935D02*
Y514331D01*
G01X1087795Y517995D02*
X1085735Y515935D01*
G01X1087795Y523900D02*
Y517995D01*
G01X1087797Y523900D02*
X1087795D01*
G01X1073484Y500085D02*
X1053685Y480286D01*
G01X1073484Y501278D02*
Y500085D01*
G01X1075496Y503290D02*
X1073484Y501278D01*
G01X1077277Y503290D02*
X1075496D01*
G01X1078443Y504456D02*
X1077277Y503290D01*
G01X1078443Y506099D02*
Y504456D01*
G01X1080244Y507900D02*
X1078443Y506099D01*
G01X1082147Y507900D02*
X1080244D01*
G01X1083654Y509407D02*
X1082147Y507900D01*
G01X1083654Y510746D02*
Y509407D01*
G01X1082049Y512351D02*
X1083654Y510746D01*
G01X1082049Y514417D02*
Y512351D01*
G01X1081102Y515364D02*
X1082049Y514417D01*
G01X1044290Y511562D02*
Y512792D01*
G01X1038618Y505890D02*
X1044290Y511562D01*
G01X1038618Y503064D02*
Y505890D01*
G01X1063186Y477746D02*
X1061625Y476185D01*
G01X1063186Y477747D02*
Y477746D01*
G01X1080902Y495463D02*
X1063186Y477747D01*
G01X1083163Y495463D02*
X1080902D01*
G01X1084800Y497100D02*
X1083163Y495463D01*
G01X1084800Y499400D02*
Y497100D01*
G01X1044204Y499386D02*
X1039675Y494857D01*
G01X1044204Y500038D02*
Y499386D01*
G01X1052500Y508334D02*
X1044204Y500038D01*
G01X1052500Y510900D02*
Y508334D01*
G01X1057676Y516076D02*
X1052500Y510900D01*
G01X1057676Y518157D02*
Y516076D01*
G01X1057677Y523923D02*
Y529007D01*
G01X1057679Y523900D02*
X1057677Y523923D01*
G01X1040358Y501697D02*
X1035475Y496814D01*
G01X1040358Y505262D02*
Y501697D01*
G01X1046500Y511404D02*
X1040358Y505262D01*
G01X1046500Y514227D02*
Y511404D01*
G01X1047637Y515364D02*
X1046500Y514227D01*
G01X1047637Y523923D02*
Y529007D01*
G01X1047639Y523900D02*
X1047637Y523923D01*
G01X1093700Y498400D02*
X1100600Y505300D01*
G01X1093700Y493892D02*
Y498400D01*
G01X1072700Y472892D02*
X1093700Y493892D01*
G01X1071063Y523923D02*
Y529021D01*
G01X1071065Y523900D02*
X1071063Y523923D01*
G01X1042758Y501046D02*
X1037575Y495863D01*
G01X1042758Y505190D02*
Y501046D01*
G01X1045442Y507874D02*
X1042758Y505190D01*
G01X1048218Y507874D02*
X1045442D01*
G01X1049600Y509256D02*
X1048218Y507874D01*
G01X1049600Y511500D02*
Y509256D01*
G01X1049100Y512000D02*
X1049600Y511500D01*
G01X1049100Y514110D02*
Y512000D01*
G01X1050354Y515364D02*
X1049100Y514110D01*
G01X1054330Y515364D02*
X1050354D01*
G01X1054330Y523923D02*
Y529021D01*
G01X1054332Y523900D02*
X1054330Y523923D01*
G01X1059640Y477140D02*
Y474572D01*
G01X1089276Y506776D02*
X1059640Y477140D01*
G01X1090813Y507413D02*
X1089276Y506776D01*
G01X1092150Y508750D02*
X1090813Y507413D01*
G01X1092150Y510450D02*
Y508750D01*
G01X1093400Y511700D02*
X1092150Y510450D01*
G01X1093400Y513600D02*
Y511700D01*
G01X1092700Y514300D02*
X1093400Y513600D01*
G01X1092700Y516600D02*
Y514300D01*
G01X1094488Y518388D02*
X1092700Y516600D01*
G01X1094488Y523900D02*
Y518388D01*
G01X1094490Y523900D02*
X1094488D01*
G01Y579810D02*
X1094490D01*
G01X1094488Y574759D02*
Y579810D01*
G01X1094490Y574757D02*
X1094488Y574759D01*
G01X1064370Y536958D02*
X1064371Y536957D01*
G01X1064370Y542010D02*
Y536958D01*
G01X1064372Y542010D02*
X1064370D01*
G01Y579810D02*
X1064372D01*
G01X1064370Y574758D02*
Y579810D01*
G01X1064371Y574757D02*
X1064370Y574758D01*
G01X1094488Y561723D02*
Y566822D01*
G01X1094490Y561700D02*
X1094488Y561723D01*
G01X1084448Y579810D02*
X1084450D01*
G01X1084448Y574759D02*
Y579810D01*
G01X1084450Y574757D02*
X1084448Y574759D01*
G01Y536959D02*
X1084450Y536957D01*
G01X1084448Y542010D02*
Y536959D01*
G01X1084450Y542010D02*
X1084448D01*
G01X1074409Y561723D02*
Y566807D01*
G01X1074411Y561700D02*
X1074409Y561723D01*
G01X1044292Y574857D02*
Y574757D01*
G01X1044291Y574858D02*
X1044292Y574857D01*
G01X1044291Y579810D02*
Y574858D01*
G01X1044293Y579810D02*
X1044291D01*
G01X1077755D02*
X1077757D01*
G01X1077755Y574759D02*
Y579810D01*
G01X1077757Y574757D02*
X1077755Y574759D01*
G01X1081102Y561723D02*
Y566807D01*
G01X1081104Y561700D02*
X1081102Y561723D01*
G01X1057677D02*
Y566807D01*
G01X1057679Y561700D02*
X1057677Y561723D01*
G01X1054330Y579810D02*
X1054332D01*
G01X1054330Y574858D02*
Y579810D01*
G01X1054331Y574857D02*
X1054330Y574858D01*
G01X1054331Y574757D02*
Y574857D01*
G01X1050984Y536958D02*
X1050985Y536957D01*
G01X1050984Y542010D02*
Y536958D01*
G01X1050986Y542010D02*
X1050984D01*
G01X1077755Y536959D02*
X1077757Y536957D01*
G01X1077755Y542010D02*
Y536959D01*
G01X1077757Y542010D02*
X1077755D01*
G01X1054330Y566821D02*
X1054331Y566822D01*
G01X1054330Y561723D02*
Y566821D01*
G01X1054332Y561700D02*
X1054330Y561723D01*
G01X1087795Y566820D02*
X1087797Y566822D01*
G01X1087795Y561723D02*
Y566820D01*
G01X1087797Y561700D02*
X1087795Y561723D01*
G01X1044291Y537146D02*
X1044203Y537058D01*
G01X1044291Y542010D02*
Y537146D01*
G01X1044293Y542010D02*
X1044291D01*
G01X1094488Y536959D02*
X1094490Y536957D01*
G01X1094488Y542010D02*
Y536959D01*
G01X1094490Y542010D02*
X1094488D01*
G01X1071063Y529021D02*
X1071064Y529022D01*
G01X1054330Y529021D02*
X1054331Y529022D01*
G01X1047637Y561723D02*
Y566807D01*
G01X1047639Y561700D02*
X1047637Y561723D01*
G01X1054330Y536958D02*
X1054331Y536957D01*
G01X1054330Y542010D02*
Y536958D01*
G01X1054332Y542010D02*
X1054330D01*
G01X1064370Y566821D02*
X1064371Y566822D01*
G01X1064370Y561723D02*
Y566821D01*
G01X1064372Y561700D02*
X1064370Y561723D01*
G01X1050984Y579810D02*
X1050986D01*
G01X1050984Y574758D02*
Y579810D01*
G01X1050985Y574757D02*
X1050984Y574758D01*
G01X1071063Y566821D02*
X1071064Y566822D01*
G01X1071063Y561723D02*
Y566821D01*
G01X1071065Y561700D02*
X1071063Y561723D01*
G01X1087795Y617610D02*
X1087797D01*
G01X1087795Y609864D02*
Y617610D01*
G01X1064370Y607291D02*
X1064369Y607292D01*
G01X1064370Y599523D02*
Y607291D01*
G01X1064372Y599500D02*
X1064370Y599523D01*
G01X1050984Y617610D02*
X1050986D01*
G01X1050984Y612658D02*
Y617610D01*
G01X1071063Y607291D02*
X1071062Y607292D01*
G01X1071063Y599523D02*
Y607291D01*
G01X1071065Y599500D02*
X1071063Y599523D01*
G01X1087795D02*
Y604614D01*
G01X1087797Y599500D02*
X1087795Y599523D01*
G01X1084448Y617610D02*
X1084450D01*
G01X1084448Y612657D02*
Y617610D01*
G01X1054330D02*
X1054332D01*
G01X1054330Y609864D02*
Y617610D01*
G01X1081102Y599523D02*
Y604499D01*
G01X1081104Y599500D02*
X1081102Y599523D01*
G01X1044291Y617610D02*
Y612658D01*
G01X1044293Y617610D02*
X1044291D01*
G01X1057677Y607291D02*
X1057676Y607292D01*
G01X1057677Y599523D02*
Y607291D01*
G01X1057679Y599500D02*
X1057677Y599523D01*
G01X1077755Y617610D02*
Y612657D01*
G01X1077757Y617610D02*
X1077755D01*
G01X1074409Y599523D02*
Y604614D01*
G01X1074411Y599500D02*
X1074409Y599523D01*
G01X1094488D02*
Y604614D01*
G01X1094490Y599500D02*
X1094488Y599523D01*
G01X1047637D02*
Y604499D01*
G01X1047639Y599500D02*
X1047637Y599523D01*
G01X1054330D02*
Y604499D01*
G01X1054332Y599500D02*
X1054330Y599523D01*
G01X1094488Y617610D02*
X1094490D01*
G01X1094488Y609864D02*
Y617610D01*
G01X1064370D02*
X1064372D01*
G01X1064370Y612658D02*
Y617610D01*
G01X1064369Y612657D02*
X1064370Y612658D01*
G01X1127953Y-3699D02*
X1127952Y-3700D01*
G01X1127953Y-2500D02*
Y-3699D01*
G01X1128473Y-1980D02*
X1127953Y-2500D01*
G01X1128473Y-1120D02*
Y-1980D01*
G01X1127953Y-600D02*
X1128473Y-1120D01*
G01X1127953Y3232D02*
Y-600D01*
G01X1127954Y3233D02*
X1127953Y3232D01*
G01X1137992Y-14877D02*
Y-9901D01*
G01X1137994Y-14877D02*
X1137992D01*
G01X1101181D02*
Y-9901D01*
G01X1101183Y-14877D02*
X1101181D01*
G01Y22923D02*
Y27899D01*
G01X1101183Y22923D02*
X1101181D01*
G01X1144685Y-14877D02*
Y-9901D01*
G01X1144687Y-14877D02*
X1144685D01*
G01X1148031Y3233D02*
X1147331Y-4100D01*
G01X1148033Y3233D02*
X1148031D01*
G01X1144685Y22923D02*
Y27899D01*
G01X1144687Y22923D02*
X1144685D01*
G01X1124606Y-14877D02*
Y-9901D01*
G01X1124608Y-14877D02*
X1124606D01*
G01X1137992Y22923D02*
Y27899D01*
G01X1137994Y22923D02*
X1137992D01*
G01X1104527Y-2008D02*
X1104141Y-4100D01*
G01X1104527Y3233D02*
Y-2008D01*
G01X1104529Y3233D02*
X1104527D01*
G01X1124606Y22923D02*
Y27899D01*
G01X1124608Y22923D02*
X1124606D01*
G01X1107874D02*
Y27899D01*
G01X1107876Y22923D02*
X1107874D01*
G01X1131299Y-14877D02*
Y-9901D01*
G01X1131301Y-14877D02*
X1131299D01*
G01X1134645Y-2608D02*
Y-3700D01*
G01X1135163Y-2090D02*
X1134645Y-2608D01*
G01X1135163Y-1210D02*
Y-2090D01*
G01X1134645Y-692D02*
X1135163Y-1210D01*
G01X1134645Y3233D02*
Y-692D01*
G01X1134647Y3233D02*
X1134645D01*
G01X1111220D02*
X1110520Y-4100D01*
G01X1111222Y3233D02*
X1111220D01*
G01X1107874Y-14877D02*
Y-9901D01*
G01X1107876Y-14877D02*
X1107874D01*
G01X1141338Y-2008D02*
X1140952Y-4100D01*
G01X1141338Y3233D02*
Y-2008D01*
G01X1141340Y3233D02*
X1141338D01*
G01X1131299Y22923D02*
Y27899D01*
G01X1131301Y22923D02*
X1131299D01*
G01X1109966Y93856D02*
X1108950Y94872D01*
G01X1109966Y92316D02*
Y93856D01*
G01X1108516Y90866D02*
X1109966Y92316D01*
G01X1108516Y89718D02*
Y90866D01*
G01X1110520Y87714D02*
X1108516Y89718D01*
G01X1107874Y60723D02*
Y65699D01*
G01X1107876Y60723D02*
X1107874D01*
G01X1134645Y35192D02*
Y34100D01*
G01X1135163Y35710D02*
X1134645Y35192D01*
G01X1135163Y36590D02*
Y35710D01*
G01X1134645Y37108D02*
X1135163Y36590D01*
G01X1134645Y41033D02*
Y37108D01*
G01X1134647Y41033D02*
X1134645D01*
G01X1103750Y93550D02*
Y101245D01*
G01X1106196Y91104D02*
X1103750Y93550D01*
G01X1106196Y89683D02*
Y91104D01*
G01X1104227Y87714D02*
X1106196Y89683D01*
G01X1101181Y60723D02*
Y65699D01*
G01X1101183Y60723D02*
X1101181D01*
G01X1147407Y34500D02*
X1147331Y33700D01*
G01X1147455Y35000D02*
X1147407Y34500D01*
G01X1148031Y41033D02*
X1147455Y35000D01*
G01X1148033Y41033D02*
X1148031D01*
G01X1134645Y72992D02*
Y71900D01*
G01X1135163Y73510D02*
X1134645Y72992D01*
G01X1135163Y74390D02*
Y73510D01*
G01X1134645Y74908D02*
X1135163Y74390D01*
G01X1134645Y78833D02*
Y74908D01*
G01X1134647Y78833D02*
X1134645D01*
G01X1130200Y91658D02*
X1131299Y92757D01*
G01X1130200Y90340D02*
Y91658D01*
G01X1131192Y89348D02*
X1130200Y90340D01*
G01X1131900Y89348D02*
X1131192D01*
G01X1132779Y90227D02*
X1131900Y89348D01*
G01X1132779Y91169D02*
Y90227D01*
G01X1133100Y91490D02*
X1132779Y91169D01*
G01X1133100Y92101D02*
Y91490D01*
G01X1133800Y92801D02*
X1133100Y92101D01*
G01X1133800Y94700D02*
Y92801D01*
G01X1131299Y97201D02*
X1133800Y94700D01*
G01X1147713Y75500D02*
X1147331Y71500D01*
G01X1148031Y78833D02*
X1147713Y75500D01*
G01X1148033Y78833D02*
X1148031D01*
G01X1127953Y78832D02*
X1127954Y78833D01*
G01X1127953Y75000D02*
Y78832D01*
G01X1128473Y74480D02*
X1127953Y75000D01*
G01X1128473Y73620D02*
Y74480D01*
G01X1127953Y73100D02*
X1128473Y73620D01*
G01X1127953Y71901D02*
Y73100D01*
G01X1127952Y71900D02*
X1127953Y71901D01*
G01X1124606Y94305D02*
Y92757D01*
G01X1125900Y95599D02*
X1124606Y94305D01*
G01X1110902Y75500D02*
X1110520Y71500D01*
G01X1111220Y78833D02*
X1110902Y75500D01*
G01X1111222Y78833D02*
X1111220D01*
G01X1106350Y94281D02*
X1107874Y92757D01*
G01X1106350Y102405D02*
Y94281D01*
G01X1141338Y73592D02*
X1140952Y71500D01*
G01X1141338Y78833D02*
Y73592D01*
G01X1141340Y78833D02*
X1141338D01*
G01X1127953Y41032D02*
X1127954Y41033D01*
G01X1127953Y37200D02*
Y41032D01*
G01X1128473Y36680D02*
X1127953Y37200D01*
G01X1128473Y35820D02*
Y36680D01*
G01X1127953Y35300D02*
X1128473Y35820D01*
G01X1127953Y34101D02*
Y35300D01*
G01X1127952Y34100D02*
X1127953Y34101D01*
G01X1111222Y34402D02*
X1110520Y33700D01*
G01X1111222Y41033D02*
Y34402D01*
G01X1131299Y60723D02*
Y65699D01*
G01X1131301Y60723D02*
X1131299D01*
G01X1136700Y89769D02*
X1134645Y87714D01*
G01X1137569Y89769D02*
X1136700D01*
G01X1140346Y92546D02*
X1137569Y89769D01*
G01X1140346Y95454D02*
Y92546D01*
G01X1104529Y34088D02*
X1104141Y33700D01*
G01X1104529Y41033D02*
Y34088D01*
G01X1095601Y88301D02*
Y85827D01*
G01X1096400Y89100D02*
X1095601Y88301D01*
G01X1096400Y98133D02*
Y89100D01*
G01X1144685Y60723D02*
Y65699D01*
G01X1144687Y60723D02*
X1144685D01*
G01X1124606D02*
Y65699D01*
G01X1124608Y60723D02*
X1124606D01*
G01X1126450Y87714D02*
X1127952D01*
G01X1125800Y88364D02*
X1126450Y87714D01*
G01X1125800Y91200D02*
Y88364D01*
G01X1128700Y94100D02*
X1125800Y91200D01*
G01X1128700Y104992D02*
Y94100D01*
G01X1141100Y34500D02*
X1140952Y33700D01*
G01X1141192Y35000D02*
X1141100Y34500D01*
G01X1141338Y35792D02*
X1141192Y35000D01*
G01X1141338Y41033D02*
Y35792D01*
G01X1141340Y41033D02*
X1141338D01*
G01X1104527Y73592D02*
X1104141Y71500D01*
G01X1104527Y78833D02*
Y73592D01*
G01X1104529Y78833D02*
X1104527D01*
G01X1101131Y92807D02*
Y100106D01*
G01X1101181Y92757D02*
X1101131Y92807D01*
G01X1137992Y60723D02*
Y65699D01*
G01X1137994Y60723D02*
X1137992D01*
G01X1108950Y103565D02*
X1101598Y110917D01*
G01X1108950Y94872D02*
Y103565D01*
G01X1102952Y116253D02*
Y117173D01*
G01X1101970Y115271D02*
X1102952Y116253D01*
G01X1101050Y115271D02*
X1101970D01*
G01X1098798Y117523D02*
X1101050Y115271D01*
G01X1097822Y117523D02*
X1098798D01*
G01X1096894Y116595D02*
X1097822Y117523D01*
G01X1096894Y115621D02*
Y116595D01*
G01X1101598Y110917D02*
X1096894Y115621D01*
G01X1154766Y131534D02*
X1158500Y127800D01*
G01X1154766Y132454D02*
Y131534D01*
G01X1156646Y134334D02*
X1154766Y132454D01*
G01X1156646Y135254D02*
Y134334D01*
G01X1155692Y136208D02*
X1156646Y135254D01*
G01X1154772Y136208D02*
X1155692D01*
G01X1152892Y134328D02*
X1154772Y136208D01*
G01X1151972Y134328D02*
X1152892D01*
G01X1151018Y135282D02*
X1151972Y134328D01*
G01X1151018Y136202D02*
Y135282D01*
G01X1152898Y138082D02*
X1151018Y136202D01*
G01X1152898Y139002D02*
Y138082D01*
G01X1151944Y139956D02*
X1152898Y139002D01*
G01X1151024Y139956D02*
X1151944D01*
G01X1149144Y138076D02*
X1151024Y139956D01*
G01X1148224Y138076D02*
X1149144D01*
G01X1147270Y139030D02*
X1148224Y138076D01*
G01X1147270Y139950D02*
Y139030D01*
G01X1149150Y141830D02*
X1147270Y139950D01*
G01X1149150Y142750D02*
Y141830D01*
G01X1148196Y143704D02*
X1149150Y142750D01*
G01X1147276Y143704D02*
X1148196D01*
G01X1145396Y141824D02*
X1147276Y143704D01*
G01X1144476Y141824D02*
X1145396D01*
G01X1128700Y157600D02*
X1144476Y141824D01*
G01X1122021Y140081D02*
X1118586Y143516D01*
G01X1127719Y140081D02*
X1122021D01*
G01X1131650Y136150D02*
X1127719Y140081D01*
G01X1131650Y131950D02*
Y136150D01*
G01X1139566Y124034D02*
X1131650Y131950D01*
G01X1139566Y123114D02*
Y124034D01*
G01X1138219Y121767D02*
X1139566Y123114D01*
G01X1138219Y120393D02*
Y121767D01*
G01X1139052Y119560D02*
X1138219Y120393D01*
G01X1139760Y119560D02*
X1139052D01*
G01X1141440Y121240D02*
X1139760Y119560D01*
G01X1142360Y121240D02*
X1141440D01*
G01X1143796Y119804D02*
X1142360Y121240D01*
G01X1143796Y119096D02*
Y119804D01*
G01X1141900Y117200D02*
X1143796Y119096D01*
G01X1141900Y116300D02*
Y117200D01*
G01X1143300Y114900D02*
X1141900Y116300D01*
G01X1143300Y113592D02*
Y114900D01*
G01X1144535Y112357D02*
X1143300Y113592D01*
G01X1106350Y155775D02*
X1105700Y156425D01*
G01X1107550Y155775D02*
X1106350D01*
G01X1108200Y155125D02*
X1107550Y155775D01*
G01X1109575Y155125D02*
X1108200D01*
G01X1110993Y153707D02*
X1109575Y155125D01*
G01X1110993Y152787D02*
Y153707D01*
G01X1110614Y152408D02*
X1110993Y152787D01*
G01X1110614Y151488D02*
Y152408D01*
G01X1111568Y150534D02*
X1110614Y151488D01*
G01X1112488Y150534D02*
X1111568D01*
G01X1112867Y150913D02*
X1112488Y150534D01*
G01X1113787Y150913D02*
X1112867D01*
G01X1114741Y149959D02*
X1113787Y150913D01*
G01X1114741Y149039D02*
Y149959D01*
G01X1114362Y148660D02*
X1114741Y149039D01*
G01X1114362Y147740D02*
Y148660D01*
G01X1118586Y143516D02*
X1114362Y147740D01*
G01X1151700Y149200D02*
X1166050Y134850D01*
G01X1144300Y149200D02*
X1151700D01*
G01X1135300Y158200D02*
X1144300Y149200D01*
G01X1131299Y107850D02*
Y104000D01*
G01X1126453Y112696D02*
X1131299Y107850D01*
G01X1126453Y118893D02*
Y112696D01*
G01X1131299Y104000D02*
Y97201D01*
G01X1147331Y102150D02*
Y106964D01*
G01X1146681Y101500D02*
X1147331Y102150D01*
G01X1144500Y101500D02*
X1146681D01*
G01X1142700Y103300D02*
X1144500Y101500D01*
G01X1142700Y105200D02*
Y103300D01*
G01X1144300Y106800D02*
X1142700Y105200D01*
G01X1144300Y109224D02*
Y106800D01*
G01X1146510Y111434D02*
X1144300Y109224D01*
G01X1146510Y115200D02*
Y111434D01*
G01Y119010D02*
Y115200D01*
G01X1147500Y120000D02*
X1146510Y119010D01*
G01X1147500Y121400D02*
Y120000D01*
G01X1147000Y121900D02*
X1147500Y121400D01*
G01X1145500Y121900D02*
X1147000D01*
G01X1134169Y133231D02*
X1145500Y121900D01*
G01X1134169Y137331D02*
Y133231D01*
G01X1128900Y142600D02*
X1134169Y137331D01*
G01X1125712Y142600D02*
X1128900D01*
G01X1111300Y157012D02*
X1125712Y142600D01*
G01X1119700Y118518D02*
Y116492D01*
G01X1125900Y96501D02*
Y95599D01*
G01X1125401Y97000D02*
X1125900Y96501D01*
G01X1120300Y97000D02*
X1125401D01*
G01X1119500Y97800D02*
X1120300Y97000D01*
G01X1119500Y99850D02*
Y97800D01*
G01X1120050Y100400D02*
X1119500Y99850D01*
G01X1125450Y100400D02*
X1120050D01*
G01X1126100Y101050D02*
X1125450Y100400D01*
G01X1126100Y102550D02*
Y101050D01*
G01X1125450Y103200D02*
X1126100Y102550D01*
G01X1120201Y103200D02*
X1125450D01*
G01X1119700Y103701D02*
X1120201Y103200D01*
G01X1119700Y116492D02*
Y103701D01*
G01X1104128Y104627D02*
X1106350Y102405D01*
G01X1150456Y146400D02*
X1161100Y135675D01*
G01X1143500Y146400D02*
X1150456D01*
G01X1132000Y157900D02*
X1143500Y146400D01*
G01X1140274Y106200D02*
X1141038Y106964D01*
G01X1138616Y106200D02*
X1140274D01*
G01X1137202Y107614D02*
X1138616Y106200D01*
G01X1137202Y109750D02*
Y107614D01*
G01X1137852Y110400D02*
X1137202Y109750D01*
G01X1139200Y110400D02*
X1137852D01*
G01X1140600Y111800D02*
X1139200Y110400D01*
G01X1140600Y113600D02*
Y111800D01*
G01X1138850Y115350D02*
X1140600Y113600D01*
G01X1135700Y118500D02*
X1138850Y115350D01*
G01X1135700Y122600D02*
Y118500D01*
G01X1102000Y156300D02*
X1135700Y122600D01*
G01X1128972Y115328D02*
X1131400Y112900D01*
G01X1128972Y119938D02*
Y115328D01*
G01X1134100Y101700D02*
X1140346Y95454D01*
G01X1134100Y110200D02*
Y101700D01*
G01X1131400Y112900D02*
X1134100Y110200D01*
G01X1123934Y117848D02*
Y112500D01*
G01Y109758D02*
X1128700Y104992D01*
G01X1123934Y112500D02*
Y109758D01*
G01X1132900Y121601D02*
X1095500Y159001D01*
G01X1132900Y117699D02*
Y121601D01*
G01X1138242Y112357D02*
X1132900Y117699D01*
G01X1153000Y151800D02*
X1170660Y134140D01*
G01X1145400Y151800D02*
X1153000D01*
G01X1137819Y159381D02*
X1145400Y151800D01*
G01X1128700Y159800D02*
Y157600D01*
G01X1126600Y161900D02*
X1128700Y159800D01*
G01X1108200Y159075D02*
Y161000D01*
G01X1107550Y158425D02*
X1108200Y159075D01*
G01X1106350Y158425D02*
X1107550D01*
G01X1105700Y157775D02*
X1106350Y158425D01*
G01X1105700Y156425D02*
Y157775D01*
G01X1135300Y160407D02*
Y158200D01*
G01X1131904Y163803D02*
X1135300Y160407D01*
G01X1111300Y161400D02*
Y157012D01*
G01X1132000Y160100D02*
Y157900D01*
G01X1129400Y162700D02*
X1132000Y160100D01*
G01X1102000Y158200D02*
Y156300D01*
G01X1105500Y161700D02*
X1102000Y158200D01*
G01X1133040Y216196D02*
X1135290D01*
G01X1099400Y163000D02*
X1101600D01*
G01X1098900Y163500D02*
X1099400Y163000D01*
G01X1098900Y163900D02*
Y163500D01*
G01X1098400Y164400D02*
X1098900Y163900D01*
G01X1096150Y164400D02*
X1098400D01*
G01X1095500Y163750D02*
X1096150Y164400D01*
G01X1095500Y159001D02*
Y163750D01*
G01X1137819Y162081D02*
Y159381D01*
G01X1134000Y165900D02*
X1137819Y162081D01*
G01X1133040Y227896D02*
X1135290D01*
G01X1133040Y220096D02*
X1135290D01*
G01X1121771Y387796D02*
X1124021D01*
G01X1098111Y354647D02*
X1100361D01*
G01X1118391Y381947D02*
X1120641D01*
G01X1121771Y376096D02*
X1124021D01*
G01X1101491Y368296D02*
X1103741D01*
G01X1108251Y383896D02*
X1110501D01*
G01X1111631Y370247D02*
X1113881D01*
G01X1111631Y354647D02*
X1113881D01*
G01X1121771Y383896D02*
X1124021D01*
G01X1098111Y389747D02*
X1100361D01*
G01X1142050Y399496D02*
X1144300D01*
G01X1118391Y370247D02*
X1120641D01*
G01X1111631Y381947D02*
X1113881D01*
G01X1138670Y393647D02*
X1140920D01*
G01X1130780Y383896D02*
X1128530D01*
G01X1111631Y362447D02*
X1113881D01*
G01X1101491Y360496D02*
X1103741D01*
G01X1131910Y389747D02*
X1134160D01*
G01X1131910Y374146D02*
X1134160D01*
G01X1098111Y370247D02*
X1100361D01*
G01X1101491Y356596D02*
X1103741D01*
G01X1098111Y381947D02*
X1100361D01*
G01X1138670Y401447D02*
X1140920D01*
G01X1108251Y387796D02*
X1110501D01*
G01X1108251Y360496D02*
X1110501D01*
G01X1121771Y368296D02*
X1124021D01*
G01X1101491Y383896D02*
X1103741D01*
G01X1111631Y389747D02*
X1113881D01*
G01X1131910Y381947D02*
X1134160D01*
G01X1108251Y376096D02*
X1110501D01*
G01X1101491D02*
X1103741D01*
G01X1130780Y387796D02*
X1128530D01*
G01X1101491D02*
X1103741D01*
G01X1098111Y362447D02*
X1100361D01*
G01X1130780Y376096D02*
X1128530D01*
G01X1098111Y374146D02*
X1100361D01*
G01X1118391Y354647D02*
X1120641D01*
G01X1142050Y395597D02*
X1144300D01*
G01X1118391Y374146D02*
X1120641D01*
G01X1138670Y381947D02*
X1140920D01*
G01X1130780Y360496D02*
X1128530D01*
G01X1142050Y356596D02*
X1144300D01*
G01X1108251Y372197D02*
X1110501D01*
G01X1111631Y374146D02*
X1113881D01*
G01X1118391Y362447D02*
X1120641D01*
G01X1118391Y389747D02*
X1120641D01*
G01X1130780Y368296D02*
X1128530D01*
G01X1108251Y356596D02*
X1110501D01*
G01X1108251Y368296D02*
X1110501D01*
G01X1121771Y356596D02*
X1124021D01*
G01X1121771Y360496D02*
X1124021D01*
G01X1095800Y462742D02*
X1107388Y474330D01*
G01X1095800Y453300D02*
Y462742D01*
G01X1149049Y461648D02*
X1161325Y473924D01*
G01X1145548Y461648D02*
X1149049D01*
G01X1129850Y445950D02*
X1145548Y461648D01*
G01X1155271Y453858D02*
X1159331D01*
G01X1151521Y450108D02*
X1155271Y453858D01*
G01X1145608Y450108D02*
X1151521D01*
G01X1137200Y441700D02*
X1145608Y450108D01*
G01X1114000Y453372D02*
X1136328Y475700D01*
G01X1114000Y449900D02*
Y453372D01*
G01X1113200Y449100D02*
X1114000Y449900D01*
G01X1132796Y464388D02*
Y465486D01*
G01X1132020Y463612D02*
X1132796Y464388D01*
G01X1130922Y463612D02*
X1132020D01*
G01X1130016Y464518D02*
X1130922Y463612D01*
G01X1128918Y464518D02*
X1130016D01*
G01X1128142Y463742D02*
X1128918Y464518D01*
G01X1128142Y462644D02*
Y463742D01*
G01X1129048Y461738D02*
X1128142Y462644D01*
G01X1129048Y460640D02*
Y461738D01*
G01X1128272Y459864D02*
X1129048Y460640D01*
G01X1127174Y459864D02*
X1128272D01*
G01X1126268Y460770D02*
X1127174Y459864D01*
G01X1125170Y460770D02*
X1126268D01*
G01X1124394Y459994D02*
X1125170Y460770D01*
G01X1124394Y458896D02*
Y459994D01*
G01X1125300Y457990D02*
X1124394Y458896D01*
G01X1125300Y456892D02*
Y457990D01*
G01X1123308Y454900D02*
X1125300Y456892D01*
G01X1119400Y454900D02*
X1123308D01*
G01X1117000Y452500D02*
X1119400Y454900D01*
G01X1117000Y449300D02*
Y452500D01*
G01X1115800Y448100D02*
X1117000Y449300D01*
G01X1156963Y456380D02*
X1159532Y458949D01*
G01X1154188Y456380D02*
X1156963D01*
G01X1150497Y452689D02*
X1154188Y456380D01*
G01X1144589Y452689D02*
X1150497D01*
G01X1135400Y443500D02*
X1144589Y452689D01*
G01X1101000Y460426D02*
Y450400D01*
G01X1126029Y485455D02*
X1101000Y460426D01*
G01X1155016Y463515D02*
X1167909Y476408D01*
G01X1155016Y462595D02*
Y463515D01*
G01X1156872Y460739D02*
X1155016Y462595D01*
G01X1156872Y459896D02*
Y460739D01*
G01X1155918Y458942D02*
X1156872Y459896D01*
G01X1154921Y458942D02*
X1155918D01*
G01X1153142Y460721D02*
X1154921Y458942D01*
G01X1151694Y460721D02*
X1153142D01*
G01X1149802Y458829D02*
X1151694Y460721D01*
G01X1149802Y455744D02*
Y458829D01*
G01X1149266Y455208D02*
X1149802Y455744D01*
G01X1147412Y455208D02*
X1149266D01*
G01X1146877Y455743D02*
X1147412Y455208D01*
G01X1146877Y457485D02*
Y455743D01*
G01X1146285Y458077D02*
X1146877Y457485D01*
G01X1145577Y458077D02*
X1146285D01*
G01X1133100Y445600D02*
X1145577Y458077D01*
G01X1098400Y461584D02*
X1111070Y474254D01*
G01X1098400Y452000D02*
Y461584D01*
G01X1108000Y457922D02*
X1116871Y466793D01*
G01X1108000Y451400D02*
Y457922D01*
G01X1119714Y462914D02*
X1126527Y469727D01*
G01X1118794Y462914D02*
X1119714D01*
G01X1118156Y463552D02*
X1118794Y462914D01*
G01X1117236Y463552D02*
X1118156D01*
G01X1116282Y462598D02*
X1117236Y463552D01*
G01X1116282Y461678D02*
Y462598D01*
G01X1116920Y461040D02*
X1116282Y461678D01*
G01X1116920Y460120D02*
Y461040D01*
G01X1115966Y459166D02*
X1116920Y460120D01*
G01X1115046Y459166D02*
X1115966D01*
G01X1114408Y459804D02*
X1115046Y459166D01*
G01X1113488Y459804D02*
X1114408D01*
G01X1112534Y458850D02*
X1113488Y459804D01*
G01X1112534Y457930D02*
Y458850D01*
G01X1113172Y457292D02*
X1112534Y457930D01*
G01X1113172Y456372D02*
Y457292D01*
G01X1111000Y454200D02*
X1113172Y456372D01*
G01X1111000Y450700D02*
Y454200D01*
G01X1110600Y450300D02*
X1111000Y450700D01*
G01X1103900Y459568D02*
X1134500Y490168D01*
G01X1103900Y449200D02*
Y459568D01*
G01X1095600Y440900D02*
X1103900Y449200D01*
G01X1122500Y516051D02*
X1124606Y518157D01*
G01X1122500Y515326D02*
Y516051D01*
G01X1126700Y511126D02*
X1122500Y515326D01*
G01X1126700Y509600D02*
Y511126D01*
G01X1125200Y508100D02*
X1126700Y509600D01*
G01X1125200Y496858D02*
Y508100D01*
G01X1113096Y484754D02*
X1125200Y496858D01*
G01X1113096Y483778D02*
Y484754D01*
G01X1114247Y482627D02*
X1113096Y483778D01*
G01X1114247Y481600D02*
Y482627D01*
G01X1113320Y480673D02*
X1114247Y481600D01*
G01X1112344Y480673D02*
X1113320D01*
G01X1111142Y481875D02*
X1112344Y480673D01*
G01X1110217Y481875D02*
X1111142D01*
G01X1107388Y479046D02*
X1110217Y481875D01*
G01X1107388Y474330D02*
Y479046D01*
G01X1107874Y523923D02*
Y528899D01*
G01X1107876Y523900D02*
X1107874Y523923D01*
G01X1111586Y513114D02*
X1110520D01*
G01X1112516Y512184D02*
X1111586Y513114D01*
G01X1112516Y509184D02*
Y512184D01*
G01X1111953Y508621D02*
X1112516Y509184D01*
G01X1111953Y507114D02*
Y508621D01*
G01X1112750Y506317D02*
X1111953Y507114D01*
G01X1113550Y506317D02*
X1112750D01*
G01X1114200Y505667D02*
X1113550Y506317D01*
G01X1114200Y503727D02*
Y505667D01*
G01X1113550Y503077D02*
X1114200Y503727D01*
G01X1112750Y503077D02*
X1113550D01*
G01X1112100Y502427D02*
X1112750Y503077D01*
G01X1112100Y499226D02*
Y502427D01*
G01X1099677Y486803D02*
X1112100Y499226D01*
G01X1098757Y486803D02*
X1099677D01*
G01X1098490Y487070D02*
X1098757Y486803D01*
G01X1097570Y487070D02*
X1098490D01*
G01X1096198Y485698D02*
X1097570Y487070D01*
G01X1096198Y484778D02*
Y485698D01*
G01X1096540Y484436D02*
X1096198Y484778D01*
G01X1096540Y483415D02*
Y484436D01*
G01X1106100Y516383D02*
X1107874Y518157D01*
G01X1106100Y514500D02*
Y516383D01*
G01X1109700Y510900D02*
X1106100Y514500D01*
G01X1109700Y508100D02*
Y510900D01*
G01X1107700Y506100D02*
X1109700Y508100D01*
G01X1107700Y505000D02*
Y506100D01*
G01X1110200Y502500D02*
X1107700Y505000D01*
G01X1110200Y501084D02*
Y502500D01*
G01X1109273Y500157D02*
X1110200Y501084D01*
G01X1108297Y500157D02*
X1109273D01*
G01X1107274Y501180D02*
X1108297Y500157D01*
G01X1106348Y501180D02*
X1107274D01*
G01X1105421Y500253D02*
X1106348Y501180D01*
G01X1105421Y499227D02*
Y500253D01*
G01X1106394Y498254D02*
X1105421Y499227D01*
G01X1106394Y497278D02*
Y498254D01*
G01X1100916Y491800D02*
X1106394Y497278D01*
G01X1098736Y491800D02*
X1100916D01*
G01X1101181Y523923D02*
Y528899D01*
G01X1101183Y523900D02*
X1101181Y523923D01*
G01X1105899Y511442D02*
X1104227Y513114D01*
G01X1105899Y508498D02*
Y511442D01*
G01X1104134Y506733D02*
X1105899Y508498D01*
G01X1104134Y505749D02*
Y506733D01*
G01X1105521Y504362D02*
X1104134Y505749D01*
G01X1105521Y503141D02*
Y504362D01*
G01X1104310Y501930D02*
X1105521Y503141D01*
G01X1103315Y501930D02*
X1104310D01*
G01X1102432Y502813D02*
X1103315Y501930D01*
G01X1101665Y502813D02*
X1102432D01*
G01X1100341Y501489D02*
X1101665Y502813D01*
G01X1100341Y500319D02*
Y501489D01*
G01X1102520Y498140D02*
X1100341Y500319D01*
G01X1102520Y497220D02*
Y498140D01*
G01X1101537Y496237D02*
X1102520Y497220D01*
G01X1100617Y496237D02*
X1101537D01*
G01X1098564Y498290D02*
X1100617Y496237D01*
G01X1097691Y498290D02*
X1098564D01*
G01X1096595Y497194D02*
X1097691Y498290D01*
G01X1096595Y496372D02*
Y497194D01*
G01X1097498Y495469D02*
X1096595Y496372D01*
G01X1097498Y494126D02*
Y495469D01*
G01X1137992Y523923D02*
Y528899D01*
G01X1137994Y523900D02*
X1137992Y523923D01*
G01X1144685D02*
Y528899D01*
G01X1144687Y523900D02*
X1144685Y523923D01*
G01X1145687Y498487D02*
X1144385D01*
G01X1146685Y499485D02*
X1145687Y498487D01*
G01X1146685Y501015D02*
Y499485D01*
G01X1146000Y501700D02*
X1146685Y501015D01*
G01X1142500Y501700D02*
X1146000D01*
G01X1141800Y501000D02*
X1142500Y501700D01*
G01X1141800Y495500D02*
Y501000D01*
G01X1142800Y494500D02*
X1141800Y495500D01*
G01X1142800Y493200D02*
Y494500D01*
G01X1143600Y492400D02*
X1142800Y493200D01*
G01X1143600Y487900D02*
Y492400D01*
G01X1146000Y485500D02*
X1143600Y487900D01*
G01X1146000Y481000D02*
Y485500D01*
G01X1140700Y475700D02*
X1146000Y481000D01*
G01X1136328Y475700D02*
X1140700D01*
G01X1148031Y490894D02*
X1147331D01*
G01X1149925Y489000D02*
X1148031Y490894D01*
G01X1149925Y485729D02*
Y489000D01*
G01X1149100Y484904D02*
X1149925Y485729D01*
G01X1149100Y480392D02*
Y484904D01*
G01X1141204Y472496D02*
X1149100Y480392D01*
G01X1140904Y472496D02*
X1141204D01*
G01X1139516Y471108D02*
X1140904Y472496D01*
G01X1138418Y471108D02*
X1139516D01*
G01X1137512Y472014D02*
X1138418Y471108D01*
G01X1136414Y472014D02*
X1137512D01*
G01X1135638Y471238D02*
X1136414Y472014D01*
G01X1135638Y470140D02*
Y471238D01*
G01X1136544Y469234D02*
X1135638Y470140D01*
G01X1136544Y468136D02*
Y469234D01*
G01X1135768Y467360D02*
X1136544Y468136D01*
G01X1134670Y467360D02*
X1135768D01*
G01X1133764Y468266D02*
X1134670Y467360D01*
G01X1132666Y468266D02*
X1133764D01*
G01X1131890Y467490D02*
X1132666Y468266D01*
G01X1131890Y466392D02*
Y467490D01*
G01X1132796Y465486D02*
X1131890Y466392D01*
G01X1095500Y511700D02*
Y512920D01*
G01X1096400Y510800D02*
X1095500Y511700D01*
G01X1096400Y507844D02*
Y510800D01*
G01X1126029Y486431D02*
Y485455D01*
G01X1124669Y487791D02*
X1126029Y486431D01*
G01X1124669Y488816D02*
Y487791D01*
G01X1125596Y489743D02*
X1124669Y488816D01*
G01X1126523Y489743D02*
X1125596D01*
G01X1127932Y488334D02*
X1126523Y489743D01*
G01X1128908Y488334D02*
X1127932D01*
G01X1131800Y491226D02*
X1128908Y488334D01*
G01X1131800Y507646D02*
Y491226D01*
G01X1133950Y509796D02*
X1131800Y507646D01*
G01X1133950Y511150D02*
Y509796D01*
G01X1130000Y515100D02*
X1133950Y511150D01*
G01X1130000Y516858D02*
Y515100D01*
G01X1131299Y518157D02*
X1130000Y516858D01*
G01X1102100Y517238D02*
X1101181Y518157D01*
G01X1102100Y512000D02*
Y517238D01*
G01X1103153Y510947D02*
X1102100Y512000D01*
G01X1103153Y509453D02*
Y510947D01*
G01X1100600Y506900D02*
X1103153Y509453D01*
G01X1100600Y505300D02*
Y506900D01*
G01X1124606Y523923D02*
Y528899D01*
G01X1124608Y523900D02*
X1124606Y523923D01*
G01X1129400Y511666D02*
X1127952Y513114D01*
G01X1129400Y509142D02*
Y511666D01*
G01X1127178Y506920D02*
X1129400Y509142D01*
G01X1127178Y504170D02*
Y506920D01*
G01X1127678Y503670D02*
X1127178Y504170D01*
G01X1129056Y503670D02*
X1127678D01*
G01X1129681Y503045D02*
X1129056Y503670D01*
G01X1129681Y501105D02*
Y503045D01*
G01X1129006Y500430D02*
X1129681Y501105D01*
G01X1128350Y500430D02*
X1129006D01*
G01X1127800Y499880D02*
X1128350Y500430D01*
G01X1127800Y496840D02*
Y499880D01*
G01X1128450Y496190D02*
X1127800Y496840D01*
G01X1128550Y496190D02*
X1128450D01*
G01X1129200Y495540D02*
X1128550Y496190D01*
G01X1129200Y493600D02*
Y495540D01*
G01X1128550Y492950D02*
X1129200Y493600D01*
G01X1125050Y492950D02*
X1128550D01*
G01X1120860Y488760D02*
X1125050Y492950D01*
G01X1120860Y487784D02*
Y488760D01*
G01X1122309Y486335D02*
X1120860Y487784D01*
G01X1122309Y485359D02*
Y486335D01*
G01X1121382Y484432D02*
X1122309Y485359D01*
G01X1120406Y484432D02*
X1121382D01*
G01X1118831Y486007D02*
X1120406Y484432D01*
G01X1117918Y486007D02*
X1118831D01*
G01X1116791Y484880D02*
X1117918Y486007D01*
G01X1116791Y483841D02*
Y484880D01*
G01X1118100Y482532D02*
X1116791Y483841D01*
G01X1118100Y481284D02*
Y482532D01*
G01X1113896Y477080D02*
X1118100Y481284D01*
G01X1112939Y477080D02*
X1113896D01*
G01X1111860Y478159D02*
X1112939Y477080D01*
G01X1111003Y478159D02*
X1111860D01*
G01X1109912Y477068D02*
X1111003Y478159D01*
G01X1109912Y476359D02*
Y477068D01*
G01X1111070Y475201D02*
X1109912Y476359D01*
G01X1111070Y474254D02*
Y475201D01*
G01X1139800Y496679D02*
X1137992Y498487D01*
G01X1139800Y495100D02*
Y496679D01*
G01X1139200Y494500D02*
X1139800Y495100D01*
G01X1139200Y492800D02*
Y494500D01*
G01X1138500Y492100D02*
X1139200Y492800D01*
G01X1138500Y484900D02*
Y492100D01*
G01X1137700Y484100D02*
X1138500Y484900D01*
G01X1134178Y484100D02*
X1137700D01*
G01X1123413Y473335D02*
X1134178Y484100D01*
G01X1123413Y472415D02*
Y473335D01*
G01X1123992Y471836D02*
X1123413Y472415D01*
G01X1123992Y470916D02*
Y471836D01*
G01X1123038Y469962D02*
X1123992Y470916D01*
G01X1122118Y469962D02*
X1123038D01*
G01X1121500Y470580D02*
X1122118Y469962D01*
G01X1120580Y470580D02*
X1121500D01*
G01X1119626Y469626D02*
X1120580Y470580D01*
G01X1119626Y468706D02*
Y469626D01*
G01X1120244Y468088D02*
X1119626Y468706D01*
G01X1120244Y467168D02*
Y468088D01*
G01X1119290Y466214D02*
X1120244Y467168D01*
G01X1118370Y466214D02*
X1119290D01*
G01X1117791Y466793D02*
X1118370Y466214D01*
G01X1116871Y466793D02*
X1117791D01*
G01X1141038Y486262D02*
Y491144D01*
G01X1142639Y484661D02*
X1141038Y486262D01*
G01X1142639Y481439D02*
Y484661D01*
G01X1140100Y478900D02*
X1142639Y481439D01*
G01X1138412Y478900D02*
X1140100D01*
G01X1136160Y481152D02*
X1138412Y478900D01*
G01X1135452Y481152D02*
X1136160D01*
G01X1134286Y479986D02*
X1135452Y481152D01*
G01X1134286Y479278D02*
Y479986D01*
G01X1134853Y478711D02*
X1134286Y479278D01*
G01X1134853Y477791D02*
Y478711D01*
G01X1133899Y476837D02*
X1134853Y477791D01*
G01X1132979Y476837D02*
X1133899D01*
G01X1132284Y477532D02*
X1132979Y476837D01*
G01X1131364Y477532D02*
X1132284D01*
G01X1130410Y476578D02*
X1131364Y477532D01*
G01X1130410Y475658D02*
Y476578D01*
G01X1131105Y474963D02*
X1130410Y475658D01*
G01X1131105Y474043D02*
Y474963D01*
G01X1130151Y473089D02*
X1131105Y474043D01*
G01X1129231Y473089D02*
X1130151D01*
G01X1128536Y473784D02*
X1129231Y473089D01*
G01X1127616Y473784D02*
X1128536D01*
G01X1126527Y472695D02*
X1127616Y473784D01*
G01X1126527Y469727D02*
Y472695D01*
G01X1131299Y523923D02*
Y528899D01*
G01X1131301Y523900D02*
X1131299Y523923D01*
G01X1137886Y513114D02*
X1134645D01*
G01X1140100Y510900D02*
X1137886Y513114D01*
G01X1140100Y507000D02*
Y510900D01*
G01X1138769Y505669D02*
X1140100Y507000D01*
G01X1137849Y505669D02*
X1138769D01*
G01X1136149Y507369D02*
X1137849Y505669D01*
G01X1135354Y507369D02*
X1136149D01*
G01X1133982Y505997D02*
X1135354Y507369D01*
G01X1133982Y504952D02*
Y505997D01*
G01X1135557Y503377D02*
X1133982Y504952D01*
G01X1135557Y502457D02*
Y503377D01*
G01X1134500Y501400D02*
X1135557Y502457D01*
G01X1134500Y490168D02*
Y501400D01*
G01X1104527Y574592D02*
X1104141Y572500D01*
G01X1104527Y579810D02*
Y574592D01*
G01X1104529Y579810D02*
X1104527D01*
G01X1127953Y535101D02*
X1127952Y535100D01*
G01X1127953Y536300D02*
Y535101D01*
G01X1128473Y536820D02*
X1127953Y536300D01*
G01X1128473Y537680D02*
Y536820D01*
G01X1127953Y538200D02*
X1128473Y537680D01*
G01X1127953Y542010D02*
Y538200D01*
G01X1127954Y542010D02*
X1127953D01*
G01X1107874Y561723D02*
Y566699D01*
G01X1107876Y561700D02*
X1107874Y561723D01*
G01X1111220Y542033D02*
X1110520Y534700D01*
G01X1111222Y542010D02*
X1111220Y542033D01*
G01X1131299Y561723D02*
Y566699D01*
G01X1131301Y561700D02*
X1131299Y561723D01*
G01X1127953Y572901D02*
X1127952Y572900D01*
G01X1127953Y574100D02*
Y572901D01*
G01X1128473Y574620D02*
X1127953Y574100D01*
G01X1128473Y575480D02*
Y574620D01*
G01X1127953Y576000D02*
X1128473Y575480D01*
G01X1127953Y579810D02*
Y576000D01*
G01X1127954Y579810D02*
X1127953D01*
G01X1111220Y579833D02*
X1110520Y572500D01*
G01X1111222Y579810D02*
X1111220Y579833D01*
G01X1134645Y573992D02*
Y572900D01*
G01X1135163Y574510D02*
X1134645Y573992D01*
G01X1135163Y575390D02*
Y574510D01*
G01X1134645Y575908D02*
X1135163Y575390D01*
G01X1134645Y579810D02*
Y575908D01*
G01X1134647Y579810D02*
X1134645D01*
G01X1148031Y579833D02*
X1147331Y572500D01*
G01X1148033Y579810D02*
X1148031Y579833D01*
G01X1144685Y561723D02*
Y566699D01*
G01X1144687Y561700D02*
X1144685Y561723D01*
G01X1124606D02*
Y566699D01*
G01X1124608Y561700D02*
X1124606Y561723D01*
G01X1134645Y542010D02*
X1134647D01*
G01X1134645Y538108D02*
Y542010D01*
G01X1135163Y537590D02*
X1134645Y538108D01*
G01X1135163Y536710D02*
Y537590D01*
G01X1134645Y536192D02*
X1135163Y536710D01*
G01X1134645Y535100D02*
Y536192D01*
G01X1101181Y561723D02*
Y566699D01*
G01X1101183Y561700D02*
X1101181Y561723D01*
G01X1104527Y536792D02*
X1104141Y534700D01*
G01X1104527Y542010D02*
Y536792D01*
G01X1104529Y542010D02*
X1104527D01*
G01X1148031Y542033D02*
X1147331Y534700D01*
G01X1148033Y542010D02*
X1148031Y542033D01*
G01X1141338Y536792D02*
X1140952Y534700D01*
G01X1141338Y542010D02*
Y536792D01*
G01X1141340Y542010D02*
X1141338D01*
G01Y574592D02*
X1140952Y572500D01*
G01X1141338Y579810D02*
Y574592D01*
G01X1141340Y579810D02*
X1141338D01*
G01X1137992Y561723D02*
Y566699D01*
G01X1137994Y561700D02*
X1137992Y561723D01*
G01X1127953Y610701D02*
X1127952Y610700D01*
G01X1127953Y611900D02*
Y610701D01*
G01X1128473Y612420D02*
X1127953Y611900D01*
G01X1128473Y613280D02*
Y612420D01*
G01X1127953Y613800D02*
X1128473Y613280D01*
G01X1127953Y617610D02*
Y613800D01*
G01X1127954Y617610D02*
X1127953D01*
G01X1147446Y611507D02*
X1147700Y611200D01*
G01X1147718Y614358D02*
X1147446Y611507D01*
G01X1148031Y617633D02*
X1147718Y614358D01*
G01X1148033Y617610D02*
X1148031Y617633D01*
G01X1141338Y611674D02*
X1141332Y611668D01*
G01X1141338Y617610D02*
Y611674D01*
G01X1141340Y617610D02*
X1141338D01*
G01X1107874Y599523D02*
Y604499D01*
G01X1107876Y599500D02*
X1107874Y599523D01*
G01X1134645Y617610D02*
X1134647D01*
G01X1134645Y613708D02*
Y617610D01*
G01X1135163Y613190D02*
X1134645Y613708D01*
G01X1135163Y612310D02*
Y613190D01*
G01X1134645Y611792D02*
X1135163Y612310D01*
G01X1134645Y610700D02*
Y611792D01*
G01X1104527Y617610D02*
X1104529D01*
G01X1104527Y612392D02*
Y617610D01*
G01X1104141Y610300D02*
X1104527Y612392D01*
G01X1144685Y599523D02*
Y604499D01*
G01X1144687Y599500D02*
X1144685Y599523D01*
G01X1137992D02*
Y604499D01*
G01X1137994Y599500D02*
X1137992Y599523D01*
G01X1124606D02*
Y604499D01*
G01X1124608Y599500D02*
X1124606Y599523D01*
G01X1111220Y617633D02*
X1110520Y610300D01*
G01X1111222Y617610D02*
X1111220Y617633D01*
G01X1131299Y599523D02*
Y604499D01*
G01X1131301Y599500D02*
X1131299Y599523D01*
G01X1101181D02*
Y604499D01*
G01X1101183Y599500D02*
X1101181Y599523D01*
G01X1218307Y-14877D02*
Y-9901D01*
G01X1218309Y-14877D02*
X1218307D01*
G01X1184842Y3233D02*
X1184142Y-4100D01*
G01X1184844Y3233D02*
X1184842D01*
G01X1168110Y-14877D02*
Y-9901D01*
G01X1168112Y-14877D02*
X1168110D01*
G01X1198228Y22923D02*
Y27899D01*
G01X1198230Y22923D02*
X1198228D01*
G01Y-14877D02*
Y-9901D01*
G01X1198230Y-14877D02*
X1198228D01*
G01X1211614Y22923D02*
Y27899D01*
G01X1211616Y22923D02*
X1211614D01*
G01X1161417D02*
Y27899D01*
G01X1161419Y22923D02*
X1161417D01*
G01X1211614Y-14877D02*
Y-9901D01*
G01X1211616Y-14877D02*
X1211614D01*
G01X1204921Y22923D02*
Y27899D01*
G01X1204923Y22923D02*
X1204921D01*
G01X1174803D02*
Y27899D01*
G01X1174805Y22923D02*
X1174803D01*
G01X1204921Y-14877D02*
Y-9901D01*
G01X1204923Y-14877D02*
X1204921D01*
G01X1201575Y-3699D02*
X1201574Y-3700D01*
G01X1201575Y-2500D02*
Y-3699D01*
G01X1202095Y-1980D02*
X1201575Y-2500D01*
G01X1202095Y-1120D02*
Y-1980D01*
G01X1201575Y-600D02*
X1202095Y-1120D01*
G01X1201575Y3232D02*
Y-600D01*
G01X1201576Y3233D02*
X1201575Y3232D01*
G01X1181496Y22923D02*
Y27899D01*
G01X1181498Y22923D02*
X1181496D01*
G01X1171456Y-2608D02*
Y-3700D01*
G01X1171974Y-2090D02*
X1171456Y-2608D01*
G01X1171974Y-1210D02*
Y-2090D01*
G01X1171456Y-692D02*
X1171974Y-1210D01*
G01X1171456Y3233D02*
Y-692D01*
G01X1171458Y3233D02*
X1171456D01*
G01X1174803Y-14877D02*
Y-9901D01*
G01X1174805Y-14877D02*
X1174803D01*
G01X1161417D02*
Y-9901D01*
G01X1161419Y-14877D02*
X1161417D01*
G01X1214960Y-2008D02*
X1214574Y-4100D01*
G01X1214960Y3233D02*
Y-2008D01*
G01X1214962Y3233D02*
X1214960D01*
G01X1208267Y-2608D02*
Y-3700D01*
G01X1208785Y-2090D02*
X1208267Y-2608D01*
G01X1208785Y-1210D02*
Y-2090D01*
G01X1208267Y-692D02*
X1208785Y-1210D01*
G01X1208267Y3233D02*
Y-692D01*
G01X1208269Y3233D02*
X1208267D01*
G01X1178149Y-2008D02*
X1177763Y-4100D01*
G01X1178149Y3233D02*
Y-2008D01*
G01X1178151Y3233D02*
X1178149D01*
G01X1168110Y22923D02*
Y27899D01*
G01X1168112Y22923D02*
X1168110D01*
G01X1164764Y3232D02*
X1164765Y3233D01*
G01X1164764Y-600D02*
Y3232D01*
G01X1165284Y-1120D02*
X1164764Y-600D01*
G01X1165284Y-1980D02*
Y-1120D01*
G01X1164764Y-2500D02*
X1165284Y-1980D01*
G01X1164764Y-3699D02*
Y-2500D01*
G01X1164763Y-3700D02*
X1164764Y-3699D01*
G01X1181496Y-14877D02*
Y-9901D01*
G01X1181498Y-14877D02*
X1181496D01*
G01X1218307Y22923D02*
Y27899D01*
G01X1218309Y22923D02*
X1218307D01*
G01X1161417Y60723D02*
Y65699D01*
G01X1161419Y60723D02*
X1161417D01*
G01X1164764Y41032D02*
X1164765Y41033D01*
G01X1164764Y37200D02*
Y41032D01*
G01X1165284Y36680D02*
X1164764Y37200D01*
G01X1165284Y35820D02*
Y36680D01*
G01X1164764Y35300D02*
X1165284Y35820D01*
G01X1164764Y34101D02*
Y35300D01*
G01X1164763Y34100D02*
X1164764Y34101D01*
G01X1178149Y73592D02*
X1177763Y71500D01*
G01X1178149Y78833D02*
Y73592D01*
G01X1178151Y78833D02*
X1178149D01*
G01X1181496Y60723D02*
Y65699D01*
G01X1181498Y60723D02*
X1181496D01*
G01X1174803D02*
Y65699D01*
G01X1174805Y60723D02*
X1174803D01*
G01X1214722Y34500D02*
X1214574Y33700D01*
G01X1214814Y35000D02*
X1214722Y34500D01*
G01X1214960Y35792D02*
X1214814Y35000D01*
G01X1214960Y41033D02*
Y35792D01*
G01X1214962Y41033D02*
X1214960D01*
G01X1171456Y35192D02*
Y34100D01*
G01X1171974Y35710D02*
X1171456Y35192D01*
G01X1171974Y36590D02*
Y35710D01*
G01X1171456Y37108D02*
X1171974Y36590D01*
G01X1171456Y41033D02*
Y37108D01*
G01X1171458Y41033D02*
X1171456D01*
G01X1198228Y60723D02*
Y65699D01*
G01X1198230Y60723D02*
X1198228D01*
G01X1164764Y78832D02*
X1164765Y78833D01*
G01X1164764Y75000D02*
Y78832D01*
G01X1165284Y74480D02*
X1164764Y75000D01*
G01X1165284Y73620D02*
Y74480D01*
G01X1164764Y73100D02*
X1165284Y73620D01*
G01X1164764Y71901D02*
Y73100D01*
G01X1164763Y71900D02*
X1164764Y71901D01*
G01X1184218Y34500D02*
X1184142Y33700D01*
G01X1184266Y35000D02*
X1184218Y34500D01*
G01X1184842Y41033D02*
X1184266Y35000D01*
G01X1184844Y41033D02*
X1184842D01*
G01X1208267Y72992D02*
Y71900D01*
G01X1208785Y73510D02*
X1208267Y72992D01*
G01X1208785Y74390D02*
Y73510D01*
G01X1208267Y74908D02*
X1208785Y74390D01*
G01X1208267Y78833D02*
Y74908D01*
G01X1208269Y78833D02*
X1208267D01*
G01X1214960Y73592D02*
X1214574Y71500D01*
G01X1214960Y78833D02*
Y73592D01*
G01X1214962Y78833D02*
X1214960D01*
G01X1168110Y60723D02*
Y65699D01*
G01X1168112Y60723D02*
X1168110D01*
G01X1184524Y75500D02*
X1184142Y71500D01*
G01X1184842Y78833D02*
X1184524Y75500D01*
G01X1184844Y78833D02*
X1184842D01*
G01X1171456Y72992D02*
Y71900D01*
G01X1171974Y73510D02*
X1171456Y72992D01*
G01X1171974Y74390D02*
Y73510D01*
G01X1171456Y74908D02*
X1171974Y74390D01*
G01X1171456Y78833D02*
Y74908D01*
G01X1171458Y78833D02*
X1171456D01*
G01X1204921Y60723D02*
Y65699D01*
G01X1204923Y60723D02*
X1204921D01*
G01X1218307D02*
Y65699D01*
G01X1218309Y60723D02*
X1218307D01*
G01X1208267Y35192D02*
Y34100D01*
G01X1208785Y35710D02*
X1208267Y35192D01*
G01X1208785Y36590D02*
Y35710D01*
G01X1208267Y37108D02*
X1208785Y36590D01*
G01X1208267Y41033D02*
Y37108D01*
G01X1208269Y41033D02*
X1208267D01*
G01X1177911Y34500D02*
X1177763Y33700D01*
G01X1178003Y35000D02*
X1177911Y34500D01*
G01X1178149Y35792D02*
X1178003Y35000D01*
G01X1178149Y41033D02*
Y35792D01*
G01X1178151Y41033D02*
X1178149D01*
G01X1211614Y60723D02*
Y65699D01*
G01X1211616Y60723D02*
X1211614D01*
G01X1201575Y41032D02*
X1201576Y41033D01*
G01X1201575Y37200D02*
Y41032D01*
G01X1202095Y36680D02*
X1201575Y37200D01*
G01X1202095Y35820D02*
Y36680D01*
G01X1201575Y35300D02*
X1202095Y35820D01*
G01X1201575Y34101D02*
Y35300D01*
G01X1201574Y34100D02*
X1201575Y34101D01*
G01Y78832D02*
X1201576Y78833D01*
G01X1201575Y75000D02*
Y78832D01*
G01X1202095Y74480D02*
X1201575Y75000D01*
G01X1202095Y73620D02*
Y74480D01*
G01X1201575Y73100D02*
X1202095Y73620D01*
G01X1201575Y71901D02*
Y73100D01*
G01X1201574Y71900D02*
X1201575Y71901D01*
G01X1161632Y114668D02*
Y112357D01*
G01X1158500Y117800D02*
X1161632Y114668D01*
G01X1158500Y122500D02*
Y117800D01*
G01Y127800D02*
Y122500D01*
G01X1167925Y118599D02*
Y112357D01*
G01X1167275Y119249D02*
X1167925Y118599D01*
G01X1164750Y119249D02*
X1167275D01*
G01X1164100Y119899D02*
X1164750Y119249D01*
G01X1164100Y121249D02*
Y119899D01*
G01X1164750Y121899D02*
X1164100Y121249D01*
G01X1167275Y121899D02*
X1164750D01*
G01X1167925Y122549D02*
X1167275Y121899D01*
G01X1167925Y124850D02*
Y122549D01*
G01X1167275Y125500D02*
X1167925Y124850D01*
G01X1164450Y125500D02*
X1167275D01*
G01X1163800Y126150D02*
X1164450Y125500D01*
G01X1163800Y127523D02*
Y126150D01*
G01X1164450Y128173D02*
X1163800Y127523D01*
G01X1165400Y128173D02*
X1164450D01*
G01X1166050Y128823D02*
X1165400Y128173D01*
G01X1166050Y130500D02*
Y128823D01*
G01Y134850D02*
Y130500D01*
G01X1204755Y145427D02*
Y139000D01*
G01X1181200Y168982D02*
X1204755Y145427D01*
G01X1199779Y109109D02*
X1201574Y107314D01*
G01X1199779Y110879D02*
Y109109D01*
G01X1200700Y111800D02*
X1199779Y110879D01*
G01X1200700Y127300D02*
Y111800D01*
G01X1204755Y131355D02*
X1200700Y127300D01*
G01X1204755Y139000D02*
Y131355D01*
G01X1174783Y150316D02*
X1165700Y159399D01*
G01X1174783Y149020D02*
Y150316D01*
G01X1171992Y146229D02*
X1174783Y149020D01*
G01X1171992Y145507D02*
Y146229D01*
G01X1173074Y144425D02*
X1171992Y145507D01*
G01X1173782Y144425D02*
X1173074D01*
G01X1176893Y147536D02*
X1173782Y144425D01*
G01X1177601Y147536D02*
X1176893D01*
G01X1179015Y146122D02*
X1177601Y147536D01*
G01X1179015Y145414D02*
Y146122D01*
G01X1177705Y144104D02*
X1179015Y145414D01*
G01X1177705Y143394D02*
Y144104D01*
G01X1178971Y142128D02*
X1177705Y143394D01*
G01X1179679Y142128D02*
X1178971D01*
G01X1180990Y143439D02*
X1179679Y142128D01*
G01X1181698Y143439D02*
X1180990D01*
G01X1183355Y141782D02*
X1181698Y143439D01*
G01X1183355Y141074D02*
Y141782D01*
G01X1179800Y137519D02*
X1183355Y141074D01*
G01X1179800Y135231D02*
Y137519D01*
G01X1182081Y132950D02*
X1179800Y135231D01*
G01X1182081Y131553D02*
Y132950D01*
G01X1180100Y129572D02*
X1182081Y131553D01*
G01X1180100Y113753D02*
Y129572D01*
G01X1181496Y112357D02*
X1180100Y113753D01*
G01X1162936Y106964D02*
X1164428D01*
G01X1162300Y107600D02*
X1162936Y106964D01*
G01X1162300Y110348D02*
Y107600D01*
G01X1164289Y112337D02*
X1162300Y110348D01*
G01X1164289Y116110D02*
Y112337D01*
G01X1161100Y119299D02*
X1164289Y116110D01*
G01X1161100Y133000D02*
Y119299D01*
G01Y135675D02*
Y133000D01*
G01X1209819Y147491D02*
Y140500D01*
G01X1183710Y173600D02*
X1209819Y147491D01*
G01X1206628Y107314D02*
X1208267D01*
G01X1205500Y108442D02*
X1206628Y107314D01*
G01X1205500Y110201D02*
Y108442D01*
G01X1207000Y111701D02*
X1205500Y110201D01*
G01X1207000Y116383D02*
Y111701D01*
G01X1210818Y120201D02*
X1207000Y116383D01*
G01X1210818Y130444D02*
Y120201D01*
G01X1209819Y131443D02*
X1210818Y130444D01*
G01X1209819Y140500D02*
Y131443D01*
G01X1176519Y115781D02*
Y125000D01*
G01X1177581Y114719D02*
X1176519Y115781D01*
G01X1177581Y112281D02*
Y114719D01*
G01X1175874Y110574D02*
X1177581Y112281D01*
G01X1175874Y109289D02*
Y110574D01*
G01X1177849Y107314D02*
X1175874Y109289D01*
G01X1171096Y150304D02*
X1163168Y158232D01*
G01X1171096Y149596D02*
Y150304D01*
G01X1169604Y148104D02*
X1171096Y149596D01*
G01X1168896Y148104D02*
X1169604D01*
G01X1167936Y149064D02*
X1168896Y148104D01*
G01X1167228Y149064D02*
X1167936D01*
G01X1166036Y147872D02*
X1167228Y149064D01*
G01X1166036Y147024D02*
Y147872D01*
G01X1176519Y136541D02*
X1166036Y147024D01*
G01X1176519Y125000D02*
Y136541D01*
G01X1182811Y113689D02*
Y119500D01*
G01X1183300Y113200D02*
X1182811Y113689D01*
G01X1183300Y111500D02*
Y113200D01*
G01X1181300Y109500D02*
X1183300Y111500D01*
G01X1181300Y107600D02*
Y109500D01*
G01X1179100Y105400D02*
X1181300Y107600D01*
G01X1179100Y102850D02*
Y105400D01*
G01X1179750Y102200D02*
X1179100Y102850D01*
G01X1182250Y102200D02*
X1179750D01*
G01X1184142Y104092D02*
X1182250Y102200D01*
G01X1184142Y106964D02*
Y104092D01*
G01X1186050Y142650D02*
X1168300Y160400D01*
G01X1186050Y139664D02*
Y142650D01*
G01X1184600Y138214D02*
X1186050Y139664D01*
G01X1184600Y130509D02*
Y138214D01*
G01X1182811Y128720D02*
X1184600Y130509D01*
G01X1182811Y119500D02*
Y128720D01*
G01X1207300Y146446D02*
Y133500D01*
G01X1182546Y171200D02*
X1207300Y146446D01*
G01X1203219Y114059D02*
X1204921Y112357D01*
G01X1203219Y126062D02*
Y114059D01*
G01X1203857Y126700D02*
X1203219Y126062D01*
G01X1205259Y126700D02*
X1203857D01*
G01X1205759Y126200D02*
X1205259Y126700D01*
G01X1205759Y122900D02*
Y126200D01*
G01X1206259Y122400D02*
X1205759Y122900D01*
G01X1207799Y122400D02*
X1206259D01*
G01X1208299Y122900D02*
X1207799Y122400D01*
G01X1208299Y129400D02*
Y122900D01*
G01X1207300Y130399D02*
X1208299Y129400D01*
G01X1207300Y133500D02*
Y130399D01*
G01X1157754Y155746D02*
Y156454D01*
G01X1158737Y154763D02*
X1157754Y155746D01*
G01X1159657Y154763D02*
X1158737D01*
G01X1160458Y155564D02*
X1159657Y154763D01*
G01X1161378Y155564D02*
X1160458D01*
G01X1165311Y151631D02*
X1161378Y155564D01*
G01X1165311Y150711D02*
Y151631D01*
G01X1164434Y149834D02*
X1165311Y150711D01*
G01X1163514Y149834D02*
X1164434D01*
G01X1161378Y151970D02*
X1163514Y149834D01*
G01X1160458Y151970D02*
X1161378D01*
G01X1159504Y151016D02*
X1160458Y151970D01*
G01X1159504Y149992D02*
Y151016D01*
G01X1174000Y135496D02*
X1159504Y149992D01*
G01X1174000Y132500D02*
Y135496D01*
G01Y113099D02*
Y132500D01*
G01X1174742Y112357D02*
X1174000Y113099D01*
G01X1198228Y113973D02*
Y112357D01*
G01X1196936Y115265D02*
X1198228Y113973D01*
G01X1196936Y120500D02*
Y115265D01*
G01Y137150D02*
Y120500D01*
G01X1197586Y137800D02*
X1196936Y137150D01*
G01X1198936Y137800D02*
X1197586D01*
G01X1199586Y137150D02*
X1198936Y137800D01*
G01X1199586Y134350D02*
Y137150D01*
G01X1200236Y133700D02*
X1199586Y134350D01*
G01X1201586Y133700D02*
X1200236D01*
G01X1202236Y134350D02*
X1201586Y133700D01*
G01X1202236Y143219D02*
Y134350D01*
G01X1201586Y143869D02*
X1202236Y143219D01*
G01X1197586Y143869D02*
X1201586D01*
G01X1196936Y144519D02*
X1197586Y143869D01*
G01X1196936Y149683D02*
Y144519D01*
G01X1179300Y167319D02*
X1196936Y149683D01*
G01X1170660Y134140D02*
Y117000D01*
G01X1172700Y108943D02*
X1170721Y106964D01*
G01X1172700Y110320D02*
Y108943D01*
G01X1170660Y112360D02*
X1172700Y110320D01*
G01X1170660Y117000D02*
Y112360D01*
G01X1165700Y165812D02*
X1165718Y165830D01*
G01X1165700Y159399D02*
Y165812D01*
G01X1163168Y158232D02*
Y166768D01*
G01X1168300Y165406D02*
X1168268Y165438D01*
G01X1168300Y160400D02*
Y165406D01*
G01X1160618Y159318D02*
Y167318D01*
G01X1157754Y156454D02*
X1160618Y159318D01*
G01X1172000Y461000D02*
Y467499D01*
G01X1159500Y448500D02*
X1172000Y461000D01*
G01X1159500Y445100D02*
Y448500D01*
G01X1165200Y439400D02*
X1159500Y445100D01*
G01X1165200Y438200D02*
Y439400D01*
G01X1186700Y456750D02*
Y488900D01*
G01X1186050Y456100D02*
X1186700Y456750D01*
G01X1184700Y456100D02*
X1186050D01*
G01X1184050Y456750D02*
X1184700Y456100D01*
G01X1184050Y463150D02*
Y456750D01*
G01X1183400Y463800D02*
X1184050Y463150D01*
G01X1182050Y463800D02*
X1183400D01*
G01X1181400Y463150D02*
X1182050Y463800D01*
G01X1181400Y445700D02*
Y463150D01*
G01X1172400Y436700D02*
X1181400Y445700D01*
G01X1200304Y443004D02*
Y471904D01*
G01X1198045Y440745D02*
X1200304Y443004D01*
G01X1196345Y440745D02*
X1198045D01*
G01X1195321Y439721D02*
X1196345Y440745D01*
G01X1195321Y438021D02*
Y439721D01*
G01X1194297Y436997D02*
X1195321Y438021D01*
G01X1192597Y436997D02*
X1194297D01*
G01X1191573Y435973D02*
X1192597Y436997D01*
G01X1191573Y434273D02*
Y435973D01*
G01X1190549Y433249D02*
X1191573Y434273D01*
G01X1188849Y433249D02*
X1190549D01*
G01X1187825Y432225D02*
X1188849Y433249D01*
G01X1187825Y430525D02*
Y432225D01*
G01X1186700Y429400D02*
X1187825Y430525D01*
G01X1185168Y429400D02*
X1186700D01*
G01X1182850Y427082D02*
X1185168Y429400D01*
G01X1177600Y451501D02*
Y465200D01*
G01X1177215Y451116D02*
X1177600Y451501D01*
G01X1176119Y451116D02*
X1177215D01*
G01X1173366Y453868D02*
X1176119Y451116D01*
G01X1172270Y453868D02*
X1173366D01*
G01X1171492Y453090D02*
X1172270Y453868D01*
G01X1171492Y451994D02*
Y453090D01*
G01X1176300Y447188D02*
X1171492Y451994D01*
G01X1176300Y445401D02*
Y447188D01*
G01X1170400Y439501D02*
X1176300Y445401D01*
G01X1170400Y438001D02*
Y439501D01*
G01X1162105Y463288D02*
X1173000Y474183D01*
G01X1162105Y462103D02*
Y463288D01*
G01X1162755Y461453D02*
X1162105Y462103D01*
G01X1164959Y461453D02*
X1162755D01*
G01X1165609Y460803D02*
X1164959Y461453D01*
G01X1165609Y459453D02*
Y460803D01*
G01X1164959Y458803D02*
X1165609Y459453D01*
G01X1162755Y458803D02*
X1164959D01*
G01X1162105Y458153D02*
X1162755Y458803D01*
G01X1162105Y456632D02*
Y458153D01*
G01X1159331Y453858D02*
X1162105Y456632D01*
G01X1205618Y438518D02*
Y466800D01*
G01X1191000Y423900D02*
X1205618Y438518D01*
G01X1188000Y423900D02*
X1191000D01*
G01X1159532Y464295D02*
X1170440Y475203D01*
G01X1159532Y458949D02*
Y464295D01*
G01X1174700Y460100D02*
Y466200D01*
G01X1167172Y452572D02*
X1174700Y460100D01*
G01X1167172Y451474D02*
Y452572D01*
G01X1169874Y448772D02*
X1167172Y451474D01*
G01X1169874Y447674D02*
Y448772D01*
G01X1169098Y446898D02*
X1169874Y447674D01*
G01X1168000Y446898D02*
X1169098D01*
G01X1165298Y449600D02*
X1168000Y446898D01*
G01X1164200Y449600D02*
X1165298D01*
G01X1162700Y448100D02*
X1164200Y449600D01*
G01X1162700Y445700D02*
Y448100D01*
G01X1167800Y440600D02*
X1162700Y445700D01*
G01X1167800Y437650D02*
Y440600D01*
G01X1188150Y426650D02*
X1186950D01*
G01X1202961Y441461D02*
X1188150Y426650D01*
G01X1202961Y464997D02*
Y441461D01*
G01X1197647Y446047D02*
Y474947D01*
G01X1180596Y428996D02*
X1197647Y446047D01*
G01X1176000Y496590D02*
X1174203Y498387D01*
G01X1176000Y489900D02*
Y496590D01*
G01X1176400Y489500D02*
X1176000Y489900D01*
G01X1176400Y471899D02*
Y489500D01*
G01X1172000Y467499D02*
X1176400Y471899D01*
G01X1204921Y523923D02*
Y528899D01*
G01X1204923Y523900D02*
X1204921Y523923D01*
G01X1185574Y493394D02*
X1184142D01*
G01X1186074Y492894D02*
X1185574Y493394D01*
G01X1186074Y489526D02*
Y492894D01*
G01X1186700Y488900D02*
X1186074Y489526D01*
G01X1163100Y496804D02*
X1161417Y498487D01*
G01X1163100Y495000D02*
Y496804D01*
G01X1162200Y494100D02*
X1163100Y495000D01*
G01X1162200Y488200D02*
Y494100D01*
G01X1165252Y485148D02*
X1162200Y488200D01*
G01X1165252Y477851D02*
Y485148D01*
G01X1164202Y476801D02*
X1165252Y477851D01*
G01X1163227Y476801D02*
X1164202D01*
G01X1162703Y477325D02*
X1163227Y476801D01*
G01X1161727Y477325D02*
X1162703D01*
G01X1160799Y476397D02*
X1161727Y477325D01*
G01X1160799Y475423D02*
Y476397D01*
G01X1161324Y474898D02*
X1160799Y475423D01*
G01X1161325Y473924D02*
X1161324Y474898D01*
G01X1161417Y523923D02*
Y528899D01*
G01X1161419Y523900D02*
X1161417Y523923D01*
G01X1203500Y493344D02*
X1200974D01*
G01X1204000Y492844D02*
X1203500Y493344D01*
G01X1204000Y489020D02*
Y492844D01*
G01X1204500Y488520D02*
X1204000Y489020D01*
G01X1204630Y488520D02*
X1204500D01*
G01X1205131Y488019D02*
X1204630Y488520D01*
G01X1205131Y480502D02*
Y488019D01*
G01X1204481Y479852D02*
X1205131Y480502D01*
G01X1203716Y479852D02*
X1204481D01*
G01X1203066Y479202D02*
X1203716Y479852D01*
G01X1203066Y477262D02*
Y479202D01*
G01X1203716Y476612D02*
X1203066Y477262D01*
G01X1204481Y476612D02*
X1203716D01*
G01X1205259Y475834D02*
X1204481Y476612D01*
G01X1205259Y474259D02*
Y475834D01*
G01X1203728Y472728D02*
X1205259Y474259D01*
G01X1201128Y472728D02*
X1203728D01*
G01X1200304Y471904D02*
X1201128Y472728D01*
G01X1181596Y498387D02*
X1180400D01*
G01X1182274Y497709D02*
X1181596Y498387D01*
G01X1182274Y486927D02*
Y497709D01*
G01X1184000Y485201D02*
X1182274Y486927D01*
G01X1184000Y471600D02*
Y485201D01*
G01X1177600Y465200D02*
X1184000Y471600D01*
G01X1218307Y523923D02*
Y528899D01*
G01X1218309Y523900D02*
X1218307Y523923D01*
G01X1172500Y492000D02*
X1170656Y493844D01*
G01X1172500Y488800D02*
Y492000D01*
G01X1173000Y488300D02*
X1172500Y488800D01*
G01X1173000Y474183D02*
Y488300D01*
G01X1210287Y496144D02*
X1208267D01*
G01X1212154Y494277D02*
X1210287Y496144D01*
G01X1212154Y490777D02*
Y494277D01*
G01X1210445Y489068D02*
X1212154Y490777D01*
G01X1210445Y471627D02*
Y489068D01*
G01X1205618Y466800D02*
X1210445Y471627D01*
G01X1174803Y523923D02*
Y528899D01*
G01X1174805Y523900D02*
X1174803Y523923D01*
G01X1181496D02*
Y528899D01*
G01X1181498Y523900D02*
X1181496Y523923D01*
G01X1169300Y496697D02*
X1167510Y498487D01*
G01X1169300Y495000D02*
Y496697D01*
G01X1168800Y494500D02*
X1169300Y495000D01*
G01X1168800Y488800D02*
Y494500D01*
G01X1170440Y487160D02*
X1168800Y488800D01*
G01X1170440Y475203D02*
Y487160D01*
G01X1211614Y523923D02*
Y528899D01*
G01X1211616Y523900D02*
X1211614Y523923D01*
G01X1168110D02*
Y528899D01*
G01X1168112Y523900D02*
X1168110Y523923D01*
G01X1166200Y491907D02*
X1164363Y493744D01*
G01X1166200Y487800D02*
Y491907D01*
G01X1167909Y486091D02*
X1166200Y487800D01*
G01X1167909Y476408D02*
Y486091D01*
G01X1179724Y491619D02*
X1177799Y493544D01*
G01X1179724Y488224D02*
Y491619D01*
G01X1179257Y487757D02*
X1179724Y488224D01*
G01X1179257Y470757D02*
Y487757D01*
G01X1174700Y466200D02*
X1179257Y470757D01*
G01X1198228Y523923D02*
Y528899D01*
G01X1198230Y523900D02*
X1198228Y523923D01*
G01X1204521Y498487D02*
X1204400D01*
G01X1206400Y496608D02*
X1204521Y498487D01*
G01X1206400Y492426D02*
Y496608D01*
G01X1207788Y491038D02*
X1206400Y492426D01*
G01X1207788Y472988D02*
Y491038D01*
G01X1202961Y468161D02*
X1207788Y472988D01*
G01X1202961Y464997D02*
Y468161D01*
G01X1198315Y498400D02*
X1198100D01*
G01X1199900Y496815D02*
X1198315Y498400D01*
G01X1199900Y494900D02*
Y496815D01*
G01X1198900Y493900D02*
X1199900Y494900D01*
G01X1198900Y485200D02*
Y493900D01*
G01X1200490Y483610D02*
X1198900Y485200D01*
G01X1200490Y477790D02*
Y483610D01*
G01X1197647Y474947D02*
X1200490Y477790D01*
G01X1178149Y579810D02*
X1178151D01*
G01X1178149Y574592D02*
Y579810D01*
G01X1177763Y572500D02*
X1178149Y574592D01*
G01X1181496Y561723D02*
Y566699D01*
G01X1181498Y561700D02*
X1181496Y561723D01*
G01X1201575Y535101D02*
X1201574Y535100D01*
G01X1201575Y536300D02*
Y535101D01*
G01X1202095Y536820D02*
X1201575Y536300D01*
G01X1202095Y537680D02*
Y536820D01*
G01X1201575Y538200D02*
X1202095Y537680D01*
G01X1201575Y542010D02*
Y538200D01*
G01X1201576Y542010D02*
X1201575D01*
G01X1218307Y561723D02*
Y566699D01*
G01X1218309Y561700D02*
X1218307Y561723D01*
G01X1178149Y536792D02*
X1177763Y534700D01*
G01X1178149Y542010D02*
Y536792D01*
G01X1178151Y542010D02*
X1178149D01*
G01X1208267Y536192D02*
Y535100D01*
G01X1208785Y536710D02*
X1208267Y536192D01*
G01X1208785Y537590D02*
Y536710D01*
G01X1208267Y538108D02*
X1208785Y537590D01*
G01X1208267Y542010D02*
Y538108D01*
G01X1208269Y542010D02*
X1208267D01*
G01X1164764Y572901D02*
X1164763Y572900D01*
G01X1164764Y574100D02*
Y572901D01*
G01X1165284Y574620D02*
X1164764Y574100D01*
G01X1165284Y575480D02*
Y574620D01*
G01X1164764Y576000D02*
X1165284Y575480D01*
G01X1164764Y579810D02*
Y576000D01*
G01X1164765Y579810D02*
X1164764D01*
G01X1214960Y574592D02*
X1214574Y572500D01*
G01X1214960Y579810D02*
Y574592D01*
G01X1214962Y579810D02*
X1214960D01*
G01X1184842Y542033D02*
X1184142Y534700D01*
G01X1184844Y542010D02*
X1184842Y542033D01*
G01X1198228Y561723D02*
Y566699D01*
G01X1198230Y561700D02*
X1198228Y561723D01*
G01X1214960Y536792D02*
X1214574Y534700D01*
G01X1214960Y542010D02*
Y536792D01*
G01X1214962Y542010D02*
X1214960D01*
G01X1184842Y579833D02*
X1184142Y572500D01*
G01X1184844Y579810D02*
X1184842Y579833D01*
G01X1168110Y561723D02*
Y566699D01*
G01X1168112Y561700D02*
X1168110Y561723D01*
G01X1164764Y535101D02*
X1164763Y535100D01*
G01X1164764Y536300D02*
Y535101D01*
G01X1165284Y536820D02*
X1164764Y536300D01*
G01X1165284Y537680D02*
Y536820D01*
G01X1164764Y538200D02*
X1165284Y537680D01*
G01X1164764Y542010D02*
Y538200D01*
G01X1164765Y542010D02*
X1164764D01*
G01X1204921Y561723D02*
Y566699D01*
G01X1204923Y561700D02*
X1204921Y561723D01*
G01X1171456Y536192D02*
Y535100D01*
G01X1171974Y536710D02*
X1171456Y536192D01*
G01X1171974Y537590D02*
Y536710D01*
G01X1171456Y538108D02*
X1171974Y537590D01*
G01X1171456Y542010D02*
Y538108D01*
G01X1171458Y542010D02*
X1171456D01*
G01Y573992D02*
Y572900D01*
G01X1171974Y574510D02*
X1171456Y573992D01*
G01X1171974Y575390D02*
Y574510D01*
G01X1171456Y575908D02*
X1171974Y575390D01*
G01X1171456Y579810D02*
Y575908D01*
G01X1171458Y579810D02*
X1171456D01*
G01X1161417Y561723D02*
Y566699D01*
G01X1161419Y561700D02*
X1161417Y561723D01*
G01X1211614D02*
Y566699D01*
G01X1211616Y561700D02*
X1211614Y561723D01*
G01X1174803D02*
Y566699D01*
G01X1174805Y561700D02*
X1174803Y561723D01*
G01X1208267Y573992D02*
Y572900D01*
G01X1208785Y574510D02*
X1208267Y573992D01*
G01X1208785Y575390D02*
Y574510D01*
G01X1208267Y575908D02*
X1208785Y575390D01*
G01X1208267Y579810D02*
Y575908D01*
G01X1208269Y579810D02*
X1208267D01*
G01X1201575Y572901D02*
X1201574Y572900D01*
G01X1201575Y574100D02*
Y572901D01*
G01X1202095Y574620D02*
X1201575Y574100D01*
G01X1202095Y575480D02*
Y574620D01*
G01X1201575Y576000D02*
X1202095Y575480D01*
G01X1201575Y579810D02*
Y576000D01*
G01X1201576Y579810D02*
X1201575D01*
G01Y617610D02*
X1201576D01*
G01X1201575Y613800D02*
Y617610D01*
G01X1202095Y613280D02*
X1201575Y613800D01*
G01X1202095Y612420D02*
Y613280D01*
G01X1201575Y611900D02*
X1202095Y612420D01*
G01X1201575Y610701D02*
Y611900D01*
G01X1201574Y610700D02*
X1201575Y610701D01*
G01X1171456Y611792D02*
Y610700D01*
G01X1171974Y612310D02*
X1171456Y611792D01*
G01X1171974Y613190D02*
Y612310D01*
G01X1171456Y613708D02*
X1171974Y613190D01*
G01X1171456Y617610D02*
Y613708D01*
G01X1171458Y617610D02*
X1171456D01*
G01X1181496Y599523D02*
Y604499D01*
G01X1181498Y599500D02*
X1181496Y599523D01*
G01X1184529Y614358D02*
X1184142Y610300D01*
G01X1184842Y617633D02*
X1184529Y614358D01*
G01X1184844Y617610D02*
X1184842Y617633D01*
G01X1218307Y599523D02*
Y604499D01*
G01X1218309Y599500D02*
X1218307Y599523D01*
G01X1204921D02*
Y604499D01*
G01X1204923Y599500D02*
X1204921Y599523D01*
G01X1208267Y617610D02*
X1208269D01*
G01X1208267Y613708D02*
Y617610D01*
G01X1208785Y613190D02*
X1208267Y613708D01*
G01X1208785Y612310D02*
Y613190D01*
G01X1208267Y611792D02*
X1208785Y612310D01*
G01X1208267Y610700D02*
Y611792D01*
G01X1211614Y599523D02*
Y604499D01*
G01X1211616Y599500D02*
X1211614Y599523D01*
G01X1178149Y612392D02*
X1177763Y610300D01*
G01X1178149Y617610D02*
Y612392D01*
G01X1178151Y617610D02*
X1178149D01*
G01X1161417Y599523D02*
Y604499D01*
G01X1161419Y599500D02*
X1161417Y599523D01*
G01X1198228D02*
Y604499D01*
G01X1198230Y599500D02*
X1198228Y599523D01*
G01X1168110D02*
Y604499D01*
G01X1168112Y599500D02*
X1168110Y599523D01*
G01X1174803D02*
Y604499D01*
G01X1174805Y599500D02*
X1174803Y599523D01*
G01X1214960Y617610D02*
X1214962D01*
G01X1214960Y612392D02*
Y617610D01*
G01X1214574Y610300D02*
X1214960Y612392D01*
G01X1164764Y610701D02*
X1164763Y610700D01*
G01X1164764Y611900D02*
Y610701D01*
G01X1165284Y612420D02*
X1164764Y611900D01*
G01X1165284Y613280D02*
Y612420D01*
G01X1164764Y613800D02*
X1165284Y613280D01*
G01X1164764Y617610D02*
Y613800D01*
G01X1164765Y617610D02*
X1164764D01*
G01X1235039Y22923D02*
Y27899D01*
G01X1235041Y22923D02*
X1235039D01*
G01X1241732Y-14877D02*
Y-9901D01*
G01X1241734Y-14877D02*
X1241732D01*
G01X1235039D02*
Y-9901D01*
G01X1235041Y-14877D02*
X1235039D01*
G01X1245078Y-2608D02*
Y-3700D01*
G01X1245596Y-2090D02*
X1245078Y-2608D01*
G01X1245596Y-1210D02*
Y-2090D01*
G01X1245078Y-692D02*
X1245596Y-1210D01*
G01X1245078Y3233D02*
Y-692D01*
G01X1245080Y3233D02*
X1245078D01*
G01X1241732Y22923D02*
Y27899D01*
G01X1241734Y22923D02*
X1241732D01*
G01X1238386Y-3699D02*
X1238385Y-3700D01*
G01X1238386Y-2500D02*
Y-3699D01*
G01X1238906Y-1980D02*
X1238386Y-2500D01*
G01X1238906Y-1120D02*
Y-1980D01*
G01X1238386Y-600D02*
X1238906Y-1120D01*
G01X1238386Y3232D02*
Y-600D01*
G01X1238387Y3233D02*
X1238386Y3232D01*
G01X1221653Y3233D02*
X1220953Y-4100D01*
G01X1221655Y3233D02*
X1221653D01*
G01X1245078Y35192D02*
Y34100D01*
G01X1245596Y35710D02*
X1245078Y35192D01*
G01X1245596Y36590D02*
Y35710D01*
G01X1245078Y37108D02*
X1245596Y36590D01*
G01X1245078Y41033D02*
Y37108D01*
G01X1245080Y41033D02*
X1245078D01*
G01X1221335Y75500D02*
X1220953Y71500D01*
G01X1221653Y78833D02*
X1221335Y75500D01*
G01X1221655Y78833D02*
X1221653D01*
G01X1245078Y72992D02*
Y71900D01*
G01X1245596Y73510D02*
X1245078Y72992D01*
G01X1245596Y74390D02*
Y73510D01*
G01X1245078Y74908D02*
X1245596Y74390D01*
G01X1245080Y74910D02*
X1245078Y74908D01*
G01X1245080Y78833D02*
Y74910D01*
G01X1221029Y34500D02*
X1220953Y33700D01*
G01X1221077Y35000D02*
X1221029Y34500D01*
G01X1221653Y41033D02*
X1221077Y35000D01*
G01X1221655Y41033D02*
X1221653D01*
G01X1235041Y65697D02*
X1235039Y65699D01*
G01X1235041Y60723D02*
Y65697D01*
G01X1238386Y78832D02*
X1238387Y78833D01*
G01X1238386Y75000D02*
Y78832D01*
G01X1238906Y74480D02*
X1238386Y75000D01*
G01X1238906Y73620D02*
Y74480D01*
G01X1238386Y73100D02*
X1238906Y73620D01*
G01X1238386Y71901D02*
Y73100D01*
G01X1238385Y71900D02*
X1238386Y71901D01*
G01Y41032D02*
X1238387Y41033D01*
G01X1238386Y37200D02*
Y41032D01*
G01X1238906Y36680D02*
X1238386Y37200D01*
G01X1238906Y35820D02*
Y36680D01*
G01X1238386Y35300D02*
X1238906Y35820D01*
G01X1238386Y34101D02*
Y35300D01*
G01X1238385Y34100D02*
X1238386Y34101D01*
G01X1241734Y65697D02*
X1241732Y65699D01*
G01X1241734Y60723D02*
Y65697D01*
G01Y523900D02*
Y528897D01*
G01X1235039Y523923D02*
Y528899D01*
G01X1235041Y523900D02*
X1235039Y523923D01*
G01X1241734Y528897D02*
X1241732Y528899D01*
G01Y561723D02*
Y566699D01*
G01X1241734Y561700D02*
X1241732Y561723D01*
G01X1245078Y579810D02*
X1245080D01*
G01X1245078Y575908D02*
Y579810D01*
G01X1245596Y575390D02*
X1245078Y575908D01*
G01X1245596Y574510D02*
Y575390D01*
G01X1245078Y573992D02*
X1245596Y574510D01*
G01X1245078Y572900D02*
Y573992D01*
G01X1238386Y535101D02*
X1238385Y535100D01*
G01X1238386Y536300D02*
Y535101D01*
G01X1238906Y536820D02*
X1238386Y536300D01*
G01X1238906Y537680D02*
Y536820D01*
G01X1238386Y538200D02*
X1238906Y537680D01*
G01X1238386Y542010D02*
Y538200D01*
G01X1238387Y542010D02*
X1238386D01*
G01X1221653Y579833D02*
X1220953Y572500D01*
G01X1221655Y579810D02*
X1221653Y579833D01*
G01Y542033D02*
X1220953Y534700D01*
G01X1221655Y542010D02*
X1221653Y542033D01*
G01X1235039Y561723D02*
Y566699D01*
G01X1235041Y561700D02*
X1235039Y561723D01*
G01X1245078Y536192D02*
Y535100D01*
G01X1245596Y536710D02*
X1245078Y536192D01*
G01X1245596Y537590D02*
Y536710D01*
G01X1245078Y538108D02*
X1245596Y537590D01*
G01X1245080Y538110D02*
X1245078Y538108D01*
G01X1245080Y542010D02*
Y538110D01*
G01X1238386Y572901D02*
X1238385Y572900D01*
G01X1238386Y574100D02*
Y572901D01*
G01X1238906Y574620D02*
X1238386Y574100D01*
G01X1238906Y575480D02*
Y574620D01*
G01X1238386Y576000D02*
X1238906Y575480D01*
G01X1238386Y579810D02*
Y576000D01*
G01X1238387Y579810D02*
X1238386D01*
G01X1221340Y614358D02*
X1220953Y610300D01*
G01X1221653Y617633D02*
X1221340Y614358D01*
G01X1221655Y617610D02*
X1221653Y617633D01*
G01X1238386Y617610D02*
X1238387D01*
G01X1238386Y613800D02*
Y617610D01*
G01X1238906Y613280D02*
X1238386Y613800D01*
G01X1238906Y612420D02*
Y613280D01*
G01X1238386Y611900D02*
X1238906Y612420D01*
G01X1238386Y610701D02*
Y611900D01*
G01X1238385Y610700D02*
X1238386Y610701D01*
G01X1235039Y599523D02*
Y604499D01*
G01X1235041Y599500D02*
X1235039Y599523D01*
G01X1245078Y611792D02*
Y610700D01*
G01X1245596Y612310D02*
X1245078Y611792D01*
G01X1245596Y613190D02*
Y612310D01*
G01X1245078Y613708D02*
X1245596Y613190D01*
G01X1245078Y617610D02*
Y613708D01*
G01X1245080Y617610D02*
X1245078D01*
G01X1241732Y599523D02*
Y604499D01*
G01X1241734Y599500D02*
X1241732Y599523D01*
G54D14*
G01X-14722Y453312D02*
X-17014Y455604D01*
G01X-15960Y499300D02*
X-16766Y500106D01*
G01X-13400Y499300D02*
X-15960D01*
G01X-16804Y506300D02*
X-14000D01*
G01X-17302Y506798D02*
X-16804Y506300D01*
G01X-17585Y501769D02*
X-15431D01*
G01X-18900Y500454D02*
X-17585Y501769D01*
G01X-18900Y498800D02*
Y500454D01*
G01X-17500Y497400D02*
X-18900Y498800D01*
G01X-16700Y497400D02*
X-17500D01*
G01X-16000Y513300D02*
X-17200D01*
G01X-15000Y512300D02*
X-16000Y513300D01*
G01X-17200D02*
Y510800D01*
G01X-20600Y507400D02*
X-17200Y510800D01*
G01X-20600Y492200D02*
Y507400D01*
G01X-17900Y489500D02*
X-20600Y492200D01*
G01X-16500Y489500D02*
X-17900D01*
G01X-16500Y494600D02*
Y493000D01*
G01X-15400Y495700D02*
X-16500Y494600D01*
G01X44500Y-56250D02*
X40500Y-52250D01*
G01X144980Y-56250D02*
X44500D01*
G01X45981Y22424D02*
X46550Y21855D01*
G01X37688Y22424D02*
X45981D01*
G01X34719Y19455D02*
X37688Y22424D01*
G01X34719Y16717D02*
Y19455D01*
G01X46180Y12090D02*
X46845Y12755D01*
G01X43790Y12090D02*
X46180D01*
G01X41862Y10162D02*
X43790Y12090D01*
G01X41862Y8675D02*
Y10162D01*
G01X31599Y14409D02*
Y17909D01*
G01X37739Y19501D02*
Y16712D01*
G01X37138Y12611D02*
Y8675D01*
G01X37739Y13212D02*
X37138Y12611D01*
G01X43819Y20431D02*
X43960Y20572D01*
G01X43819Y17401D02*
Y20431D01*
G01X40796Y19954D02*
X40530Y20220D01*
G01X40796Y17406D02*
Y19954D01*
G01X43437Y10345D02*
Y8675D01*
G01X44152Y11060D02*
X43437Y10345D01*
G01X47580Y11060D02*
X44152D01*
G01X38713Y11193D02*
Y8675D01*
G01X40796Y13276D02*
X38713Y11193D01*
G01X40796Y13906D02*
Y13276D01*
G01X40287Y10257D02*
Y8675D01*
G01X43819Y13789D02*
X40287Y10257D01*
G01X43819Y13901D02*
Y13789D01*
G01X35563Y10953D02*
Y8675D01*
G01X34719Y11797D02*
X35563Y10953D01*
G01X34719Y13217D02*
Y11797D01*
G01X136Y27309D02*
X5873Y33046D01*
G01X-1347Y27309D02*
X136D01*
G01X38142Y96986D02*
X47828Y87300D01*
G01X5873Y33046D02*
X8141D01*
G01X38142Y135792D02*
Y96986D01*
G01X37037Y136897D02*
X38142Y135792D01*
G01X37037Y138425D02*
Y136897D01*
G01X36333Y154477D02*
X43056Y161200D01*
G01X36333Y147283D02*
Y154477D01*
G01X29641Y140591D02*
X36333Y147283D01*
G01X28740Y140591D02*
X29641D01*
G01X6299Y135099D02*
Y132717D01*
G01X7225Y136025D02*
X6299Y135099D01*
G01X30341Y136025D02*
X7225D01*
G01X44616Y150300D02*
X30341Y136025D01*
G01X56700Y150300D02*
X44616D01*
G01X41708Y157500D02*
X39109Y154901D01*
G01X787Y134087D02*
Y132717D01*
G01X3970Y137270D02*
X787Y134087D01*
G01X29682Y137270D02*
X3970D01*
G01X39109Y146697D02*
X29682Y137270D01*
G01X39109Y154901D02*
Y146697D01*
G01X44601Y148500D02*
X52100D01*
G01X40354Y144253D02*
X44601Y148500D01*
G01X40354Y143663D02*
Y144253D01*
G01X42869Y141148D02*
X40354Y143663D01*
G01X42869Y140558D02*
Y141148D01*
G01X42451Y140140D02*
X42869Y140558D01*
G01X41861Y140140D02*
X42451D01*
G01X39346Y142655D02*
X41861Y140140D01*
G01X38756Y142655D02*
X39346D01*
G01X38338Y142237D02*
X38756Y142655D01*
G01X38338Y141647D02*
Y142237D01*
G01X40853Y139132D02*
X38338Y141647D01*
G01X40853Y138542D02*
Y139132D01*
G01X40435Y138124D02*
X40853Y138542D01*
G01X39845Y138124D02*
X40435D01*
G01X37330Y140639D02*
X39845Y138124D01*
G01X36740Y140639D02*
X37330D01*
G01X34558Y138457D02*
X36740Y140639D01*
G01X34558Y135853D02*
Y138457D01*
G01X36260Y134151D02*
X34558Y135853D01*
G01X36260Y127730D02*
Y134151D01*
G01X35758Y127228D02*
X36260Y127730D01*
G01X33077Y127228D02*
X35758D01*
G01X32660Y127645D02*
X33077Y127228D01*
G01X32660Y129585D02*
Y127645D01*
G01X32243Y130002D02*
X32660Y129585D01*
G01X31652Y130002D02*
X32243D01*
G01X31235Y129585D02*
X31652Y130002D01*
G01X31235Y127645D02*
Y129585D01*
G01X30818Y127228D02*
X31235Y127645D01*
G01X30227Y127228D02*
X30818D01*
G01X29810Y127645D02*
X30227Y127228D01*
G01X29810Y129585D02*
Y127645D01*
G01X29393Y130002D02*
X29810Y129585D01*
G01X28802Y130002D02*
X29393D01*
G01X28385Y129585D02*
X28802Y130002D01*
G01X28385Y127645D02*
Y129585D01*
G01X27968Y127228D02*
X28385Y127645D01*
G01X27377Y127228D02*
X27968D01*
G01X26960Y127645D02*
X27377Y127228D01*
G01X26960Y129585D02*
Y127645D01*
G01X26543Y130002D02*
X26960Y129585D01*
G01X25952Y130002D02*
X26543D01*
G01X25535Y129585D02*
X25952Y130002D01*
G01X25535Y127645D02*
Y129585D01*
G01X25118Y127228D02*
X25535Y127645D01*
G01X24527Y127228D02*
X25118D01*
G01X24110Y127645D02*
X24527Y127228D01*
G01X24110Y129585D02*
Y127645D01*
G01X23693Y130002D02*
X24110Y129585D01*
G01X23102Y130002D02*
X23693D01*
G01X22685Y129585D02*
X23102Y130002D01*
G01X22685Y127645D02*
Y129585D01*
G01X22268Y127228D02*
X22685Y127645D01*
G01X21677Y127228D02*
X22268D01*
G01X21260Y127645D02*
X21677Y127228D01*
G01X21260Y129585D02*
Y127645D01*
G01X20843Y130002D02*
X21260Y129585D01*
G01X20252Y130002D02*
X20843D01*
G01X19835Y129585D02*
X20252Y130002D01*
G01X19835Y127645D02*
Y129585D01*
G01X19418Y127228D02*
X19835Y127645D01*
G01X13338Y127228D02*
X19418D01*
G01X11811Y128755D02*
X13338Y127228D01*
G01X11811Y132717D02*
Y128755D01*
G01X43056Y161200D02*
X71900D01*
G01X48300Y157500D02*
X41708D01*
G01X8000Y277500D02*
Y275500D01*
G01X8120Y277620D02*
X8000Y277500D01*
G01X8120Y280500D02*
Y277620D01*
G01X11000Y277000D02*
Y275500D01*
G01X10680Y277320D02*
X11000Y277000D01*
G01X10680Y280500D02*
Y277320D01*
G01X8000Y293500D02*
Y295500D01*
G01X8120Y293380D02*
X8000Y293500D01*
G01X8120Y290500D02*
Y293380D01*
G01X5560Y293440D02*
Y290500D01*
G01X5000Y294000D02*
X5560Y293440D01*
G01X5000Y295500D02*
Y294000D01*
G01X8000Y301153D02*
X6806Y302347D01*
G01X8000Y299000D02*
Y301153D01*
G01X5000D02*
X3806Y302347D01*
G01X5000Y299000D02*
Y301153D01*
G01X44500Y386500D02*
X56000Y398000D01*
G01X44500Y350800D02*
Y386500D01*
G01X46400Y348900D02*
X44500Y350800D01*
G01X43225Y388725D02*
X52500Y398000D01*
G01X43225Y349875D02*
Y388725D01*
G01X46591Y346509D02*
X43225Y349875D01*
G01X45800Y384300D02*
X59500Y398000D01*
G01X45800Y352700D02*
Y384300D01*
G01X46991Y351509D02*
X45800Y352700D01*
G01X42000Y391100D02*
X49000Y398100D01*
G01X42000Y349100D02*
Y391100D01*
G01X47091Y344009D02*
X42000Y349100D01*
G01X5950Y456500D02*
Y451000D01*
G01X2450Y460000D02*
X5950Y456500D01*
G01X-1278Y465508D02*
Y464071D01*
G01Y458122D02*
X-1950Y457450D01*
G01X-1278Y460571D02*
Y458122D01*
G01X-5722Y453678D02*
Y452578D01*
G01X-1950Y457450D02*
X-5722Y453678D01*
G01X46100Y416271D02*
X49800Y412571D01*
G01X-13802Y457472D02*
Y462160D01*
G01X-11620Y455290D02*
X-13802Y457472D01*
G01X-7310Y455290D02*
X-11620D01*
G01X-6700Y455900D02*
X-7310Y455290D01*
G01X-6650Y455900D02*
X-6700D01*
G01X-3400Y459150D02*
X-6650Y455900D01*
G01X-3400Y466350D02*
Y459150D01*
G01X-14722Y452578D02*
Y453312D01*
G01X-11242Y457977D02*
Y462160D01*
G01X-10095Y456830D02*
X-11242Y457977D01*
G01X-7069Y456830D02*
X-10095D01*
G01X-4350Y459549D02*
X-7069Y456830D01*
G01X-4350Y466750D02*
Y459549D01*
G01X787Y460837D02*
X6849Y466899D01*
G01X787Y458051D02*
Y460837D01*
G01X-2358Y454906D02*
X787Y458051D01*
G01X-2358Y436224D02*
Y454906D01*
G01X-4488Y434094D02*
X-2358Y436224D01*
G01X47500Y412120D02*
X46100Y413520D01*
G01X-7660Y512300D02*
X-7360Y512000D01*
G01X-10500Y512300D02*
X-7660D01*
G01X-9600Y525701D02*
Y526100D01*
G01X-8990Y525091D02*
X-9600Y525701D01*
G01X-8990Y523040D02*
Y525091D01*
G01X-7400Y505400D02*
X-6200D01*
G01X-8300Y506300D02*
X-7400Y505400D01*
G01X-10500Y506300D02*
X-8300D01*
G01X-4403Y505400D02*
X-6200D01*
G01X-3590Y504587D02*
X-4403Y505400D01*
G01X-1550Y504587D02*
X-3590D01*
G01X-13802Y476152D02*
X-11490Y473840D01*
G01X-13802Y478340D02*
Y476152D01*
G01X-8900Y501800D02*
X-6676D01*
G01X-9900Y502800D02*
X-8900Y501800D01*
G01X-2987Y503013D02*
X-1550D01*
G01X-4200Y501800D02*
X-2987Y503013D01*
G01X-6676Y501800D02*
X-4200D01*
G01X-5000Y499300D02*
X-6660D01*
G01X-2862Y501438D02*
X-5000Y499300D01*
G01X-1550Y501438D02*
X-2862D01*
G01X-6660Y499300D02*
X-9900D01*
G01X2350Y473150D02*
Y469650D01*
G01X1483Y474017D02*
X2350Y473150D01*
G01X-1093Y471441D02*
Y467071D01*
G01X1483Y474017D02*
X-1093Y471441D01*
G01Y465693D02*
X-1278Y465508D01*
G01X-1093Y467071D02*
Y465693D01*
G01X-1829Y513450D02*
X-2083Y513704D01*
G01X1013Y513450D02*
X-1829D01*
G01X-11242Y476062D02*
Y478340D01*
G01X-8760Y473580D02*
X-11242Y476062D01*
G01X-6420Y473580D02*
X-8760D01*
G01X-1000Y479000D02*
X-6420Y473580D01*
G01X-9040Y519590D02*
X-8990Y519540D01*
G01X-12690Y519590D02*
X-9040D01*
G01X-12264Y516700D02*
X-11202D01*
G01X-12690Y517126D02*
X-12264Y516700D01*
G01X-12690Y519590D02*
Y517126D01*
G01X-3174Y510887D02*
X-1550D01*
G01X-6126Y513839D02*
X-3174Y510887D01*
G01X-7583Y513839D02*
X-6126D01*
G01X-10444Y516700D02*
X-7583Y513839D01*
G01X-11202Y516700D02*
X-10444D01*
G01X-7405Y509300D02*
X-6703Y508598D01*
G01X-10500Y509300D02*
X-7405D01*
G01X-6700Y508598D02*
X-6703D01*
G01X-6700Y508600D02*
Y508598D01*
G01X-5200Y508600D02*
X-6700D01*
G01X-2762Y506162D02*
X-5200Y508600D01*
G01X-1550Y506162D02*
X-2762D01*
G01X6748Y517021D02*
X7313Y516456D01*
G01X-14400Y502800D02*
X-13400D01*
G01X-15431Y501769D02*
X-14400Y502800D01*
G01X-3000Y466750D02*
X-3400Y466350D01*
G01X-3000Y473000D02*
Y466750D01*
G01X1000Y477000D02*
X-3000Y473000D01*
G01X3200Y477000D02*
X1000D01*
G01X4530Y478330D02*
X3200Y477000D01*
G01X5100Y478330D02*
X4530D01*
G01X-5590Y518340D02*
X-2390D01*
G01X-5870Y518060D02*
X-5590Y518340D01*
G01X-5870Y516573D02*
Y518060D01*
G01X-6712Y515731D02*
X-5870Y516573D01*
G01X2588Y515138D02*
Y513450D01*
G01X710Y517016D02*
X2588Y515138D01*
G01X710Y518390D02*
Y517016D01*
G01X-1004Y518390D02*
X710D01*
G01X-1054Y518340D02*
X-1004Y518390D01*
G01X-2390Y518340D02*
X-1054D01*
G01X-5590Y523503D02*
Y521840D01*
G01X-5500Y523593D02*
X-5590Y523503D01*
G01X-5500Y524390D02*
Y523593D01*
G01X-5680Y524570D02*
X-5500Y524390D01*
G01X-14000Y509300D02*
Y512300D01*
G01D02*
X-15000D01*
G01X-3950Y467150D02*
X-4350Y466750D01*
G01X-3950Y473550D02*
Y467150D01*
G01X1500Y479000D02*
X-3950Y473550D01*
G01X2160Y479000D02*
X1500D01*
G01X13400Y487950D02*
X15200D01*
G01X10259Y484809D02*
X13400Y487950D01*
G01X10259Y479950D02*
Y484809D01*
G01X6849Y476540D02*
X10259Y479950D01*
G01X6849Y466899D02*
Y476540D01*
G01X27074Y479126D02*
X50581D01*
G01X18250Y487950D02*
X27074Y479126D01*
G01X15200Y487950D02*
X18250D01*
G01X-7300Y495700D02*
X-11685D01*
G01X-3137Y499863D02*
X-7300Y495700D01*
G01X-1550Y499863D02*
X-3137D01*
G01X-11685Y495700D02*
X-15400D01*
G01X-10404Y537800D02*
X-7335D01*
G01X-12500Y535704D02*
X-10404Y537800D01*
G01X-12500Y534300D02*
Y535704D01*
G01X-6422Y537800D02*
X-7335D01*
G01X-4520Y539702D02*
X-6422Y537800D01*
G01X-8150Y573040D02*
X-7383Y573807D01*
G01X-10110Y573040D02*
X-8150D01*
G01X-12500Y570650D02*
X-10110Y573040D01*
G01X-12500Y570300D02*
Y570650D01*
G01X-7383Y573807D02*
X-5488Y575702D01*
G01X46550Y21855D02*
Y20464D01*
G01Y18801D02*
Y20464D01*
G01X46570Y18781D02*
X46550Y18801D01*
G01X46570Y18680D02*
Y18781D01*
G01X46845Y18405D02*
X46570Y18680D01*
G01X46845Y17442D02*
Y18405D01*
G01X64355Y582D02*
Y-5240D01*
G01X63712Y1225D02*
X64355Y582D01*
G01X63712Y2888D02*
Y1225D01*
G01X46872Y17415D02*
X49880D01*
G01X46845Y17442D02*
X46872Y17415D01*
G01X80299Y-14599D02*
X82300Y-16600D01*
G01X71849Y-14599D02*
X80299D01*
G01X64355Y-7105D02*
X71849Y-14599D01*
G01X64355Y-5240D02*
Y-7105D01*
G01X46845Y12755D02*
Y13942D01*
G01X57812Y17445D02*
X62008Y13249D01*
G01X55942Y17445D02*
X57812D01*
G01X52925Y13945D02*
X55942D01*
G01X52906Y13926D02*
X52925Y13945D01*
G01X46985Y8675D02*
X46587D01*
G01X49690Y11380D02*
X46985Y8675D01*
G01X50879Y11380D02*
X49690D01*
G01X52906Y13407D02*
X50879Y11380D01*
G01X52906Y13926D02*
Y13407D01*
G01X51090Y6710D02*
Y8080D01*
G01X50492Y6112D02*
X51090Y6710D01*
G01X49150Y6112D02*
X50492D01*
G01X53704Y8216D02*
Y4716D01*
G01X51541D02*
X53704D01*
G01X51362Y4537D02*
X51541Y4716D01*
G01X49150Y4537D02*
X51362D01*
G01X58549Y2888D02*
X60212D01*
G01X58343Y2682D02*
X58549Y2888D01*
G01X54075Y2682D02*
X58343D01*
G01X53704Y3053D02*
X54075Y2682D01*
G01X53704Y4716D02*
Y3053D01*
G01Y8994D02*
Y8216D01*
G01X55060Y10350D02*
X53704Y8994D01*
G01X59564Y10350D02*
X55060D01*
G01X61689Y8225D02*
X59564Y10350D01*
G01X63261Y8225D02*
X61689D01*
G01X64769Y10693D02*
X64159Y11303D01*
G01X64769Y8651D02*
Y10693D01*
G01X64343Y8225D02*
X64769Y8651D01*
G01X63261Y8225D02*
X64343D01*
G01X51365Y-188D02*
X49150D01*
G01X52216Y663D02*
X51365Y-188D01*
G01X54323Y663D02*
X52216D01*
G01X57625Y-2639D02*
X54323Y663D01*
G01X62276Y-2639D02*
X57625D01*
G01X62536Y-2379D02*
X62276Y-2639D01*
G01X49880Y13360D02*
X47580Y11060D01*
G01X49880Y13915D02*
Y13360D01*
G01X51130Y1387D02*
X49150D01*
G01X51398Y1655D02*
X51130Y1387D01*
G01X54798Y1655D02*
X51398D01*
G01X57732Y-1279D02*
X54798Y1655D01*
G01X60353Y-1279D02*
X57732D01*
G01X61994Y362D02*
X60353Y-1279D01*
G01X86600Y-15900D02*
X87091Y-16391D01*
G01X86600Y1500D02*
Y-15900D01*
G01X87700Y2600D02*
X86600Y1500D01*
G01X87700Y80300D02*
Y2600D01*
G01X74069Y87300D02*
X76106Y89337D01*
G01X47828Y87300D02*
X74069D01*
G01X69700Y102389D02*
X82046Y90043D01*
G01X75440Y92560D02*
X87700Y80300D01*
G01X75440Y92706D02*
Y92560D01*
G01X70980Y97166D02*
X75440Y92706D01*
G01X79670Y128830D02*
X81500Y127000D01*
G01X79670Y132300D02*
Y128830D01*
G01X61800Y155400D02*
X56700Y150300D01*
G01X79600Y155400D02*
X61800D01*
G01X82298Y152702D02*
X79600Y155400D01*
G01X82298Y137852D02*
Y152702D01*
G01X91160Y128990D02*
X82298Y137852D01*
G01X91160Y123600D02*
Y128990D01*
G01X88500Y120940D02*
X91160Y123600D01*
G01X88500Y118000D02*
Y120940D01*
G01Y105936D02*
Y118000D01*
G01X87564Y105000D02*
X88500Y105936D01*
G01X84033Y138637D02*
Y156267D01*
G01X93100Y129570D02*
X84033Y138637D01*
G01X93100Y125603D02*
Y129570D01*
G01X94443Y124260D02*
X93100Y125603D01*
G01X100764Y124260D02*
X94443D01*
G01X101458Y124954D02*
X100764Y124260D01*
G01X104289Y124954D02*
X101458D01*
G01X104500Y121500D02*
Y118000D01*
G01X104300Y110957D02*
X104424Y110833D01*
G01X104300Y117800D02*
Y110957D01*
G01X104500Y118000D02*
X104300Y117800D01*
G01X104289Y123350D02*
Y124954D01*
G01X104500Y123139D02*
X104289Y123350D01*
G01X104500Y121500D02*
Y123139D01*
G01X69700Y108500D02*
Y102389D01*
G01X71300Y110100D02*
X69700Y108500D01*
G01X71300Y118200D02*
Y110100D01*
G01X70317Y119183D02*
X71300Y118200D01*
G01X70317Y143783D02*
Y119183D01*
G01X65600Y148500D02*
X70317Y143783D01*
G01X55600Y148500D02*
X65600D01*
G01X98910Y118000D02*
X101000D01*
G01X98410Y118500D02*
X98910Y118000D01*
G01X95500Y118500D02*
X98410D01*
G01X88500Y124300D02*
Y127000D01*
G01X87100Y122900D02*
X88500Y124300D01*
G01X83700Y122900D02*
X87100D01*
G01X81500Y120700D02*
X83700Y122900D01*
G01X81500Y118000D02*
Y120700D01*
G01X74400Y122000D02*
X72500D01*
G01X78400Y118000D02*
X74400Y122000D01*
G01X81500Y118000D02*
X78400D01*
G01X95190Y150741D02*
Y157410D01*
G01X89980Y145531D02*
X95190Y150741D01*
G01X95500Y141051D02*
X99980Y145531D01*
G01X95500Y127500D02*
Y141051D01*
G01X72900Y171700D02*
X72700Y171900D01*
G01X72900Y168118D02*
Y171700D01*
G01X72700Y172400D02*
Y171900D01*
G01X68768Y176332D02*
X72700Y172400D01*
G01X64187Y176332D02*
X68768D01*
G01X53600Y159300D02*
X51800Y157500D01*
G01X81000Y159300D02*
X53600D01*
G01X84033Y156267D02*
X81000Y159300D01*
G01X90949Y167800D02*
X88600D01*
G01X91600Y167149D02*
X90949Y167800D01*
G01X91600Y162300D02*
Y167149D01*
G01Y161000D02*
Y162300D01*
G01X95190Y157410D02*
X91600Y161000D01*
G01X82859Y165559D02*
X79900D01*
G01X83635Y166335D02*
X82859Y165559D01*
G01X83635Y171112D02*
Y166335D01*
G01X83184Y171563D02*
X83635Y171112D01*
G01X83184Y185601D02*
Y171563D01*
G01X86731Y189148D02*
X83184Y185601D01*
G01X101500Y324000D02*
X100000Y322500D01*
G01X101500Y326133D02*
Y324000D01*
G01X100673Y326960D02*
X101500Y326133D01*
G01X100673Y331933D02*
Y326960D01*
G01X100106Y332500D02*
X100673Y331933D01*
G01X97250Y332500D02*
X100106D01*
G01X100350Y312400D02*
X102450D01*
G01X98337Y314413D02*
X100350Y312400D01*
G01X98337Y321677D02*
Y314413D01*
G01X99160Y322500D02*
X98337Y321677D01*
G01X100000Y322500D02*
X99160D01*
G01X97250Y334298D02*
Y332500D01*
G01X101339Y338387D02*
X97250Y334298D01*
G01X102067Y338387D02*
X101339D01*
G01X85800Y307200D02*
X84300Y305700D01*
G01X85800Y307800D02*
Y307200D01*
G01X87500Y309500D02*
X85800Y307800D01*
G01X84300Y305200D02*
Y305700D01*
G01X82025Y302925D02*
X84300Y305200D01*
G01X80750Y302925D02*
X82025D01*
G01X53150Y302700D02*
X53250Y302800D01*
G01X52412Y302700D02*
X53150D01*
G01X50900Y301188D02*
X52412Y302700D01*
G01X50900Y298800D02*
Y301188D01*
G01X54600Y304000D02*
X56000D01*
G01X53400Y302800D02*
X54600Y304000D01*
G01X53250Y302800D02*
X53400D01*
G01X57000Y304000D02*
X56000D01*
G01X57500Y304500D02*
X57000Y304000D01*
G01X59501Y304500D02*
X57500D01*
G01X61076Y302925D02*
X59501Y304500D01*
G01X62250Y302925D02*
X61076D01*
G01X60300Y307950D02*
X55500Y312750D01*
G01X60300Y306001D02*
Y307950D01*
G01X61406Y304895D02*
X60300Y306001D01*
G01X62250Y304895D02*
X61406D01*
G01X72000Y341800D02*
Y338800D01*
G01X90297Y302997D02*
X88600D01*
G01X91000Y303700D02*
X90297Y302997D01*
G01X91000Y306000D02*
Y303700D01*
G01X104250Y329140D02*
X103200Y330190D01*
G01X104250Y327382D02*
Y329140D01*
G01X103500Y326632D02*
X104250Y327382D01*
G01X103500Y322500D02*
Y326632D01*
G01X69125Y311975D02*
Y310625D01*
G01X67850Y313250D02*
X69125Y311975D01*
G01X66500Y313250D02*
X67850D01*
G01X66575Y309175D02*
Y307250D01*
G01X68025Y310625D02*
X66575Y309175D01*
G01X69125Y310625D02*
X68025D01*
G01X77600Y317900D02*
Y320800D01*
G01X79100Y316400D02*
X77600Y317900D01*
G01X79100Y315822D02*
Y316400D01*
G01X80713Y314209D02*
X79100Y315822D01*
G01X85209Y314209D02*
X80713D01*
G01X86222Y315222D02*
X85209Y314209D01*
G01X95632Y315222D02*
X86222D01*
G01X97320Y316910D02*
X95632Y315222D01*
G01X97320Y323574D02*
Y316910D01*
G01X94570Y326324D02*
X97320Y323574D01*
G01X94570Y329051D02*
Y326324D01*
G01X95460Y329941D02*
X94570Y329051D01*
G01X97250Y329941D02*
X95460D01*
G01X78820Y322020D02*
X80500D01*
G01X77600Y320800D02*
X78820Y322020D01*
G01X80500Y323820D02*
Y322020D01*
G01X82450Y325770D02*
X80500Y323820D01*
G01X82450Y328000D02*
Y325770D01*
G01X75000Y339050D02*
X74800Y338850D01*
G01X75000Y341500D02*
Y339050D01*
G01X63000Y339000D02*
X62900D01*
G01X63000Y341500D02*
Y339000D01*
G01X72100Y318350D02*
X70800Y317050D01*
G01X72100Y321800D02*
Y318350D01*
G01X61350Y316750D02*
X61000D01*
G01X64000Y314100D02*
X61350Y316750D01*
G01X64000Y313900D02*
Y314100D01*
G01X64225Y311000D02*
X64700Y310525D01*
G01X61801Y311000D02*
X64225D01*
G01X61000Y311801D02*
X61801Y311000D01*
G01X61000Y313250D02*
Y311801D01*
G01X64800Y310425D02*
X64700Y310525D01*
G01X64800Y309201D02*
Y310425D01*
G01X64605Y309006D02*
X64800Y309201D01*
G01X64605Y307250D02*
Y309006D01*
G01X69000Y341800D02*
Y338800D01*
G01X77500Y309700D02*
Y312500D01*
G01X76425Y308625D02*
X77500Y309700D01*
G01X76425Y307250D02*
Y308625D01*
G01X84700Y310700D02*
X84300D01*
G01X87500Y313500D02*
X84700Y310700D01*
G01X82600Y309000D02*
X84300Y310700D01*
G01X82600Y305968D02*
Y309000D01*
G01X81527Y304895D02*
X82600Y305968D01*
G01X80750Y304895D02*
X81527D01*
G01X50300Y295300D02*
X50900D01*
G01X48550Y297050D02*
X50300Y295300D01*
G01X48550Y301650D02*
Y297050D01*
G01X70800Y312600D02*
X72600Y310800D01*
G01X70800Y313550D02*
Y312600D01*
G01X70515Y308715D02*
X72600Y310800D01*
G01X70515Y307250D02*
Y308715D01*
G01X98700Y300500D02*
Y303900D01*
G01X98500Y300300D02*
X98700Y300500D01*
G01X98500Y298500D02*
Y300300D01*
G01Y297080D02*
Y298500D01*
G01X98950Y296630D02*
X98500Y297080D01*
G01X101170Y296630D02*
X98950D01*
G01X102322Y295478D02*
X101170Y296630D01*
G01X64250Y316750D02*
X66500D01*
G01X64000Y316500D02*
X64250Y316750D01*
G01X83456Y300955D02*
X80750D01*
G01X85467Y302966D02*
X83456Y300955D01*
G01X86500Y303999D02*
X85467Y302966D01*
G01X86674Y303999D02*
X86500D01*
G01X87500Y304825D02*
X86674Y303999D01*
G01X87500Y306000D02*
Y304825D01*
G01X49008Y348900D02*
X46400D01*
G01X49117Y349009D02*
X49008Y348900D01*
G01X78000Y345700D02*
Y344550D01*
G01X79100Y346800D02*
X78000Y345700D01*
G01X79100Y347000D02*
Y346800D01*
G01Y348800D02*
Y347000D01*
G01X78862Y349038D02*
X79100Y348800D01*
G01X78862Y352600D02*
Y349038D01*
G01X49017Y346509D02*
X46591D01*
G01X63000Y345000D02*
X66000D01*
G01Y345237D02*
Y345000D01*
G01X68700Y347937D02*
X66000Y345237D01*
G01X68700Y349000D02*
Y347937D01*
G01X70988Y351288D02*
X68700Y349000D01*
G01X70988Y352600D02*
Y351288D01*
G01X54159Y348400D02*
X51923Y346164D01*
G01X54500Y348400D02*
X54159D01*
G01X64000Y351400D02*
X60900Y348300D01*
G01X67339Y351400D02*
X64000D01*
G01X67839Y351900D02*
X67339Y351400D01*
G01X67839Y352600D02*
Y351900D01*
G01X58700Y346700D02*
X57000Y345000D01*
G01X59300Y346700D02*
X58700D01*
G01X60900Y348300D02*
X59300Y346700D01*
G01X61776Y351737D02*
X61041D01*
G01X63410Y353371D02*
X61776Y351737D01*
G01X63410Y354527D02*
Y353371D01*
G01X64222Y355339D02*
X63410Y354527D01*
G01X65100Y355339D02*
X64222D01*
G01X75713Y348713D02*
Y352600D01*
G01X73805Y346805D02*
X75713Y348713D01*
G01X73505Y346805D02*
X73805D01*
G01X72000Y345300D02*
X73505Y346805D01*
G01X59500Y401500D02*
Y405200D01*
G01X49091Y351509D02*
X46991D01*
G01X63438Y361638D02*
X65100D01*
G01X62500Y360700D02*
X63438Y361638D01*
G01X57274Y360700D02*
X62500D01*
G01X54425Y357851D02*
X57274Y360700D01*
G01X51899Y357851D02*
X54425D01*
G01X50510Y359240D02*
X51899Y357851D01*
G01X62320Y347120D02*
X63800Y348600D01*
G01X62120Y347120D02*
X62320D01*
G01X60000Y345000D02*
X62120Y347120D01*
G01X65100Y349900D02*
X63800Y348600D01*
G01X67900Y349900D02*
X65100D01*
G01X69413Y351413D02*
X67900Y349900D01*
G01X69413Y352600D02*
Y351413D01*
G01X75126Y346526D02*
X76500Y347900D01*
G01X75126Y346127D02*
Y346526D01*
G01X75000Y346001D02*
X75126Y346127D01*
G01X75000Y345000D02*
Y346001D01*
G01X77287Y348687D02*
Y352600D01*
G01X76500Y347900D02*
X77287Y348687D01*
G01X73200Y348000D02*
X72131D01*
G01X74138Y348938D02*
X73200Y348000D01*
G01X74138Y352600D02*
Y348938D01*
G01X69000Y345900D02*
Y345300D01*
G01X71100Y348000D02*
X69000Y345900D01*
G01X72131Y348000D02*
X71100D01*
G01X49800Y404200D02*
X52500Y401500D01*
G01X58000Y354600D02*
Y351500D01*
G01Y348400D02*
Y351500D01*
G01X62863Y356913D02*
X65100D01*
G01X62063Y356113D02*
X62863Y356913D01*
G01X62063Y355061D02*
Y356113D01*
G01X61089Y354087D02*
X62063Y355061D01*
G01X59711Y354087D02*
X61089D01*
G01X59198Y354600D02*
X59711Y354087D01*
G01X58000Y354600D02*
X59198D01*
G01X49017Y344009D02*
X47091D01*
G01X63037Y360063D02*
X65100D01*
G01X62809Y359835D02*
X63037Y360063D01*
G01X57800Y359835D02*
X62809D01*
G01X54800Y356835D02*
X57800Y359835D01*
G01X50480Y356835D02*
X54800D01*
G01X47970Y359345D02*
X50480Y356835D01*
G01X47970Y359550D02*
Y359345D01*
G01X106510Y351100D02*
X111600D01*
G01X49000Y401600D02*
X47500Y403100D01*
G01X56000Y401500D02*
Y403800D01*
G01X78700Y462600D02*
Y460200D01*
G01X78100Y463200D02*
X78700Y462600D01*
G01X78100Y465511D02*
Y463200D01*
G01X74648Y465463D02*
Y461201D01*
G01X56644Y416478D02*
X54662D01*
G01X60635Y412487D02*
X56644Y416478D01*
G01X60635Y406335D02*
Y412487D01*
G01X59500Y405200D02*
X60635Y406335D01*
G01X49800Y412571D02*
Y404200D01*
G01X47500Y403100D02*
Y412120D01*
G01X53231Y414695D02*
X51645Y416281D01*
G01X56977Y414695D02*
X53231D01*
G01X59210Y412462D02*
X56977Y414695D01*
G01X59210Y407010D02*
Y412462D01*
G01X56000Y403800D02*
X59210Y407010D01*
G01X78100Y467174D02*
Y465511D01*
G01X76865Y468409D02*
X78100Y467174D01*
G01X76865Y470975D02*
Y468409D01*
G01X71640Y478080D02*
X74820D01*
G01X71050Y478670D02*
X71640Y478080D01*
G01X74266Y465845D02*
X74600Y465511D01*
G01X74266Y469837D02*
Y465845D01*
G01X74202Y469901D02*
X74266Y469837D01*
G01X74202Y472049D02*
Y469901D01*
G01X74266Y472113D02*
X74202Y472049D01*
G01X74266Y475371D02*
Y472113D01*
G01X73841Y475796D02*
X74266Y475371D01*
G01X69658Y475796D02*
X73841D01*
G01X69233Y476221D02*
X69658Y475796D01*
G01X69233Y479508D02*
Y476221D01*
G01X67132Y481609D02*
X69233Y479508D01*
G01X61274Y481609D02*
X67132D01*
G01X59731Y480066D02*
X61274Y481609D01*
G01X74600Y465511D02*
X74648Y465463D01*
G01X72937Y465511D02*
X74600D01*
G01X72564Y465138D02*
X72937Y465511D01*
G01X70525Y465138D02*
X72564D01*
G01X85865Y472444D02*
Y470975D01*
G01X82529Y475780D02*
X85865Y472444D01*
G01X81476Y475780D02*
X82529D01*
G01X74422Y482834D02*
X81476Y475780D01*
G01X54289Y482834D02*
X74422D01*
G01X50581Y479126D02*
X54289Y482834D01*
G01X147382Y-53848D02*
X144980Y-56250D01*
G01X445470Y-53848D02*
X147382D01*
G01X148901Y-50423D02*
X445470D01*
G01X118935Y111133D02*
Y118861D01*
G01X120533Y109535D02*
X118935Y111133D01*
G01X115772Y126345D02*
X118935D01*
G01X115014Y125587D02*
X115772Y126345D01*
G01X115014Y121182D02*
Y125587D01*
G01X112950Y119118D02*
X115014Y121182D01*
G01X111350Y119118D02*
X112950D01*
G01X111093Y118861D02*
X111350Y119118D01*
G01X116124Y112643D02*
Y112393D01*
G01X114155Y114612D02*
X116124Y112643D01*
G01X113331Y114612D02*
X114155D01*
G01X111093Y116850D02*
X113331Y114612D01*
G01X111093Y118861D02*
Y116850D01*
G01X113588Y248588D02*
Y252322D01*
G01X112200Y247200D02*
X113588Y248588D01*
G01X113100Y278500D02*
Y281000D01*
G01X112400Y277800D02*
X113100Y278500D01*
G01X113162Y219572D02*
X114120Y220530D01*
G01X110198Y219572D02*
X113162D01*
G01X114317Y282217D02*
Y283595D01*
G01X113100Y281000D02*
X114317Y282217D01*
G01X116405Y283595D02*
X114317D01*
G01X116830Y283170D02*
X116405Y283595D01*
G01X118770Y283170D02*
X116830D01*
G01X119835Y284235D02*
X118770Y283170D01*
G01X122165Y284235D02*
X119835D01*
G01X115319Y378710D02*
X113620D01*
G01X116169Y377860D02*
X115319Y378710D01*
G01X116910Y377860D02*
X116169D01*
G01X119945Y380235D02*
X122165D01*
G01X117570Y377860D02*
X119945Y380235D01*
G01X116910Y377860D02*
X117570D01*
G01X117972Y402500D02*
X116700D01*
G01X119385Y403913D02*
X117972Y402500D01*
G01X116700Y405500D02*
Y402500D01*
G01X113366Y349334D02*
Y348586D01*
G01X111600Y351100D02*
X113366Y349334D01*
G01X119000Y411700D02*
X119100Y411600D01*
G01X116600Y411700D02*
X119000D01*
G01X148828Y422658D02*
X151314D01*
G01X148409Y422239D02*
X148828Y422658D01*
G01X117099Y414201D02*
X119016D01*
G01X116600Y414700D02*
X117099Y414201D01*
G01X150228Y418959D02*
X148666Y417397D01*
G01X151343Y418959D02*
X150228D01*
G01X121261Y403913D02*
X119385D01*
G01X121981Y404633D02*
X121261Y403913D01*
G01X121981Y405573D02*
Y404633D01*
G01X117600Y408600D02*
X116700D01*
G01X119398Y406802D02*
X117600Y408600D01*
G01X119398Y406348D02*
Y406802D01*
G01X276869Y205210D02*
X274619D01*
G01X276869Y201309D02*
X274619D01*
G01X273489Y203260D02*
X271239D01*
G01X276869Y209109D02*
X274619D01*
G01X273489Y207159D02*
X271239D01*
G01X280249Y199360D02*
X277999D01*
G01X270109Y209109D02*
X267859D01*
G01X276869Y271509D02*
X274619D01*
G01X280249Y273460D02*
X277999D01*
G01X293769D02*
X291519D01*
G01X293769Y324160D02*
X291519D01*
G01X283629Y322209D02*
X281379D01*
G01X287009Y320260D02*
X284759D01*
G01X290389Y322209D02*
X288139D01*
G01X293769Y320260D02*
X291519D01*
G01X280249Y324160D02*
X277999D01*
G01X276869Y396309D02*
X274619D01*
G01X273489Y398260D02*
X271239D01*
G01X270109Y392410D02*
X267859D01*
G01X283629Y400209D02*
X281379D01*
G01X276869D02*
X274619D01*
G01X280249Y398260D02*
X277999D01*
G01X273489Y394359D02*
X271239D01*
G01X317714Y3233D02*
Y-4536D01*
G01X307675Y22923D02*
Y28014D01*
G01Y-7662D02*
X308157Y-7180D01*
G01X307675Y-14877D02*
Y-7662D01*
G01X317714Y35957D02*
Y41033D01*
G01Y73757D02*
Y78833D01*
G01X307675Y67549D02*
X307928Y67802D01*
G01X307675Y60723D02*
Y67549D01*
G01X297149Y197409D02*
X294899D01*
G01X351228Y213009D02*
X348978D01*
G01X340292Y204712D02*
X338838Y203258D01*
G01X340292Y206363D02*
Y204712D01*
G01X341088Y207159D02*
X340292Y206363D01*
G01X347848Y211060D02*
X345598D01*
G01X344468Y216909D02*
X342218D01*
G01X337708Y205210D02*
X338838Y207158D01*
G01X324188Y279310D02*
X321938D01*
G01X341088Y273460D02*
X338838D01*
G01X324188Y252009D02*
X321938D01*
G01X347848Y257860D02*
X345598D01*
G01X300529Y269560D02*
X298279D01*
G01X303909Y271509D02*
X301659D01*
G01X330948Y275409D02*
X328698D01*
G01X327568Y277360D02*
X325318D01*
G01X354607Y253960D02*
X352357D01*
G01X297149Y267609D02*
X294899D01*
G01X347848Y261760D02*
X345598D01*
G01X334328Y277360D02*
X332078D01*
G01X334328Y222760D02*
X332078D01*
G01X330948Y279310D02*
X328698D01*
G01X297149Y271509D02*
X294899D01*
G01X310668Y248109D02*
X308418D01*
G01X347848Y222760D02*
X345598D01*
G01X300529Y273460D02*
X298279D01*
G01X334328D02*
X332078D01*
G01X351228Y255909D02*
X348978D01*
G01X330948Y228610D02*
X328698D01*
G01X341088Y277360D02*
X338838D01*
G01X332079Y230559D02*
X332078Y230560D01*
G01X334328Y230559D02*
X332079D01*
G01X337708Y220809D02*
X335458D01*
G01X314048Y242260D02*
X311798D01*
G01X320808Y250060D02*
X318558D01*
G01X354607D02*
X352357D01*
G01X337708Y228610D02*
X335458D01*
G01X330948Y271509D02*
X328698D01*
G01X341088Y269560D02*
X338838D01*
G01X337708Y275409D02*
X335458D01*
G01X347848Y250060D02*
X345598D01*
G01X334328Y226660D02*
X332078D01*
G01X314048Y246160D02*
X311798D01*
G01X335459Y232509D02*
X335458Y232510D01*
G01X337708Y232509D02*
X335459D01*
G01X337708Y279310D02*
X335458D01*
G01X354607Y257860D02*
X352357D01*
G01X351228Y259809D02*
X348978D01*
G01X330948Y224709D02*
X328698D01*
G01X317428Y248109D02*
X315178D01*
G01X351228Y252009D02*
X348978D01*
G01X317428Y244209D02*
X315178D01*
G01X347848Y253960D02*
X345598D01*
G01X337708Y271509D02*
X335458D01*
G01X354607Y339760D02*
X352357D01*
G01X294900Y326110D02*
X294899Y326109D01*
G01X297149Y326110D02*
X294900D01*
G01X297149Y330009D02*
X294899D01*
G01X334328Y367060D02*
X332078D01*
G01X337708Y369010D02*
X335458D01*
G01X310668Y349509D02*
X308418D01*
G01X347848Y347560D02*
X345598D01*
G01X334328Y374860D02*
X332078D01*
G01X324188Y341709D02*
X321938D01*
G01X354607Y343660D02*
X352357D01*
G01X314048Y355360D02*
X311798D01*
G01X317428Y349509D02*
X315178D01*
G01X344468D02*
X342218D01*
G01X297149Y400209D02*
X294899D01*
G01X317428Y380709D02*
X315178D01*
G01X314048Y347560D02*
X311798D01*
G01X354607D02*
X352357D01*
G01X351228Y384609D02*
X348978D01*
G01X347848Y374860D02*
X345598D01*
G01X337708Y376809D02*
X335458D01*
G01X317428Y384609D02*
X315178D01*
G01X334328Y370959D02*
X332078D01*
G01X314048Y351460D02*
X311798D01*
G01X317428Y353409D02*
X315178D01*
G01X330948Y369010D02*
X328698D01*
G01X324188Y345609D02*
X321938D01*
G01X337708Y365109D02*
X335458D01*
G01X330948Y372909D02*
X328698D01*
G01X341088Y363160D02*
X338838D01*
G01X307675Y523900D02*
Y528340D01*
G01X317714Y542010D02*
Y536957D01*
G01X307675Y528340D02*
X308198Y528863D01*
G01X307675Y566434D02*
X307984Y566743D01*
G01X307675Y561700D02*
Y566434D01*
G01X317714Y579810D02*
Y574757D01*
G01X307675Y606738D02*
X308157Y607220D01*
G01X307675Y599500D02*
Y606738D01*
G01X317714Y617610D02*
Y609864D01*
G01X411415Y3233D02*
Y-4536D01*
G01X394682Y60724D02*
X394683Y60723D01*
G01X394682Y68492D02*
Y60724D01*
G01X394492Y55318D02*
Y54700D01*
G01X392892Y56918D02*
X394492Y55318D01*
G01X392892Y69104D02*
Y56918D01*
G01X395562Y71774D02*
X392892Y69104D01*
G01X419473Y71774D02*
X395562D01*
G01X411416Y73857D02*
Y73757D01*
G01X411415Y73858D02*
X411416Y73857D01*
G01X411415Y78833D02*
Y73858D01*
G01Y41033D02*
Y36058D01*
G01X401926Y211060D02*
X399676D01*
G01X388407Y242260D02*
X386157D01*
G01X357987Y255909D02*
X355737D01*
G01X385027Y240309D02*
X382777D01*
G01X381647Y246160D02*
X379397D01*
G01X361367Y253960D02*
X359117D01*
G01X401926Y246160D02*
X399676D01*
G01X401926Y242260D02*
X399676D01*
G01X364747Y252009D02*
X362497D01*
G01X385027Y244209D02*
X382777D01*
G01X395166Y242260D02*
X392916D01*
G01X381647D02*
X379397D01*
G01X361367Y250060D02*
X359117D01*
G01X395166Y246160D02*
X392916D01*
G01X368127D02*
X365877D01*
G01X364747Y248109D02*
X362497D01*
G01X405306Y244209D02*
X407706D01*
G01X398546Y240309D02*
X396296D01*
G01X368127Y250060D02*
X365877D01*
G01X374887Y246160D02*
X372637D01*
G01X378267Y244209D02*
X376017D01*
G01X388407Y246160D02*
X386157D01*
G01X398546Y244209D02*
X396296D01*
G01X371507Y248109D02*
X369257D01*
G01X391787Y240309D02*
X389537D01*
G01X357987Y252009D02*
X355737D01*
G01X391787Y244209D02*
X389537D01*
G01X364747Y345609D02*
X362497D01*
G01X385027Y357309D02*
X382777D01*
G01X381647Y355360D02*
X379397D01*
G01X408686D02*
X411086D01*
G01X401926Y398260D02*
X402892Y400400D01*
G01X408686Y378760D02*
X411086D01*
G01X398546Y400209D02*
Y402900D01*
G01X364747Y349509D02*
X362497D01*
G01X405306Y353409D02*
X403056D01*
G01X368127Y347560D02*
X365877D01*
G01X408686Y363160D02*
X411447D01*
G01X361367Y347560D02*
X359117D01*
G01X405306Y396309D02*
X403056D01*
G01X378267Y349509D02*
X376017D01*
G01X381647Y351460D02*
X379397D01*
G01X401926Y355360D02*
X399676D01*
G01X408686Y390460D02*
X411086D01*
G01X408686Y386560D02*
X411086D01*
G01X385027Y353409D02*
X382777D01*
G01X411547Y368813D02*
Y368260D01*
G01X409401Y370959D02*
X411547Y368813D01*
G01X408686Y370959D02*
X409401D01*
G01X368127Y351460D02*
X365877D01*
G01X357987Y345609D02*
X355737D01*
G01X357987Y341709D02*
X355737D01*
G01X372637Y351460D02*
X374887D01*
G01X410086Y365660D02*
X411547D01*
G01X408686Y367060D02*
X410086Y365660D01*
G01X411340Y359260D02*
X411431Y359351D01*
G01X408686Y359260D02*
X411340D01*
G01X401926D02*
X399676D01*
G01X388407Y355360D02*
X386157D01*
G01X408686Y394359D02*
X411086D01*
G01X361367Y343660D02*
X359117D01*
G01X401926Y386560D02*
X399676D01*
G01X408686Y382660D02*
X411086D01*
G01X394683Y528930D02*
Y523900D01*
G01X394682Y572210D02*
Y569492D01*
G01X392792Y574100D02*
X394682Y572210D01*
G01X392792Y589700D02*
Y574100D01*
G01X392892Y535600D02*
Y535200D01*
G01X394683Y569491D02*
Y561723D01*
G01X394682Y569492D02*
X394683Y569491D01*
G01X394587Y529026D02*
X394683Y528930D01*
G01X411416Y537057D02*
Y536957D01*
G01X411415Y537058D02*
X411416Y537057D01*
G01X411415Y542010D02*
Y537058D01*
G01X411416Y574857D02*
Y574757D01*
G01X411415Y574858D02*
X411416Y574857D01*
G01X411415Y579810D02*
Y574858D01*
G01X394683Y607291D02*
Y599500D01*
G01X394682Y607292D02*
X394683Y607291D01*
G01Y591591D02*
X392792Y589700D01*
G01X394683Y599500D02*
Y591591D01*
G01X411415Y617610D02*
Y609864D01*
G01X445470Y-50423D02*
G02Y-53848I0J-1712D01*
G01X421455Y3233D02*
X421454Y-1817D01*
G01X438187Y35959D02*
X438189Y35957D01*
G01X438187Y41033D02*
Y35959D01*
G01X421456Y73757D02*
X419473Y71774D01*
G01X421455Y46921D02*
Y41033D01*
G01Y73758D02*
Y78833D01*
G01X421456Y73757D02*
X421455Y73758D01*
G01X438187Y73759D02*
X438189Y73757D01*
G01X438187Y78833D02*
Y73759D01*
G01X445400Y268800D02*
X442700Y271500D01*
G01X445400Y268639D02*
Y268800D01*
G01X446877Y267162D02*
X445400Y268639D01*
G01X448561Y267162D02*
X446877D01*
G01X449288Y266435D02*
X448561Y267162D01*
G01X449646Y273300D02*
X449100D01*
G01X452865Y270081D02*
X449646Y273300D01*
G01X433700Y269800D02*
X432000Y271500D01*
G01X435100Y269800D02*
X433700D01*
G01X439000Y265900D02*
X435100Y269800D01*
G01X439000Y264363D02*
Y265900D01*
G01X439664Y263699D02*
X439000Y264363D01*
G01X439764Y263699D02*
X439664D01*
G01X436000Y271000D02*
Y271500D01*
G01X440500Y266500D02*
X436000Y271000D01*
G01X439500D02*
Y271500D01*
G01X443195Y267305D02*
X439500Y271000D01*
G01X444408Y267305D02*
X443195D01*
G01X466066Y295934D02*
X461500Y300500D01*
G01X466066Y292452D02*
Y295934D01*
G01X461800Y297500D02*
X461500D01*
G01X464000Y295300D02*
X461800Y297500D01*
G01X464000Y294500D02*
Y295300D01*
G01X453600Y293700D02*
X457800D01*
G01X453586Y293686D02*
X453600Y293700D01*
G01X453400Y293686D02*
X453586D01*
G01X463300Y282600D02*
X461400Y284500D01*
G01X463300Y282100D02*
Y282600D01*
G01X465100Y280300D02*
X463300Y282100D01*
G01X462800Y290500D02*
X461400D01*
G01X463800Y289500D02*
X462800Y290500D01*
G01X461826Y287074D02*
X466734D01*
G01X461400Y287500D02*
X461826Y287074D01*
G01X463400Y291600D02*
X461300Y293700D01*
G01X464300Y291600D02*
X463400D01*
G01X466734Y289166D02*
X464300Y291600D01*
G01X466734Y287074D02*
Y289166D01*
G01X462621Y303500D02*
X461500D01*
G01X466100Y300021D02*
X462621Y303500D01*
G01X468783Y342947D02*
X471033D01*
G01X428224Y358547D02*
X430474D01*
G01X441743Y370247D02*
X443993D01*
G01X443992Y374146D02*
X443993Y374147D01*
G01X441743Y374146D02*
X443992D01*
G01X438363Y376096D02*
X440613D01*
G01X431604Y356596D02*
X433854D01*
G01X434983Y378047D02*
X437233D01*
G01X458643Y344896D02*
X460893D01*
G01X421455Y547921D02*
X421456Y547922D01*
G01X421455Y542010D02*
Y547921D01*
G01Y585721D02*
Y579810D01*
G01X421456Y585722D02*
X421455Y585721D01*
G01X438187Y536959D02*
X438189Y536957D01*
G01X438187Y542010D02*
Y536959D01*
G01Y574759D02*
X438189Y574757D01*
G01X438187Y579810D02*
Y574759D01*
G01X421455Y617610D02*
X421454Y612560D01*
G01X482302Y210346D02*
X480052D01*
G01X485682Y212296D02*
X483432D01*
G01X539761Y204496D02*
X540300Y203958D01*
G01X522861Y241547D02*
X525111D01*
G01X502582Y268847D02*
X504832D01*
G01X516102Y257147D02*
X518352D01*
G01X516102Y276646D02*
X518352D01*
G01X512722Y274696D02*
X514972D01*
G01X502582Y272747D02*
X504832D01*
G01X519481Y262996D02*
X521731D01*
G01X512722Y255196D02*
X514972D01*
G01X509342Y268847D02*
X511592D01*
G01X519481Y278596D02*
X521731D01*
G01X505962Y274696D02*
X508212D01*
G01X504831Y276646D02*
X504832Y276647D01*
G01X502582Y276646D02*
X504831D01*
G01X489062Y272747D02*
X491312D01*
G01X526241Y262996D02*
X528491D01*
G01X509342Y272747D02*
X511592D01*
G01X495822Y249347D02*
X498072D01*
G01X485682Y239596D02*
X483432D01*
G01X511591Y276646D02*
X511592Y276647D01*
G01X509342Y276646D02*
X511591D01*
G01X516102Y264947D02*
X518352D01*
G01X498071Y276646D02*
X498072Y276647D01*
G01X495822Y276646D02*
X498071D01*
G01X522861Y264947D02*
X525111D01*
G01X522861Y276646D02*
X525111D01*
G01X491311D02*
X491312Y276647D01*
G01X489062Y276646D02*
X491311D01*
G01X526241Y251296D02*
X528491D01*
G01X495822Y272747D02*
X498072D01*
G01X501452Y278596D02*
X499202D01*
G01X505962Y243496D02*
X508212D01*
G01X526241Y239596D02*
X528491D01*
G01X529621Y253247D02*
X531871D01*
G01X526241Y266896D02*
X528491D01*
G01X526241Y333196D02*
X528491D01*
G01X509342Y280547D02*
X511592D01*
G01X522861Y319547D02*
X525111D01*
G01X536381Y327347D02*
X538631D01*
G01X529621Y331247D02*
X531871D01*
G01X492442Y282496D02*
X494692D01*
G01X489062Y303947D02*
X491312D01*
G01X539761Y301996D02*
X542011D01*
G01X512722Y282496D02*
X514972D01*
G01X522861Y331247D02*
X525111D01*
G01X489062Y284447D02*
X491312D01*
G01X542011Y325396D02*
X539761D01*
G01X478922D02*
X481172D01*
G01X529621Y296147D02*
X531871D01*
G01X516102Y284447D02*
X518352D01*
G01X533001Y313696D02*
X535251D01*
G01X489062Y280547D02*
X491312D01*
G01X533001Y305896D02*
X535251D01*
G01X482302Y331247D02*
X484552D01*
G01X508212Y286396D02*
X505962D01*
G01X495822Y280547D02*
X498072D01*
G01X502582Y288347D02*
X504832D01*
G01X519481Y333196D02*
X521731D01*
G01X519481Y329296D02*
X521731D01*
G01X499202Y309797D02*
X501452D01*
G01X478922Y333196D02*
X481172D01*
G01X516102Y335147D02*
X518352D01*
G01X536381Y296147D02*
X538631D01*
G01X519481Y282496D02*
X521731D01*
G01X529621Y315647D02*
X531871D01*
G01X492442Y298096D02*
X494692D01*
G01X489062Y315647D02*
X491312D01*
G01X533001Y340996D02*
X535251D01*
G01X485682Y313696D02*
X487932D01*
G01X533001Y337096D02*
X535251D01*
G01X495822Y292247D02*
X498072D01*
G01X536381Y300047D02*
X538631D01*
G01X539761Y309797D02*
X542011D01*
G01X499202Y337096D02*
X501452D01*
G01X519481D02*
X521731D01*
G01X516102Y280547D02*
X518352D01*
G01X542011Y329296D02*
X539761D01*
G01X505962Y282496D02*
X508212D01*
G01X539761Y313696D02*
X542011D01*
G01X485682Y305896D02*
X487932D01*
G01X495822Y284447D02*
X498072D01*
G01X522861Y327347D02*
X525111D01*
G01X484551Y319547D02*
X484552Y319546D01*
G01X482302Y319547D02*
X484551D01*
G01X529621Y339047D02*
X531871D01*
G01X478922Y317596D02*
X481172D01*
G01X542011Y333196D02*
X539761D01*
G01X489062Y288347D02*
X491312D01*
G01X482302Y303947D02*
X484552D01*
G01X502582Y284447D02*
X504832D01*
G01X538631Y315647D02*
X536381D01*
G01X529621Y323446D02*
X531871D01*
G01X495822Y288347D02*
X498072D01*
G01X526241Y325396D02*
X528491D01*
G01X542011Y340996D02*
X539761D01*
G01X485682Y286396D02*
X487932D01*
G01X533001Y298096D02*
X535251D01*
G01X526241Y329296D02*
X528491D01*
G01X526241Y321496D02*
X528491D01*
G01X499202Y286396D02*
X501452D01*
G01X539761Y305896D02*
X542011D01*
G01X522861Y323446D02*
X525111D01*
G01X536381Y303947D02*
X538631D01*
G01X536381Y331247D02*
X538631D01*
G01X526241Y340996D02*
X528491D01*
G01X502582Y280547D02*
X504832D01*
G01X492442Y301996D02*
X494692D01*
G01X485682Y294196D02*
X487932D01*
G01X495822Y307847D02*
X498072D01*
G01X478922Y321496D02*
X481172D01*
G01X492442Y290296D02*
X494692D01*
G01X536381Y307847D02*
X538631D01*
G01X499202Y305896D02*
X501452D01*
G01X539761Y317596D02*
X542011D01*
G01X489062Y296147D02*
X491312D01*
G01X485682Y298096D02*
X487932D01*
G01X536381Y323446D02*
X538631D01*
G01X485682Y301996D02*
X487932D01*
G01X533001Y317596D02*
X535251D01*
G01X519481Y340996D02*
X521731D01*
G01X502582Y292247D02*
X504832D01*
G01X542011Y337096D02*
X539761D01*
G01X526241Y383896D02*
X528491D01*
G01X502582Y370247D02*
X504832D01*
G01X533001Y364396D02*
X535251D01*
G01X516102Y350747D02*
X518352D01*
G01X502582Y374146D02*
X504832D01*
G01X526241Y348796D02*
X528491D01*
G01X526241Y379996D02*
X528491D01*
G01X509342Y362447D02*
X511592D01*
G01X542011Y395597D02*
X539761D01*
G01X519481Y391696D02*
X521731D01*
G01X492442Y383896D02*
X494692D01*
G01X516102Y354647D02*
X518352D01*
G01X526241Y376096D02*
X528491D01*
G01X529621Y358547D02*
X531871D01*
G01X509342Y401447D02*
X511592D01*
G01X492442Y379996D02*
X494692D01*
G01X536381Y401447D02*
X534600Y403228D01*
G01X505962Y383896D02*
X508212D01*
G01X499202Y372197D02*
X501452D01*
G01X512722Y360496D02*
X514972D01*
G01X533001Y344896D02*
X535251D01*
G01X522861Y346847D02*
X525111D01*
G01X526241Y344896D02*
X528491D01*
G01X519481Y395597D02*
X521731D01*
G01X512722Y391696D02*
X514972D01*
G01X526241Y387796D02*
X528491D01*
G01X509342Y358547D02*
X511592D01*
G01X539761Y387796D02*
X542011D01*
G01X505962Y376096D02*
X508212D01*
G01X522861Y385847D02*
X525111D01*
G01X533001Y379996D02*
X535251D01*
G01X516102Y393647D02*
X518352D01*
G01X542011Y391696D02*
X539761D01*
G01X516102Y346847D02*
X518352D01*
G01X519481Y352696D02*
X521731D01*
G01X542011Y356596D02*
X539761D01*
G01X509342Y389747D02*
X511592D01*
G01X489062Y342947D02*
X491312D01*
G01X505962Y364396D02*
X508212D01*
G01X495822Y374146D02*
X498072D01*
G01X526241Y352696D02*
X528491D01*
G01X495822Y378047D02*
X498072D01*
G01X512722Y368296D02*
X514972D01*
G01X512722Y387796D02*
X514972D01*
G01X509342Y366347D02*
X511592D01*
G01X533001Y376096D02*
X535251D01*
G01X529621Y381947D02*
X531871D01*
G01X512722Y395597D02*
X514972D01*
G01X536381Y342947D02*
X538631D01*
G01X509342Y354647D02*
X511592D01*
G01X536381Y374146D02*
X538631D01*
G01X505962Y368296D02*
X508212D01*
G01X529621Y366347D02*
X531871D01*
G01X519481Y383896D02*
X521731D01*
G01X536381Y350747D02*
X538631D01*
G01X492442Y387796D02*
X494692D01*
G01X529621Y378047D02*
X531871D01*
G01X533001Y368296D02*
X535251D01*
G01X529621Y362447D02*
X531871D01*
G01X505962Y372197D02*
X508212D01*
G01X533001D02*
X535251D01*
G01X485682Y356596D02*
X487932D01*
G01X533001Y360496D02*
X535251D01*
G01X536381Y362447D02*
X538631D01*
G01X542011Y344896D02*
X539761D01*
G01X508733Y405347D02*
X504832Y401446D01*
G01X536381Y346847D02*
X538631D01*
G01X533001Y348796D02*
X535251D01*
G01X495822Y381947D02*
X498072D01*
G01X529621Y342947D02*
X531871D01*
G01X539761Y399496D02*
X541500Y401235D01*
G01X512722Y376096D02*
X514972D01*
G01X499202D02*
X501452D01*
G01X495822Y370247D02*
X498072D01*
G01X536381Y358547D02*
X538631D01*
G01X522861Y389747D02*
X525111D01*
G01X512722Y364396D02*
X514972D01*
G01X489062Y354647D02*
X491312D01*
G01X536381D02*
X538631D01*
G01X519481Y387796D02*
X521731D01*
G01X533500Y407050D02*
X544150Y417700D01*
G01X533500Y403895D02*
Y407050D01*
G01X533001Y403396D02*
X533500Y403895D01*
G01X534600Y406008D02*
X544692Y416100D01*
G01X534600Y403228D02*
Y406008D01*
G01X509342Y405347D02*
X508733D01*
G01X592858Y122700D02*
X589650D01*
G01X598077Y127919D02*
X592858Y122700D01*
G01X620681Y127919D02*
X598077D01*
G01X577375Y202076D02*
Y204125D01*
G01X575889Y200590D02*
X577375Y202076D01*
G01X567947Y197300D02*
X575889Y200590D01*
G01X548459Y197300D02*
X567947D01*
G01X543067Y199534D02*
X548459Y197300D01*
G01X541250Y201350D02*
X543067Y199534D01*
G01X541250Y203350D02*
Y201350D01*
G01X541801Y203901D02*
X541250Y203350D01*
G01X542437Y203901D02*
X541801D01*
G01X543141Y203197D02*
X542437Y203901D01*
G01X543141Y202547D02*
Y203197D01*
G01X546800Y208372D02*
X546521Y208397D01*
G01X550565Y208030D02*
X546800Y208372D01*
G01X552620Y206796D02*
X550565Y208030D01*
G01X552900Y206600D02*
X552620Y206796D01*
G01X557091Y205000D02*
X552900Y206600D01*
G01X561383Y205000D02*
X557091D01*
G01X561886Y205503D02*
X561383Y205000D01*
G01X562861Y205503D02*
X561886D01*
G01X556661Y213439D02*
Y214247D01*
G01X557628Y212472D02*
X556661Y213439D01*
G01X559272Y212472D02*
X557628D01*
G01X560344Y211400D02*
X559272Y212472D01*
G01X563300Y211400D02*
X560344D01*
G01X563900Y212000D02*
X563300Y211400D01*
G01X563900Y213500D02*
Y212000D01*
G01X575560Y216559D02*
X576261Y217961D01*
G01X574497Y213989D02*
X575560Y216559D01*
G01X574767Y213336D02*
X574497Y213989D01*
G01X574423Y212503D02*
X574767Y213336D01*
G01X573768Y212233D02*
X574423Y212503D01*
G01X573189Y210834D02*
X573768Y212233D01*
G01X573459Y210180D02*
X573189Y210834D01*
G01X573115Y209348D02*
X573459Y210180D01*
G01X572461Y209077D02*
X573115Y209348D01*
G01X571477Y206701D02*
X572461Y209077D01*
G01X569407Y204178D02*
X571477Y206701D01*
G01X569477Y203474D02*
X569407Y204178D01*
G01X568906Y202777D02*
X569477Y203474D01*
G01X568201Y202708D02*
X568906Y202777D01*
G01X567626Y202006D02*
X568201Y202708D01*
G01X565749Y200750D02*
X567626Y202006D01*
G01X552805Y200750D02*
X565749D01*
G01X551008Y202547D02*
X552805Y200750D01*
G01X549901Y202547D02*
X551008D01*
G01X549901Y209598D02*
Y210346D01*
G01X550499Y209000D02*
X549901Y209598D01*
G01X551400Y209000D02*
X550499D01*
G01X552652Y210252D02*
X551400Y209000D01*
G01X554147Y210252D02*
X552652D01*
G01X555799Y208600D02*
X554147Y210252D01*
G01X557699Y208600D02*
X555799D01*
G01X558700Y207599D02*
X557699Y208600D01*
G01X558700Y206550D02*
Y207599D01*
G01X559300Y205950D02*
X558700Y206550D01*
G01X560989Y205950D02*
X559300D01*
G01X561347Y206308D02*
X560989Y205950D01*
G01X561347Y207017D02*
Y206308D01*
G01X560739Y207625D02*
X561347Y207017D01*
G01X565733Y211237D02*
X566051Y211555D01*
G01X564481Y211237D02*
X565733D01*
G01X563694Y210450D02*
X564481Y211237D01*
G01X559950Y210450D02*
X563694D01*
G01X558878Y211522D02*
X559950Y210450D01*
G01X557621Y211522D02*
X558878D01*
G01X556661Y210562D02*
X557621Y211522D01*
G01X556661Y210346D02*
Y210562D01*
G01X578647Y202003D02*
X579497D01*
G01X576428Y199784D02*
X578647Y202003D01*
G01X568136Y196350D02*
X576428Y199784D01*
G01X548269Y196350D02*
X568136D01*
G01X547407Y196707D02*
X548269Y196350D01*
G01X546800Y196958D02*
X547407Y196707D01*
G01X542528Y198728D02*
X546800Y196958D01*
G01X540300Y200956D02*
X542528Y198728D01*
G01X540300Y203958D02*
Y200956D01*
G01X574780Y217124D02*
X575480Y218524D01*
G01X574754Y217098D02*
X574780Y217124D01*
G01X570653Y207195D02*
X574754Y217098D01*
G01X566980Y202718D02*
X570653Y207195D01*
G01X565460Y201700D02*
X566980Y202718D01*
G01X553199Y201700D02*
X565460D01*
G01X551900Y202999D02*
X553199Y201700D01*
G01X551900Y203995D02*
Y202999D01*
G01X552401Y204496D02*
X551900Y203995D01*
G01X553281Y204496D02*
X552401D01*
G01X578980Y219334D02*
Y217884D01*
G01X578661Y219653D02*
X578980Y219334D01*
G01X577953Y219653D02*
X578661D01*
G01X576261Y217961D02*
X577953Y219653D01*
G01X579652Y220006D02*
X581102D01*
G01X579055Y220603D02*
X579652Y220006D01*
G01X577559Y220603D02*
X579055D01*
G01X575480Y218524D02*
X577559Y220603D01*
G01X549901Y307847D02*
X552151D01*
G01X553281Y337096D02*
X555531D01*
G01X594500Y340900D02*
X584700Y350700D01*
G01X596600Y340900D02*
X594500D01*
G01X546521Y298096D02*
X548771D01*
G01X560041Y337096D02*
X562591D01*
G01X546521Y301996D02*
X548771D01*
G01X549901Y300047D02*
X552151D01*
G01X555681Y317596D02*
X553281D01*
G01X555831Y317446D02*
X555681Y317596D01*
G01X549901Y315647D02*
X552151D01*
G01X556661Y327347D02*
X559211D01*
G01X562591Y340996D02*
X560041D01*
G01X553281Y301996D02*
X555831D01*
G01X543141Y327347D02*
X545391D01*
G01X553281Y321496D02*
X555531D01*
G01X553281Y329296D02*
X555531D01*
G01X549901Y303947D02*
X552151D01*
G01X553281Y313696D02*
X555831D01*
G01X549901Y319547D02*
X552151D01*
G01X549901Y311747D02*
X552151D01*
G01X543141D02*
X545391D01*
G01X556661Y323446D02*
X559211D01*
G01X594600Y335900D02*
X583700Y346800D01*
G01X596600Y335900D02*
X594600D01*
G01X549901Y327347D02*
X552151D01*
G01X546521Y321496D02*
X548771D01*
G01X556661Y339047D02*
X558911D01*
G01X543141Y323446D02*
X545391D01*
G01X553281Y325396D02*
X555531D01*
G01X546521Y317596D02*
X548771D01*
G01X543141Y339047D02*
X545391D01*
G01X559067Y331247D02*
X556661D01*
G01X559211Y331103D02*
X559067Y331247D01*
G01X546521Y305896D02*
X548771D01*
G01X553281Y379996D02*
X555531D01*
G01X556661Y350747D02*
X558911D01*
G01X556661Y389747D02*
X559212D01*
G01X553281Y352696D02*
X555531D01*
G01X561945Y350700D02*
X560041Y348796D01*
G01X584700Y350700D02*
X561945D01*
G01X549901Y401447D02*
X554954Y406500D01*
G01X553281Y344896D02*
X555531D01*
G01X562455Y398800D02*
X596481D01*
G01X560705Y397050D02*
X562455Y398800D01*
G01X555562Y397050D02*
X560705D01*
G01X554109Y395597D02*
X555562Y397050D01*
G01X553281Y395597D02*
X554109D01*
G01X582553Y358547D02*
X556661D01*
G01X595200Y345900D02*
X582553Y358547D01*
G01X596600Y345900D02*
X595200D01*
G01X549901Y393647D02*
X552151D01*
G01X546521Y348796D02*
X548771D01*
G01X583153Y362447D02*
X556661D01*
G01X594700Y350900D02*
X583153Y362447D01*
G01X596600Y350900D02*
X594700D01*
G01X597400Y377600D02*
X610200D01*
G01X579000Y396000D02*
X597400Y377600D01*
G01X556200Y396000D02*
X579000D01*
G01X554600Y394400D02*
X556200Y396000D01*
G01X554600Y393015D02*
Y394400D01*
G01X553281Y391696D02*
X554600Y393015D01*
G01X556661Y354647D02*
X558911D01*
G01X549901Y381947D02*
X552151D01*
G01X543141Y389747D02*
X545391D01*
G01X600681Y401500D02*
X601381Y400800D01*
G01X561455Y401500D02*
X600681D01*
G01X558105Y398150D02*
X561455Y401500D01*
G01X554849Y398150D02*
X558105D01*
G01X554101Y397402D02*
X554849Y398150D01*
G01X552402Y397402D02*
X554101D01*
G01X550600Y395600D02*
X552402Y397402D01*
G01X549100Y395600D02*
X550600D01*
G01X547900Y394400D02*
X549100Y395600D01*
G01X547900Y393075D02*
Y394400D01*
G01X546521Y391696D02*
X547900Y393075D01*
G01X543141Y350747D02*
X545391D01*
G01X544700Y402972D02*
Y404200D01*
G01X546521Y401151D02*
X544700Y402972D01*
G01X546521Y399496D02*
Y401151D01*
G01X549901Y385847D02*
X552151D01*
G01X543141Y393647D02*
X545391D01*
G01X549901Y362447D02*
X552151D01*
G01X553281Y348796D02*
X555531D01*
G01X556661Y366347D02*
X559211D01*
G01X549901Y354647D02*
X552151D01*
G01X582804Y376096D02*
X553281D01*
G01X593000Y365900D02*
X582804Y376096D01*
G01X596600Y365900D02*
X593000D01*
G01X561400Y360500D02*
X563500D01*
G01X561396Y360496D02*
X561400Y360500D01*
G01X560041Y360496D02*
X561396D01*
G01X555476Y399496D02*
X555750Y399770D01*
G01X553281Y399496D02*
X555476D01*
G01X585153Y378047D02*
X556661D01*
G01X592300Y370900D02*
X585153Y378047D01*
G01X596600Y370900D02*
X592300D01*
G01X549901Y366347D02*
X552151D01*
G01X556708Y346800D02*
X556661Y346847D01*
G01X583700Y346800D02*
X556708D01*
G01X549901Y370247D02*
X552151D01*
G01X586438Y368296D02*
X553281D01*
G01X593834Y360900D02*
X586438Y368296D01*
G01X596600Y360900D02*
X593834D01*
G01X553281Y372197D02*
X555531D01*
G01X541500Y401235D02*
Y407300D01*
G01X546521Y387796D02*
X548771D01*
G01X599500Y373800D02*
X602500Y370800D01*
G01X595100Y373800D02*
X599500D01*
G01X585004Y383896D02*
X595100Y373800D01*
G01X553281Y383896D02*
X585004D01*
G01X596500Y375500D02*
X603300D01*
G01X580200Y391800D02*
X596500Y375500D01*
G01X555700Y391800D02*
X580200D01*
G01X553647Y389747D02*
X555700Y391800D01*
G01X549901Y389747D02*
X553647D01*
G01X549901Y399301D02*
X554400Y403800D01*
G01X549901Y397546D02*
Y399301D01*
G01X586004Y364396D02*
X553281D01*
G01X594500Y355900D02*
X586004Y364396D01*
G01X596600Y355900D02*
X594500D01*
G01X600681Y406500D02*
X601381Y405800D01*
G01X554954Y406500D02*
X600681D01*
G01X598300Y417700D02*
X604900Y424300D01*
G01X544150Y417700D02*
X598300D01*
G01X598500Y416100D02*
X601700Y419300D01*
G01X544692Y416100D02*
X598500D01*
G01X600800Y411300D02*
X601300Y410800D01*
G01X549094Y411300D02*
X600800D01*
G01X543141Y405347D02*
X549094Y411300D01*
G01X549300Y408800D02*
X596481D01*
G01X544700Y404200D02*
X549300Y408800D01*
G01X548716Y403396D02*
X548990Y403670D01*
G01X546521Y403396D02*
X548716D01*
G01X548500Y414300D02*
X604900D01*
G01X541500Y407300D02*
X548500Y414300D01*
G01X554400Y403800D02*
X596481D01*
G01X605510Y-14877D02*
Y-9901D01*
G01Y22923D02*
Y27899D01*
G01X658700Y23900D02*
X659700Y22900D01*
G01X658700Y25600D02*
Y23900D01*
G01X658600Y25500D02*
X658700Y25600D01*
G01X655500Y25500D02*
X658600D01*
G01X659700Y22466D02*
Y22900D01*
G01X663760Y18406D02*
X659700Y22466D01*
G01X654690Y-2575D02*
Y3070D01*
G01X652492Y-4773D02*
X654690Y-2575D01*
G01X646309Y-4773D02*
X652492D01*
G01X643959Y-2423D02*
X646309Y-4773D01*
G01X643959Y4281D02*
Y-2423D01*
G01X645300Y5622D02*
X643959Y4281D01*
G01X645300Y24200D02*
Y5622D01*
G01X649600Y28500D02*
X645300Y24200D01*
G01X649600Y30525D02*
Y28500D01*
G01X648867Y31258D02*
X649600Y30525D01*
G01X615549Y-14877D02*
Y-9901D01*
G01X651025Y30808D02*
X651442Y31225D01*
G01X651025Y27909D02*
Y30808D01*
G01X646800Y23684D02*
X651025Y27909D01*
G01X646800Y5022D02*
Y23684D01*
G01X645459Y3681D02*
X646800Y5022D01*
G01X645459Y-1907D02*
Y3681D01*
G01X646865Y-3313D02*
X645459Y-1907D01*
G01X650951Y-3313D02*
X646865D01*
G01X652130Y-2134D02*
X650951Y-3313D01*
G01X652130Y3070D02*
Y-2134D01*
G01X654690Y-11810D02*
Y-14930D01*
G01X656000Y-10500D02*
X654690Y-11810D01*
G01X659000Y-10500D02*
X656000D01*
G01X659843Y-11343D02*
X659000Y-10500D01*
G01X659843Y-12036D02*
Y-11343D01*
G01X659747Y-12132D02*
X659843Y-12036D01*
G01X653642Y30776D02*
X654016Y31150D01*
G01X653642Y27787D02*
Y30776D01*
G01X652000Y26145D02*
X653642Y27787D01*
G01X652000Y25500D02*
Y26145D01*
G01X615549Y22923D02*
Y27899D01*
G01X605510Y3233D02*
Y-1743D01*
G01X648500Y-10600D02*
X647000Y-12100D01*
G01X651400Y-10600D02*
X648500D01*
G01X652130Y-11330D02*
X651400Y-10600D01*
G01X652130Y-14930D02*
Y-11330D01*
G01X605510Y60723D02*
Y65699D01*
G01X615549Y60723D02*
Y65699D01*
G01X605510Y41033D02*
Y36057D01*
G01Y78833D02*
Y73857D01*
G01X629600Y119000D02*
X620681Y127919D01*
G01X633800Y119000D02*
X629600D01*
G01X640566Y278324D02*
Y280040D01*
G01X651200Y275600D02*
X652700D01*
G01X650900Y275300D02*
X651200Y275600D01*
G01X649500Y275300D02*
X650900D01*
G01X656450Y271750D02*
Y270087D01*
G01X654437Y273763D02*
X656450Y271750D01*
G01X654437Y275163D02*
Y273763D01*
G01X654000Y275600D02*
X654437Y275163D01*
G01X652700Y275600D02*
X654000D01*
G01X645140Y269660D02*
X642855D01*
G01X646500Y268300D02*
X645140Y269660D01*
G01X639320Y275980D02*
Y274550D01*
G01X638700Y276600D02*
X639320Y275980D01*
G01X638700Y282600D02*
Y276600D01*
G01X658000Y275500D02*
X656100D01*
G01X659013Y274487D02*
X658000Y275500D01*
G01X659013Y272650D02*
Y274487D01*
G01X652400Y264000D02*
Y266849D01*
G01X654187Y262213D02*
X652400Y264000D01*
G01X656450Y262213D02*
X654187D01*
G01X651974Y268300D02*
X650000D01*
G01X652400Y267874D02*
X651974Y268300D01*
G01X652400Y266849D02*
Y267874D01*
G01X651500Y278100D02*
X655000D01*
G01D02*
X658500D01*
G01X659739Y276861D02*
X658500Y278100D01*
G01X659739Y275349D02*
Y276861D01*
G01X660588Y274500D02*
X659739Y275349D01*
G01X660588Y272650D02*
Y274500D01*
G01X644674Y265900D02*
X643591Y266983D01*
G01X645100Y265900D02*
X644674D01*
G01X646000Y265000D02*
X645100Y265900D01*
G01X618279Y272278D02*
Y251393D01*
G01X624501Y278500D02*
X618279Y272278D01*
G01X633499Y278500D02*
X624501D01*
G01X634264Y277735D02*
X633499Y278500D01*
G01X636708Y277735D02*
X634264D01*
G01X643500Y274862D02*
Y274868D01*
G01X646000Y272362D02*
X643500Y274862D01*
G01X646000Y272000D02*
Y272362D01*
G01X651300Y272000D02*
X652700Y270600D01*
G01X649500Y272000D02*
X651300D01*
G01X654100Y269200D02*
X652700Y270600D01*
G01X654100Y264600D02*
Y269200D01*
G01X654913Y263787D02*
X654100Y264600D01*
G01X656450Y263787D02*
X654913D01*
G01X649500Y264200D02*
X651950Y261750D01*
G01X649500Y265000D02*
Y264200D01*
G01X653062Y260638D02*
X656450D01*
G01X651950Y261750D02*
X653062Y260638D01*
G01X640566Y280040D02*
X641665Y281139D01*
G01X628323Y281235D02*
X627529Y280441D01*
G01X636708Y281235D02*
X628323D01*
G01X646700Y308700D02*
Y308850D01*
G01X647481Y307919D02*
X646700Y308700D01*
G01X649819Y307919D02*
X647481D01*
G01X647040Y326100D02*
X646800D01*
G01X647500Y325640D02*
X647040Y326100D01*
G01X649819Y325640D02*
X647500D01*
G01X646700Y309000D02*
Y308850D01*
G01X647588Y309888D02*
X646700Y309000D01*
G01X649819Y309888D02*
X647588D01*
G01X637300Y284000D02*
X638700Y282600D01*
G01X635854Y284000D02*
X637300D01*
G01X631250Y288604D02*
X635854Y284000D01*
G01X631250Y289650D02*
Y288604D01*
G01X657950Y296350D02*
Y296850D01*
G01X655500Y293900D02*
X657950Y296350D01*
G01X655500Y293500D02*
Y293900D01*
G01X657950Y298438D02*
Y296850D01*
G01X658159Y298647D02*
X657950Y298438D01*
G01X658159Y301548D02*
Y298647D01*
G01X655000Y281600D02*
Y284600D01*
G01X658159Y338409D02*
X658900Y339150D01*
G01X658159Y335948D02*
Y338409D01*
G01X660128Y337922D02*
X658900Y339150D01*
G01X660128Y335948D02*
Y337922D01*
G01X646288Y328763D02*
X646272Y328800D01*
G01X649077Y327609D02*
X646288Y328763D01*
G01X649819Y327609D02*
X649077D01*
G01X660128Y301548D02*
Y296830D01*
G01X658638Y294090D02*
X658853Y294305D01*
G01X658638Y291123D02*
Y294090D01*
G01X660128Y295580D02*
Y296830D01*
G01X658853Y294305D02*
X660128Y295580D01*
G01X633384Y332516D02*
X636100Y329800D01*
G01X633384Y338884D02*
Y332516D01*
G01X640555Y346055D02*
X633384Y338884D01*
G01X661730Y287819D02*
X661232Y287321D01*
G01X661730Y290008D02*
Y287819D01*
G01X662200Y284800D02*
X663300Y283700D01*
G01X624668Y287832D02*
X624600Y287900D01*
G01X628525Y287832D02*
X624668D01*
G01X662238Y297018D02*
Y296146D01*
G01X661497Y297759D02*
X662238Y297018D01*
G01X661497Y299380D02*
Y297759D01*
G01X662097Y299980D02*
X661497Y299380D01*
G01X662097Y301548D02*
Y299980D01*
G01X662238Y295805D02*
Y296146D01*
G01X661730Y295297D02*
X662238Y295805D01*
G01X661730Y293508D02*
Y295297D01*
G01X640555Y351419D02*
Y346055D01*
G01X644614Y355478D02*
X640555Y351419D01*
G01X684378Y355478D02*
X644614D01*
G01X603300Y375500D02*
X607900Y370900D01*
G01X611325Y466000D02*
X608800Y463475D01*
G01X601700Y419300D02*
X604900D01*
G01X629300Y447400D02*
X683800D01*
G01X626600Y444700D02*
X629300Y447400D01*
G01X626600Y435600D02*
Y444700D01*
G01X629400Y432800D02*
X626600Y435600D01*
G01X642800Y432800D02*
X629400D01*
G01X647100Y437100D02*
X642800Y432800D01*
G01X648900Y437100D02*
X647100D01*
G01X651100Y434900D02*
X648900Y437100D01*
G01X651100Y429100D02*
Y434900D01*
G01X652875Y427325D02*
X651100Y429100D01*
G01X652877Y427325D02*
X652875D01*
G01X653201Y427001D02*
X652877Y427325D01*
G01X671366Y427001D02*
X653201D01*
G01X647277Y434925D02*
X648091D01*
G01X644065Y431713D02*
X647277Y434925D01*
G01X625507Y431713D02*
X644065D01*
G01X611800Y445420D02*
X625507Y431713D01*
G01X611800Y448845D02*
Y445420D01*
G01X609191Y451454D02*
X611800Y448845D01*
G01X617552Y464748D02*
X616300Y466000D01*
G01X620400Y464323D02*
X619975Y464748D01*
G01X620400Y463990D02*
Y464323D01*
G01X655310Y487690D02*
X656100Y486900D01*
G01X652230Y487690D02*
X655310D01*
G01X645230D02*
X652230D01*
G01X631190Y484490D02*
X634930D01*
G01X628700Y482000D02*
X631190Y484490D01*
G01X611159Y481930D02*
X616930D01*
G01X609284Y480055D02*
X611159Y481930D01*
G01X619010Y469830D02*
X619390Y469450D01*
G01X618197Y469830D02*
X619010D01*
G01X617926Y469559D02*
X618197Y469830D01*
G01X615834Y469559D02*
X617926D01*
G01X621329Y469830D02*
X622000Y469159D01*
G01X619770Y469830D02*
X621329D01*
G01X619390Y469450D02*
X619770Y469830D01*
G01X612800Y466000D02*
X611325D01*
G01X612490Y484490D02*
X616930D01*
G01X612000Y484000D02*
X612490Y484490D01*
G01X609884Y469559D02*
X608800Y468475D01*
G01X612334Y469559D02*
X609884D01*
G01X615549Y523900D02*
Y528899D01*
G01X648000Y497800D02*
X642600D01*
G01X648800Y498600D02*
X648000Y497800D01*
G01X666400Y498600D02*
X648800D01*
G01X639197Y494397D02*
Y490367D01*
G01X642600Y497800D02*
X639197Y494397D01*
G01X617775Y474500D02*
X618800D01*
G01X616034Y472759D02*
X617775Y474500D01*
G01X620541Y472759D02*
X622000D01*
G01X618800Y474500D02*
X620541Y472759D01*
G01X655300Y490250D02*
X656050Y489500D01*
G01X652230Y490250D02*
X655300D01*
G01X649200Y496600D02*
X653800D01*
G01X645400Y492800D02*
X649200Y496600D01*
G01X644036Y492800D02*
X645400D01*
G01X641150Y489914D02*
X644036Y492800D01*
G01X641150Y484300D02*
Y489914D01*
G01X641980Y485130D02*
X641150Y484300D01*
G01X645230Y485130D02*
X641980D01*
G01X663100Y496600D02*
X653800D01*
G01X667137Y492563D02*
X663100Y496600D01*
G01X639630Y479370D02*
X634930D01*
G01X640000Y479000D02*
X639630Y479370D01*
G01X640000Y476500D02*
Y479000D01*
G01X639120Y475620D02*
X640000Y476500D01*
G01X626800Y480337D02*
X625569Y481568D01*
G01X629389Y480337D02*
X626800D01*
G01X630982Y481930D02*
X629389Y480337D01*
G01X634930Y481930D02*
X630982D01*
G01X619975Y464748D02*
X617552D01*
G01X609516Y472759D02*
X608800Y473475D01*
G01X612534Y472759D02*
X609516D01*
G01X605510Y523900D02*
Y528899D01*
G01X615549Y561700D02*
Y566699D01*
G01X605510Y542010D02*
Y537057D01*
G01Y579810D02*
Y574857D01*
G01X659500Y587600D02*
Y591500D01*
G01X659400Y587500D02*
X659500Y587600D01*
G01Y587400D02*
X659400Y587500D01*
G01X659500Y585374D02*
Y587400D01*
G01X662475Y582399D02*
X659500Y585374D01*
G01X665795Y582399D02*
X662475D01*
G01X661100Y587500D02*
X661800Y588200D01*
G01X659400Y587500D02*
X661100D01*
G01X605510Y561700D02*
Y566699D01*
G01X656700Y609900D02*
X655100Y611500D01*
G01X656700Y595723D02*
Y609900D01*
G01X656000Y595023D02*
X656700Y595723D01*
G01X656000Y591500D02*
Y595023D01*
G01X605510Y617610D02*
Y612657D01*
G01X661800Y588800D02*
X662000Y589000D01*
G01X661800Y588200D02*
Y588800D01*
G01X615549Y599500D02*
Y604499D01*
G01X605510Y599500D02*
Y604499D01*
G01X712000Y27500D02*
Y29000D01*
G01X706000Y21500D02*
X712000Y27500D01*
G01X697901Y21500D02*
X706000D01*
G01X695748Y19347D02*
X697901Y21500D01*
G01X695748Y18348D02*
Y19347D01*
G01X695300Y17900D02*
X695748Y18348D01*
G01X692400Y19500D02*
Y20800D01*
G01X694000Y17900D02*
X692400Y19500D01*
G01X695300Y17900D02*
X694000D01*
G01X665396Y18406D02*
X663760D01*
G01X702826Y32200D02*
X704500D01*
G01X702400Y31774D02*
X702826Y32200D01*
G01X702400Y23700D02*
Y31774D01*
G01X704500Y32200D02*
Y37300D01*
G01X706163Y32200D02*
X704500D01*
G01X706463Y32500D02*
X706163Y32200D01*
G01X708500Y32500D02*
X706463D01*
G01X712000D02*
X708500D01*
G01X712500Y17500D02*
X708900D01*
G01Y14600D02*
Y17500D01*
G01X711300Y12200D02*
X708900Y14600D01*
G01X712848Y10652D02*
X711300Y12200D01*
G01X717063Y10652D02*
X712848D01*
G01X713993Y17452D02*
X715937D01*
G01X713945Y17500D02*
X713993Y17452D01*
G01X712500Y17500D02*
X713945D01*
G01X675800Y30800D02*
Y34200D01*
G01X711616Y23716D02*
X708900Y21000D01*
G01X711791Y23716D02*
X711616D01*
G01X677350Y23260D02*
Y27300D01*
G01X676700Y22610D02*
X677350Y23260D01*
G01X676700Y20374D02*
Y22610D01*
G01X683900Y21500D02*
X680700Y24700D01*
G01X683400Y21000D02*
Y17900D01*
G01X683900Y21500D02*
X683400Y21000D01*
G01X678100Y27300D02*
X680700Y24700D01*
G01X677350Y27300D02*
X678100D01*
G01X710150Y257D02*
Y-5950D01*
G01X710551Y658D02*
X710150Y257D01*
G01X710248Y-6048D02*
X710150Y-5950D01*
G01X713937Y-6048D02*
X710248D01*
G01X713989Y-6100D02*
X713937Y-6048D01*
G01X716921Y-6100D02*
X713989D01*
G01X716921Y-6048D02*
Y-6100D01*
G01Y-3832D02*
Y-6048D01*
G01X719031Y-1722D02*
X716921Y-3832D01*
G01X719031Y-652D02*
Y-1722D01*
G01X710150Y-11791D02*
X710327Y-11968D01*
G01X710150Y-9450D02*
Y-11791D01*
G01X711389Y-18333D02*
X713824D01*
G01X707600Y-14544D02*
X711389Y-18333D01*
G01X707600Y12900D02*
Y-14544D01*
G01X704150Y16350D02*
X707600Y12900D01*
G01X704150Y19650D02*
Y16350D01*
G01X671600Y27300D02*
X673850D01*
G01X670400Y26100D02*
X671600Y27300D01*
G01X714176Y92446D02*
X716053Y94323D01*
G01X711074Y92446D02*
X714176D01*
G01X721462Y94323D02*
X716053D01*
G01X723703Y92082D02*
X721462Y94323D01*
G01X723703Y87137D02*
Y92082D01*
G01X720596Y84030D02*
X723703Y87137D01*
G01X720596Y81586D02*
Y84030D01*
G01X714700Y75690D02*
X720596Y81586D01*
G01X716053Y94323D02*
X715089Y95287D01*
G01X702453Y39347D02*
Y41350D01*
G01X704500Y37300D02*
X702453Y39347D01*
G01X670404Y34100D02*
X672900D01*
G01X670227Y34277D02*
X670404Y34100D01*
G01X673000Y34200D02*
X675800D01*
G01X672900Y34100D02*
X673000Y34200D01*
G01X679300Y34300D02*
Y34200D01*
G01X681130Y36130D02*
X679300Y34300D01*
G01X681130Y36185D02*
Y36130D01*
G01X683077Y38132D02*
X681130Y36185D01*
G01X685884Y38132D02*
X683077D01*
G01X686387Y38635D02*
X685884Y38132D01*
G01X686387Y39191D02*
Y38635D01*
G01X688350Y41154D02*
X686387Y39191D01*
G01X688350Y43642D02*
Y41154D01*
G01X697356Y90856D02*
X697100Y90600D01*
G01X717326Y90856D02*
X697356D01*
G01X718916Y92446D02*
X717326Y90856D01*
G01X715753Y99930D02*
X718916D01*
G01X715089Y99266D02*
X715753Y99930D01*
G01X715089Y95287D02*
Y99266D01*
G01X702100Y258900D02*
X703700D01*
G01X700400Y257200D02*
X702100Y258900D01*
G01X710500Y260000D02*
X710700Y260200D01*
G01X710500Y258500D02*
Y260000D01*
G01X708000Y256000D02*
X710500Y258500D01*
G01X707500Y256000D02*
X708000D01*
G01X712200Y260200D02*
X710700D01*
G01X714500Y262500D02*
X712200Y260200D01*
G01X715739Y262500D02*
X714500D01*
G01X716839Y263600D02*
X715739Y262500D01*
G01X717000Y257560D02*
X718246Y258806D01*
G01X717000Y256000D02*
Y257560D01*
G01Y256000D02*
X714000D01*
G01X719200Y259760D02*
X718246Y258806D01*
G01X719200Y260700D02*
Y259760D01*
G01X719988Y261488D02*
X719200Y260700D01*
G01X719988Y263600D02*
Y261488D01*
G01X678400Y254700D02*
X677800Y254100D01*
G01X678400Y256300D02*
Y254700D01*
G01X677212Y257488D02*
X678400Y256300D01*
G01X675750Y257488D02*
X677212D01*
G01X720500Y250000D02*
X720450Y249950D01*
G01X720500Y252500D02*
Y250000D01*
G01Y249900D02*
Y247500D01*
G01X720450Y249950D02*
X720500Y249900D01*
G01X717000Y250680D02*
Y252500D01*
G01X717420Y250260D02*
X717000Y250680D01*
G01X717420Y249920D02*
Y250260D01*
G01X723138Y260138D02*
X721921Y258921D01*
G01X723138Y263600D02*
Y260138D01*
G01X720500Y257500D02*
Y256000D01*
G01X721921Y258921D02*
X720500Y257500D01*
G01X665451Y278905D02*
Y280697D01*
G01X665463Y278893D02*
X665451Y278905D01*
G01X665463Y275120D02*
Y278893D01*
G01X665313Y274970D02*
X665463Y275120D01*
G01X665313Y272650D02*
Y274970D01*
G01X710690Y270430D02*
X705320D01*
G01X712898Y272638D02*
X710690Y270430D01*
G01X714100Y272638D02*
X712898D01*
G01X723500Y249900D02*
Y247500D01*
G01X723400Y250000D02*
X723500Y249900D01*
G01Y250100D02*
X723400Y250000D01*
G01X723500Y252500D02*
Y250100D01*
G01X664456Y278867D02*
X663300Y280023D01*
G01X664456Y277002D02*
Y278867D01*
G01X663738Y276284D02*
X664456Y277002D01*
G01X663738Y272650D02*
Y276284D01*
G01X711096Y269597D02*
X703438D01*
G01X712562Y271063D02*
X711096Y269597D01*
G01X714100Y271063D02*
X712562D01*
G01X707200Y257861D02*
Y258900D01*
G01X707002Y257663D02*
X707200Y257861D01*
G01X706226Y257663D02*
X707002D01*
G01X705837Y257274D02*
X706226Y257663D01*
G01X705837Y255475D02*
Y257274D01*
G01X704662Y254300D02*
X705837Y255475D01*
G01X701757Y254300D02*
X704662D01*
G01X701134Y253677D02*
X701757Y254300D01*
G01X707000Y265500D02*
Y262000D01*
G01X707200Y260500D02*
Y258900D01*
G01X707000Y260700D02*
X707200Y260500D01*
G01X707000Y262000D02*
Y260700D01*
G01X710400Y265500D02*
X707000D01*
G01X712813Y267913D02*
X710400Y265500D01*
G01X714100Y267913D02*
X712813D01*
G01X713900Y258900D02*
X715200D01*
G01X711000Y256000D02*
X713900Y258900D01*
G01X718413Y262113D02*
X715200Y258900D01*
G01X718413Y263600D02*
Y262113D01*
G01X713589Y266339D02*
X710675Y263425D01*
G01X714100Y266339D02*
X713589D01*
G01X723500Y257472D02*
Y256000D01*
G01X724713Y258685D02*
X723500Y257472D01*
G01X724713Y263600D02*
Y258685D01*
G01X680012Y285588D02*
X683490Y282110D01*
G01X678268Y285588D02*
X680012D01*
G01X675880Y299770D02*
Y301548D01*
G01X677390Y298260D02*
X675880Y299770D01*
G01X681088Y298260D02*
X677390D01*
G01X684056Y295292D02*
X681088Y298260D01*
G01X684056Y294136D02*
Y295292D01*
G01X682000Y292080D02*
X684056Y294136D01*
G01X682000Y286750D02*
Y292080D01*
G01X683162Y285588D02*
X682000Y286750D01*
G01X685268Y285588D02*
X683162D01*
G01X698600Y337900D02*
X701000Y335500D01*
G01X698600Y338900D02*
Y337900D01*
G01X688100Y308450D02*
Y308600D01*
G01X687569Y307919D02*
X688100Y308450D01*
G01X684219Y307919D02*
X687569D01*
G01X688100Y308650D02*
Y308600D01*
G01X686862Y309888D02*
X688100Y308650D01*
G01X684219Y309888D02*
X686862D01*
G01X686860Y325640D02*
X687300Y325200D01*
G01X684219Y325640D02*
X686860D01*
G01X702000Y338100D02*
X701100Y339000D01*
G01X702400Y338100D02*
X702000D01*
G01X705000Y335500D02*
X702400Y338100D01*
G01X686809Y327609D02*
X687400Y328200D01*
G01X684219Y327609D02*
X686809D01*
G01X675880Y338020D02*
X674700Y339200D01*
G01X675880Y335948D02*
Y338020D01*
G01X673911Y338411D02*
X674700Y339200D01*
G01X673911Y335948D02*
Y338411D01*
G01X685658Y297778D02*
X686140Y298260D01*
G01X683300Y297778D02*
X685658D01*
G01X681748Y299330D02*
X683300Y297778D01*
G01X678840Y299330D02*
X681748D01*
G01X677849Y300321D02*
X678840Y299330D01*
G01X677849Y301548D02*
Y300321D01*
G01X687850Y298260D02*
X686140D01*
G01X692470Y293640D02*
X687850Y298260D01*
G01X665463Y284337D02*
X665000Y284800D01*
G01X665463Y280709D02*
Y284337D01*
G01X665451Y280697D02*
X665463Y280709D01*
G01X673500Y297656D02*
X673922Y298078D01*
G01X673500Y295000D02*
Y297656D01*
G01X671942Y300058D02*
X673922Y298078D01*
G01X671942Y301548D02*
Y300058D01*
G01X663300Y280023D02*
Y281820D01*
G01Y283700D02*
Y281820D01*
G01X680624Y295496D02*
Y295168D01*
G01X679145Y296975D02*
X680624Y295496D01*
G01X677395Y296975D02*
X679145D01*
G01X673911Y300459D02*
X677395Y296975D01*
G01X673911Y301548D02*
Y300459D01*
G01X678268Y292018D02*
Y290706D01*
G01X680624Y294374D02*
X678268Y292018D01*
G01X680624Y295168D02*
Y294374D01*
G01X685268Y288147D02*
X688924D01*
G01X675241D02*
X674469Y287375D01*
G01X678268Y288147D02*
X675241D01*
G01X686470Y282870D02*
Y282220D01*
G01X690680Y287080D02*
X686470Y282870D01*
G01X690680Y288799D02*
Y287080D01*
G01X688773Y290706D02*
X690680Y288799D01*
G01X685268Y290706D02*
X688773D01*
G01X686934Y384926D02*
X687427D01*
G01X684967Y382959D02*
X686934Y384926D01*
G01X684967Y379176D02*
Y382959D01*
G01X680304Y386589D02*
X679523Y385808D01*
G01X688116Y386589D02*
X680304D01*
G01X690087Y384618D02*
X688116Y386589D01*
G01X690087Y379176D02*
Y384618D01*
G01Y399299D02*
Y402676D01*
G01X684956Y394168D02*
X690087Y399299D01*
G01X684956Y391301D02*
Y394168D01*
G01X685393Y390864D02*
X684956Y391301D01*
G01X689889Y390864D02*
X685393D01*
G01X690653Y390100D02*
X689889Y390864D01*
G01X691179Y390100D02*
X690653D01*
G01X691240Y390039D02*
X691179Y390100D01*
G01X676900Y382200D02*
Y381800D01*
G01X678800Y384100D02*
X676900Y382200D01*
G01X681457Y384100D02*
X678800D01*
G01X682407Y383150D02*
X681457Y384100D01*
G01X682407Y379176D02*
Y383150D01*
G01X683200Y397300D02*
X684700D01*
G01X682407Y398093D02*
X683200Y397300D01*
G01X682407Y402676D02*
Y398093D01*
G01X684967Y397567D02*
X684700Y397300D01*
G01X684967Y402676D02*
Y397567D01*
G01X683100Y395700D02*
Y392200D01*
G01X684700Y397300D02*
X683100Y395700D01*
G01X678772Y362799D02*
Y359140D01*
G01X678730Y362841D02*
X678772Y362799D01*
G01X678100Y393600D02*
Y420600D01*
G01X682261Y389439D02*
X678100Y393600D01*
G01X689298Y389439D02*
X682261D01*
G01X691237Y387500D02*
X689298Y389439D01*
G01X693900Y387500D02*
X691237D01*
G01X697000Y384400D02*
X693900Y387500D01*
G01X697000Y381725D02*
Y384400D01*
G01X697935Y380790D02*
X697000Y381725D01*
G01X731210Y380790D02*
X697935D01*
G01X695014Y366114D02*
X684378Y355478D01*
G01X709646Y366114D02*
X695014D01*
G01X722712Y379180D02*
X709646Y366114D01*
G01X731180Y379180D02*
X722712D01*
G01X687527Y373573D02*
X689900Y371200D01*
G01X687527Y379176D02*
Y373573D01*
G01X693346Y371200D02*
X694662Y369884D01*
G01X689900Y371200D02*
X693346D01*
G01X680076Y388014D02*
X679385Y388705D01*
G01X688707Y388014D02*
X680076D01*
G01X690646Y386075D02*
X688707Y388014D01*
G01X690647Y386075D02*
X690646D01*
G01X692647Y384075D02*
X690647Y386075D01*
G01X692647Y379176D02*
Y384075D01*
G01Y396197D02*
Y402676D01*
G01X689050Y392600D02*
X692647Y396197D01*
G01X686619Y392600D02*
X689050D01*
G01X684126Y372346D02*
Y369876D01*
G01X683056Y373416D02*
X684126Y372346D01*
G01X681796Y373416D02*
X683056D01*
G01X679847Y375365D02*
X681796Y373416D01*
G01X679847Y379176D02*
Y375365D01*
G01X680498Y371200D02*
X679400D01*
G01X681822Y369876D02*
X680498Y371200D01*
G01X684126Y369876D02*
X681822D01*
G01X693200Y424000D02*
Y420275D01*
G01X693091Y424109D02*
X693200Y424000D01*
G01X693091Y429925D02*
Y424109D01*
G01X725200Y452034D02*
X723091Y449925D01*
G01X718300Y469035D02*
X725200Y462135D01*
G01X696400Y424596D02*
Y420275D01*
G01X695700Y425296D02*
X696400Y424596D01*
G01X695700Y432316D02*
Y425296D01*
G01X693091Y434925D02*
X695700Y432316D01*
G01X720600Y462702D02*
X713866Y469436D01*
G01X720600Y454700D02*
Y462702D01*
G01X718100Y452200D02*
X720600Y454700D01*
G01X718100Y450000D02*
Y452200D01*
G01X718091Y449925D02*
X718100Y450000D01*
G01X686000Y457600D02*
X693700Y465300D01*
G01X686000Y449600D02*
Y457600D01*
G01X683800Y447400D02*
X686000Y449600D01*
G01X671367Y427000D02*
X671366Y427001D01*
G01X671700Y427000D02*
X671367D01*
G01X678100Y420600D02*
X671700Y427000D01*
G01X723091Y462228D02*
X716100Y469219D01*
G01X723091Y454925D02*
Y462228D01*
G01X733100Y456251D02*
X719225Y470126D01*
G01X718100Y455000D02*
X718091Y454925D01*
G01X718100Y462787D02*
Y455000D01*
G01X712441Y468446D02*
X718100Y462787D01*
G01X708500Y518750D02*
X712100D01*
G01X704500D02*
X708500D01*
G01X702453Y525947D02*
Y527600D01*
G01X704500Y523900D02*
X702453Y525947D01*
G01X704500Y518750D02*
Y523900D01*
G01X702300Y510000D02*
X702100Y509800D01*
G01X702300Y518099D02*
Y510000D01*
G01X702951Y518750D02*
X702300Y518099D01*
G01X704500Y518750D02*
X702951D01*
G01X682050Y500030D02*
X681990Y499970D01*
G01X682050Y503970D02*
Y500030D01*
G01X724056Y485344D02*
X725400Y484000D01*
G01X724056Y485445D02*
Y485344D01*
G01X721301Y488200D02*
X724056Y485445D01*
G01X718300Y482020D02*
Y469035D01*
G01X714920Y485400D02*
X718300Y482020D01*
G01X714920Y502318D02*
Y485400D01*
G01X717563Y504961D02*
X714920Y502318D01*
G01X717563Y506539D02*
Y504961D01*
G01X716789Y507313D02*
X717563Y506539D01*
G01X715211Y507313D02*
X716789D01*
G01X715198Y507300D02*
X715211Y507313D01*
G01X715000Y507300D02*
X715198D01*
G01X713200Y505500D02*
X715000Y507300D01*
G01X670958Y503158D02*
X666400Y498600D01*
G01X674259Y503158D02*
X670958D01*
G01X677300Y506199D02*
X674259Y503158D01*
G01X677300Y516800D02*
Y506199D01*
G01X678250Y517750D02*
X677300Y516800D01*
G01X679000Y517750D02*
X678250D01*
G01X679000Y521250D02*
X678650Y521600D01*
G01X679000Y517750D02*
Y521250D01*
G01X673000Y497700D02*
X676600Y501300D01*
G01X670400Y497700D02*
X673000D01*
G01X723775Y471226D02*
X738091Y456910D01*
G01X723775Y482325D02*
Y471226D01*
G01X720300Y485800D02*
X723775Y482325D01*
G01X707850Y505651D02*
Y505700D01*
G01X713015Y500486D02*
X707850Y505651D01*
G01X713015Y484687D02*
Y500486D01*
G01X713866Y483836D02*
X713015Y484687D01*
G01X713866Y469436D02*
Y483836D01*
G01X719500Y507072D02*
X721414Y508986D01*
G01X719500Y504280D02*
Y507072D01*
G01X716808Y501588D02*
X719500Y504280D01*
G01X716808Y486130D02*
Y501588D01*
G01X720500Y482438D02*
X716808Y486130D01*
G01X720500Y470501D02*
Y482438D01*
G01X735300Y455701D02*
X720500Y470501D01*
G01X714669Y512917D02*
X715009D01*
G01X709552Y507800D02*
X714669Y512917D01*
G01X706900Y507800D02*
X709552D01*
G01X701800Y502700D02*
X706900Y507800D01*
G01X689200Y502700D02*
X701800D01*
G01X686463Y499963D02*
X689200Y502700D01*
G01X686463Y485537D02*
Y499963D01*
G01X693700Y478300D02*
X686463Y485537D01*
G01X693700Y465300D02*
Y478300D01*
G01X678770Y499970D02*
X679430D01*
G01X671363Y492563D02*
X678770Y499970D01*
G01X670185Y492563D02*
X671363D01*
G01X670185D02*
X667137D01*
G01X714791Y481569D02*
X716100Y480260D01*
G01X714791Y484220D02*
Y481569D01*
G01X713992Y485019D02*
X714791Y484220D01*
G01X713992Y503742D02*
Y485019D01*
G01X715900Y505650D02*
X713992Y503742D01*
G01X716100Y469219D02*
Y480260D01*
G01X718488Y509261D02*
X720565Y511338D01*
G01X718488Y504577D02*
Y509261D01*
G01X715845Y501934D02*
X718488Y504577D01*
G01X715845Y485784D02*
Y501934D01*
G01X719225Y482404D02*
X715845Y485784D01*
G01X719225Y470126D02*
Y482404D01*
G01X712100Y515250D02*
Y512700D01*
G01X723792Y489148D02*
X727063Y485877D01*
G01X683350Y521600D02*
X682150D01*
G01X686000Y524250D02*
X683350Y521600D01*
G01X686000Y524999D02*
Y524250D01*
G01X688350Y527349D02*
X686000Y524999D01*
G01X712441Y483859D02*
Y468446D01*
G01X710760Y485540D02*
X712441Y483859D01*
G01X710760Y488200D02*
Y485540D01*
G01Y490460D02*
Y488200D01*
G01X711339Y491039D02*
X710760Y490460D01*
G01X711339Y499478D02*
Y491039D01*
G01X683700Y489400D02*
X679700D01*
G01X684550Y490250D02*
X683700Y489400D01*
G01X684550Y492970D02*
Y490250D01*
G01X681990Y490940D02*
Y492970D01*
G01X681275Y490225D02*
X681990Y490940D01*
G01X680525Y490225D02*
X681275D01*
G01X679700Y489400D02*
X680525Y490225D01*
G01X712511Y563200D02*
X729980D01*
G01X708155Y567556D02*
X712511Y563200D01*
G01X686450Y587850D02*
X686500Y587800D01*
G01X686450Y591000D02*
Y587850D01*
G01X677099Y584367D02*
Y589116D01*
G01X703344Y567556D02*
X702100Y568800D01*
G01X704655Y567556D02*
X703344D01*
G01X714890Y564125D02*
X708153Y570862D01*
G01X730364Y564125D02*
X714890D01*
G01X724974Y584050D02*
X725400Y583624D01*
G01X723980Y584050D02*
X724974D01*
G01X688350Y529892D02*
Y527349D01*
G01X702538Y570862D02*
X704653D01*
G01X702000Y571400D02*
X702538Y570862D01*
G01X698730Y585220D02*
X692950Y591000D01*
G01X698730Y579030D02*
Y585220D01*
G01X695600Y575900D02*
X698730Y579030D01*
G01X693200Y575900D02*
X695600D01*
G01X682640Y591000D02*
X686450D01*
G01X677880Y589897D02*
Y591560D01*
G01X677099Y589116D02*
X677880Y589897D01*
G01X680710Y591000D02*
X682640D01*
G01X680150Y591560D02*
X680710Y591000D01*
G01X677880Y591560D02*
X680150D01*
G01X722012Y598556D02*
X722406Y598950D01*
G01X722012Y595354D02*
Y598556D01*
G01X723956Y600500D02*
X726800D01*
G01X722406Y598950D02*
X723956Y600500D01*
G01X692950Y591000D02*
X689950D01*
G01X764289Y218589D02*
X762300Y216600D01*
G01X726287Y263600D02*
Y258979D01*
G01X726500Y257772D02*
Y256000D01*
G01X726287Y257985D02*
X726500Y257772D01*
G01X726287Y258979D02*
Y257985D01*
G01X756879Y249020D02*
X756639Y248780D01*
G01X761600Y249020D02*
X756879D01*
G01X728291Y252966D02*
X730000Y254675D01*
G01X728291Y247500D02*
Y252966D01*
G01X728770Y255905D02*
X730000Y254675D01*
G01X728770Y258190D02*
Y255905D01*
G01X727862Y259098D02*
X728770Y258190D01*
G01X727862Y263600D02*
Y259098D01*
G01X765186Y218589D02*
X764289D01*
G01X726500Y250151D02*
Y252500D01*
G01X726328Y249979D02*
X726500Y250151D01*
G01X761850Y279060D02*
Y282668D01*
G01X762417Y311705D02*
Y316392D01*
G01X759900Y309188D02*
X762417Y311705D01*
G01X731012Y291412D02*
X732700Y293100D01*
G01X731012Y286400D02*
Y291412D01*
G01X734200Y294600D02*
Y297650D01*
G01X732700Y293100D02*
X734200Y294600D01*
G01X761972Y282730D02*
X761942Y282760D01*
G01X768930Y282730D02*
X761972D01*
G01X770435Y284235D02*
X768930Y282730D01*
G01X771773Y284235D02*
X770435D01*
G01X761850Y282668D02*
X761942Y282760D01*
G01X769787Y348235D02*
X771773D01*
G01X768426Y346874D02*
X769787Y348235D01*
G01X766236Y346874D02*
X768426D01*
G01X765700Y346338D02*
X766236Y346874D01*
G01X763912Y346338D02*
X765700D01*
G01X763020Y347230D02*
X763912Y346338D01*
G01X762350Y347230D02*
X763020D01*
G01X732000Y380000D02*
X731210Y380790D01*
G01X732000Y380000D02*
X731180Y379180D01*
G01X740700Y452316D02*
X743091Y449925D01*
G01X740700Y456600D02*
Y452316D01*
G01X725400Y471900D02*
X740700Y456600D01*
G01X740015Y447483D02*
X739933Y447401D01*
G01X740015Y448085D02*
Y447483D01*
G01X738100Y450000D02*
X740015Y448085D01*
G01X738091Y449925D02*
X738100Y450000D01*
G01X725200Y462135D02*
Y452034D01*
G01X738091Y456910D02*
Y454925D01*
G01X735300Y452134D02*
Y455701D01*
G01X733091Y449925D02*
X735300Y452134D01*
G01X744625Y444925D02*
X747950Y441600D01*
G01X743091Y444925D02*
X744625D01*
G01X744303Y434925D02*
X743091D01*
G01X746151Y433077D02*
X744303Y434925D01*
G01X745725Y429925D02*
X743091D01*
G01X745930Y430130D02*
X745725Y429925D01*
G01X746130Y430130D02*
X745930D01*
G01X747475Y439925D02*
X748500Y438900D01*
G01X743091Y439925D02*
X747475D01*
G01X733100Y455000D02*
Y456251D01*
G01X733091Y454925D02*
X733100Y455000D01*
G01X743091Y456508D02*
Y454925D01*
G01X727063Y472536D02*
X743091Y456508D01*
G01X733152Y503637D02*
X734056D01*
G01X730709Y506080D02*
X733152Y503637D01*
G01X726040Y506080D02*
X730709D01*
G01X735758Y503637D02*
X734056D01*
G01X730250Y496153D02*
X727916D01*
G01X732469Y498372D02*
X730250Y496153D01*
G01X732469Y502050D02*
Y498372D01*
G01X734056Y503637D02*
X732469Y502050D01*
G01X725400Y484000D02*
Y471900D01*
G01X729875Y512375D02*
X729000Y511500D01*
G01X729875Y513383D02*
Y512375D01*
G01X741259Y524767D02*
X729875Y513383D01*
G01X745670Y524767D02*
X741259D01*
G01X751056Y530153D02*
X745670Y524767D01*
G01X746054Y523842D02*
X751981Y529769D01*
G01X741643Y523842D02*
X746054D01*
G01X730802Y513001D02*
X741643Y523842D01*
G01X730802Y512398D02*
Y513001D01*
G01X731600Y511600D02*
X730802Y512398D01*
G01X727063Y485877D02*
Y472536D01*
G01X737648Y496153D02*
X735758D01*
G01X738648Y495153D02*
X737648Y496153D01*
G01X738648Y492050D02*
Y495153D01*
G01X751056Y535757D02*
Y530153D01*
G01X744738Y542075D02*
X751056Y535757D01*
G01X741589Y542075D02*
X744738D01*
G01X736110Y547554D02*
X741589Y542075D01*
G01X736110Y557070D02*
Y547554D01*
G01X729980Y563200D02*
X736110Y557070D01*
G01X737035Y557454D02*
X730364Y564125D01*
G01X737035Y547938D02*
Y557454D01*
G01X741973Y543000D02*
X737035Y547938D01*
G01X745122Y543000D02*
X741973D01*
G01X751982Y536140D02*
X745122Y543000D01*
G01X751982Y535374D02*
Y536140D01*
G01X751981Y535373D02*
X751982Y535374D01*
G01X751981Y529769D02*
Y535373D01*
G01X732600Y573950D02*
X730100D01*
G01X730050Y577500D02*
X730100Y577450D01*
G01X726500Y577500D02*
X730050D01*
G01X726500Y579800D02*
Y577500D01*
G01X725400Y580900D02*
X726500Y579800D01*
G01X725400Y583624D02*
Y580900D01*
G01X730100Y604000D02*
X733032D01*
G01X726800Y600500D02*
X730100D01*
G01X787572Y201290D02*
X786709Y200427D01*
G01X792514Y201290D02*
X787572D01*
G01X797123Y194410D02*
X799224Y192309D01*
G01X797123Y201313D02*
Y194410D01*
G01X797717Y201907D02*
X797123Y201313D01*
G01X814849Y203282D02*
Y205001D01*
G01X817821Y200310D02*
X814849Y203282D01*
G01X817821Y193049D02*
Y200310D01*
G01X818960Y196448D02*
Y202230D01*
G01X823206Y192202D02*
X818960Y196448D01*
G01X812555Y203529D02*
X808165D01*
G01X816164Y199920D02*
X812555Y203529D01*
G01X816164Y194820D02*
Y199920D01*
G01X813248Y191904D02*
X816164Y194820D01*
G01X813248Y190338D02*
Y191904D01*
G01X802000Y420000D02*
X803500D01*
G01X798500Y416500D02*
X802000Y420000D01*
G01X798500Y412600D02*
Y416500D01*
G01X801500Y417000D02*
X803500D01*
G01X800620Y416120D02*
X801500Y417000D01*
G01X800620Y415010D02*
Y416120D01*
G01X800610Y415000D02*
X800620Y415010D01*
G01X957283Y22923D02*
Y28014D01*
G01X957285Y22923D02*
X957283D01*
G01Y-7662D02*
X957765Y-7180D01*
G01X957283Y-14877D02*
Y-7662D01*
G01X957285Y-14877D02*
X957283D01*
G01X967324Y3233D02*
X967322Y-4536D01*
G01X957283Y67549D02*
X957536Y67802D01*
G01X957283Y60723D02*
Y67549D01*
G01X957285Y60723D02*
X957283D01*
G01X967324Y78833D02*
X967322Y73757D01*
G01X967324Y41033D02*
X967322Y35957D01*
G01X919717Y209109D02*
X917467D01*
G01X926477Y205210D02*
X924227D01*
G01X926477Y201309D02*
X924227D01*
G01X923097Y207159D02*
X920847D01*
G01X926477Y209109D02*
X924227D01*
G01X946757Y197409D02*
X944507D01*
G01X923097Y203260D02*
X920847D01*
G01X929857Y199360D02*
X927607D01*
G01X963656Y242260D02*
X961406D01*
G01X973796Y279310D02*
X971546D01*
G01X946757Y271509D02*
X944507D01*
G01X943377Y273460D02*
X941127D01*
G01X929857D02*
X927607D01*
G01X950137D02*
X947887D01*
G01X967036Y248109D02*
X964786D01*
G01X967036Y244209D02*
X964786D01*
G01X950137Y269560D02*
X947887D01*
G01X953517Y271509D02*
X951267D01*
G01X973796Y252009D02*
X971546D01*
G01X946757Y267609D02*
X944507D01*
G01X926477Y271509D02*
X924227D01*
G01X970416Y250060D02*
X968166D01*
G01X963656Y246160D02*
X961406D01*
G01X960276Y248109D02*
X958026D01*
G01X939997Y322209D02*
X937747D01*
G01X946757Y326110D02*
X944507D01*
G01X943377Y320260D02*
X941127D01*
G01X946757Y330009D02*
X944507D01*
G01X936617Y320260D02*
X934367D01*
G01X943377Y324160D02*
X941127D01*
G01X929857D02*
X927607D01*
G01X933237Y322209D02*
X930987D01*
G01X926477Y400209D02*
X924227D01*
G01X963656Y347560D02*
X961406D01*
G01X973796Y341709D02*
X971546D01*
G01X933237Y400209D02*
X930987D01*
G01X919717Y392410D02*
X917467D01*
G01X960276Y349509D02*
X958026D01*
G01X967036Y353409D02*
X964786D01*
G01X923097Y394359D02*
X920847D01*
G01X967036Y349509D02*
X964786D01*
G01X923097Y398260D02*
X920847D01*
G01X929857D02*
X927607D01*
G01X967036Y384609D02*
X964786D01*
G01X973796Y345609D02*
X971546D01*
G01X926477Y396309D02*
X924227D01*
G01X946757Y400209D02*
X944507D01*
G01X963656Y351460D02*
X961406D01*
G01X967036Y380709D02*
X964786D01*
G01X963656Y355360D02*
X961406D01*
G01X957283Y523923D02*
Y528340D01*
G01X957285Y523900D02*
X957283Y523923D01*
G01Y566434D02*
X957592Y566743D01*
G01X957283Y561723D02*
Y566434D01*
G01X957285Y561700D02*
X957283Y561723D01*
G01Y528340D02*
X957806Y528863D01*
G01X967324Y542010D02*
X967322Y536957D01*
G01X967324Y579810D02*
X967322Y574757D01*
G01X957283Y606738D02*
X957765Y607220D01*
G01X957283Y599523D02*
Y606738D01*
G01X957285Y599500D02*
X957283Y599523D01*
G01X967324Y617610D02*
X967322Y609864D01*
G01X987316Y205210D02*
X988446Y207158D01*
G01X994076Y216909D02*
X991826D01*
G01X997456Y211060D02*
X995206D01*
G01X1000836Y213009D02*
X998586D01*
G01X989900Y204712D02*
X988446Y203258D01*
G01X989900Y206363D02*
Y204712D01*
G01X990696Y207159D02*
X989900Y206363D01*
G01X983936Y277360D02*
X981686D01*
G01X980556Y279310D02*
X978306D01*
G01X987316Y228610D02*
X985066D01*
G01X1000836Y259809D02*
X998586D01*
G01X997456Y261760D02*
X995206D01*
G01X997456Y250060D02*
X995206D01*
G01X1031255Y242260D02*
X1029005D01*
G01X980556Y228610D02*
X978306D01*
G01X990696Y269560D02*
X988446D01*
G01X983936Y226660D02*
X981686D01*
G01X1021115Y248109D02*
X1018865D01*
G01X1025625Y244209D02*
X1027875D01*
G01X1004215Y250060D02*
X1001965D01*
G01X1014355Y248109D02*
X1012105D01*
G01X987316Y220809D02*
X985066D01*
G01X1034635Y244209D02*
X1032385D01*
G01X997456Y257860D02*
X995206D01*
G01X990696Y273460D02*
X988446D01*
G01X1004215Y253960D02*
X1001965D01*
G01X1034635Y240309D02*
X1032385D01*
G01X987316Y271509D02*
X985066D01*
G01X997456Y222760D02*
X995206D01*
G01X1024495Y246160D02*
X1022245D01*
G01X1031255D02*
X1029005D01*
G01X1000836Y255909D02*
X998586D01*
G01X1007595Y252009D02*
X1005345D01*
G01X977176Y277360D02*
X974926D01*
G01X983936Y222760D02*
X981686D01*
G01X990696Y277360D02*
X988446D01*
G01X1010975Y253960D02*
X1008725D01*
G01X980556Y271509D02*
X978306D01*
G01X1014355Y252009D02*
X1012105D01*
G01X983936Y273460D02*
X981686D01*
G01X1010975Y250060D02*
X1008725D01*
G01X1000836Y252009D02*
X998586D01*
G01X997456Y253960D02*
X995206D01*
G01X1007595Y255909D02*
X1005345D01*
G01X983936Y230559D02*
X981686D01*
G01X1017735Y246160D02*
X1015485D01*
G01X980556Y224709D02*
X978306D01*
G01X980556Y275409D02*
X978306D01*
G01X1017735Y250060D02*
X1015485D01*
G01X987316Y275409D02*
X985066D01*
G01X987316Y279310D02*
X985066D01*
G01X1004215Y257860D02*
X1001965D01*
G01X987316Y232509D02*
X985066D01*
G01X1004215Y339760D02*
X1001965D01*
G01X1034635Y357309D02*
X1032385D01*
G01X983936Y367060D02*
X981686D01*
G01X987316Y369010D02*
X985066D01*
G01X983936Y374860D02*
X981686D01*
G01X997456D02*
X995206D01*
G01X1007595Y345609D02*
X1005345D01*
G01X1007595Y341709D02*
X1005345D01*
G01X980556Y369010D02*
X978306D01*
G01X997456Y347560D02*
X995206D01*
G01X1004215Y343660D02*
X1001965D01*
G01X1010975D02*
X1008725D01*
G01X1031255Y355360D02*
X1029005D01*
G01X1017735Y351460D02*
X1015485D01*
G01X1017735Y347560D02*
X1015485D01*
G01X1022245Y351460D02*
X1024495D01*
G01X1004215Y347560D02*
X1001965D01*
G01X1014355Y345609D02*
X1012105D01*
G01X1025625Y349509D02*
X1027875D01*
G01X1010975Y347560D02*
X1008725D01*
G01X983936Y370959D02*
X981686D01*
G01X980556Y372909D02*
X978306D01*
G01X987316Y376809D02*
X985066D01*
G01X987316Y365109D02*
X985066D01*
G01X990696Y363160D02*
X988446D01*
G01X1000836Y384609D02*
X998586D01*
G01X1014355Y349509D02*
X1012105D01*
G01X1034635Y353409D02*
X1032385D01*
G01X1031255Y351460D02*
X1029005D01*
G01X994076Y349509D02*
X991826D01*
G01X1071065Y3233D02*
X1071062Y-1817D01*
G01X1061025Y3233D02*
X1061023Y-4536D01*
G01X1061025Y41033D02*
X1061024Y35957D01*
G01X1044293Y68961D02*
X1044290Y68964D01*
G01X1044293Y60723D02*
Y68961D01*
G01Y56910D02*
Y60723D01*
G01X1044291Y56908D02*
X1044293Y56910D01*
G01X1087795Y35959D02*
X1087797Y35957D01*
G01X1087795Y41033D02*
Y35959D01*
G01X1087797Y41033D02*
X1087795D01*
G01X1071063Y46921D02*
X1071064Y46922D01*
G01X1071063Y41033D02*
Y46921D01*
G01X1071065Y41033D02*
X1071063D01*
G01Y78833D02*
X1071065D01*
G01X1071063Y73758D02*
Y78833D01*
G01X1071064Y73757D02*
X1071063Y73758D01*
G01X1069081Y71774D02*
X1071064Y73757D01*
G01X1043402Y71774D02*
X1069081D01*
G01X1042500Y70872D02*
X1043402Y71774D01*
G01X1042500Y56300D02*
Y70872D01*
G01X1044100Y54700D02*
X1042500Y56300D01*
G01X1087795Y73759D02*
X1087797Y73757D01*
G01X1087795Y78833D02*
Y73759D01*
G01X1087797Y78833D02*
X1087795D01*
G01X1061025D02*
X1061024Y73757D01*
G01X1051534Y211060D02*
X1049284D01*
G01X1084500Y271500D02*
Y272000D01*
G01X1089000Y267000D02*
X1084500Y271500D01*
G01X1091500Y270500D02*
Y272000D01*
G01X1093000Y269000D02*
X1091500Y270500D01*
G01X1095490Y269000D02*
X1093000D01*
G01X1044774Y242260D02*
X1042524D01*
G01X1054914Y244209D02*
X1057314D01*
G01X1048154Y240309D02*
X1045904D01*
G01X1051534Y246160D02*
X1049284D01*
G01X1041395Y240309D02*
X1039145D01*
G01X1038015Y246160D02*
X1035765D01*
G01X1088000Y271500D02*
Y272000D01*
G01X1092300Y267200D02*
X1088000Y271500D01*
G01X1041395Y244209D02*
X1039145D01*
G01X1038015Y242260D02*
X1035765D01*
G01X1044774Y246160D02*
X1042524D01*
G01X1051534Y242260D02*
X1049284D01*
G01X1094764Y271972D02*
X1096290D01*
G01X1089000Y264500D02*
X1089100D01*
G01X1087500Y266000D02*
X1089000Y264500D01*
G01X1087500Y266400D02*
Y266000D01*
G01X1083600Y270300D02*
X1087500Y266400D01*
G01X1082200Y270300D02*
X1083600D01*
G01X1080500Y272000D02*
X1082200Y270300D01*
G01X1048154Y244209D02*
X1045904D01*
G01X1075220Y336830D02*
Y342380D01*
G01X1076270Y335780D02*
X1075220Y336830D01*
G01X1058294Y382660D02*
X1060694D01*
G01X1084591Y378047D02*
X1086841D01*
G01X1038015Y355360D02*
X1035765D01*
G01X1058294Y394359D02*
X1060694D01*
G01X1051534Y355360D02*
X1049284D01*
G01X1087971Y376096D02*
X1090221D01*
G01X1075220Y342380D02*
X1076435Y343595D01*
G01X1058294Y355360D02*
X1060694D01*
G01X1091351Y374146D02*
X1093601D01*
G01X1058294Y390460D02*
X1060694D01*
G01X1077832Y358547D02*
X1080082D01*
G01X1054914Y396309D02*
X1052664D01*
G01X1058294Y378760D02*
X1060694D01*
G01X1051717Y398666D02*
X1052500Y400400D01*
G01X1051534Y398260D02*
X1051717Y398666D01*
G01X1058294Y386560D02*
X1060694D01*
G01X1051534D02*
X1049284D01*
G01X1058294Y367060D02*
X1064371D01*
G01X1058294Y370959D02*
X1060963D01*
G01X1054914Y353409D02*
X1052664D01*
G01X1051534Y359260D02*
X1049284D01*
G01X1060948D02*
X1061039Y359351D01*
G01X1058294Y359260D02*
X1060948D01*
G01X1091351Y370247D02*
X1093601D01*
G01X1058294Y363160D02*
X1061055D01*
G01X1081212Y356596D02*
X1083462D01*
G01X1048154Y400209D02*
Y402900D01*
G01X1044293Y528928D02*
Y523900D01*
G01X1087797Y579810D02*
Y574757D01*
G01X1044291Y555958D02*
Y561700D01*
G01X1042377Y554044D02*
X1044291Y555958D01*
G01X1042377Y530844D02*
Y554044D01*
G01X1044195Y529026D02*
X1042377Y530844D01*
G01X1044293Y561700D02*
X1044291D01*
G01X1042378Y574122D02*
Y589678D01*
G01X1044290Y572210D02*
X1042378Y574122D01*
G01X1044290Y569492D02*
Y572210D01*
G01X1044195Y529026D02*
X1044293Y528928D01*
G01X1044291Y569491D02*
X1044290Y569492D01*
G01X1044291Y561700D02*
Y569491D01*
G01X1061025Y579810D02*
X1061024Y574757D01*
G01X1061025Y542010D02*
X1061024Y536957D01*
G01X1071065Y585721D02*
X1071064Y585722D01*
G01X1071065Y579810D02*
Y585721D01*
G01Y547921D02*
X1071064Y547922D01*
G01X1071065Y542010D02*
Y547921D01*
G01X1087795Y536959D02*
X1087797Y536957D01*
G01X1087795Y542010D02*
Y536959D01*
G01X1087797Y542010D02*
X1087795D01*
G01X1044291Y599500D02*
Y607291D01*
G01X1044293Y599500D02*
X1044291D01*
G01Y609709D02*
Y607291D01*
G01X1042000Y612000D02*
X1044291Y609709D01*
G01X1042000Y622075D02*
Y612000D01*
G01X1043425Y623500D02*
X1042000Y622075D01*
G01X1046500Y623500D02*
X1043425D01*
G01X1044293Y591593D02*
Y599500D01*
G01X1042378Y589678D02*
X1044293Y591593D01*
G01X1044291Y607291D02*
X1044290Y607292D01*
G01X1071065Y617610D02*
X1071062Y612560D01*
G01X1061025Y617610D02*
X1061023Y609864D01*
G01X1131910Y210346D02*
X1129660D01*
G01X1133040Y212296D02*
X1135290D01*
G01X1154439Y276646D02*
X1154440Y276647D01*
G01X1152190Y276646D02*
X1154439D01*
G01X1138670Y272747D02*
X1140920D01*
G01X1095700Y268790D02*
X1095490Y269000D01*
G01X1145430Y257147D02*
X1147680D01*
G01X1145430Y249347D02*
X1147680D01*
G01X1148810Y251296D02*
X1151060D01*
G01X1148810Y255196D02*
X1151060D01*
G01X1152190Y272747D02*
X1154440D01*
G01X1145430D02*
X1147680D01*
G01X1133040Y239596D02*
X1135290D01*
G01X1155570Y243496D02*
X1157820D01*
G01X1138670Y261047D02*
X1136420D01*
G01X1145430Y253247D02*
X1147680D01*
G01X1140919Y276646D02*
X1140920Y276647D01*
G01X1138670Y276646D02*
X1140919D01*
G01X1107607Y277317D02*
X1108125Y276799D01*
G01X1105175Y277317D02*
X1107607D01*
G01X1148810Y278596D02*
X1151060D01*
G01X1152190Y268847D02*
X1154440D01*
G01X1133040Y262996D02*
X1135290D01*
G01X1097411Y267611D02*
X1095700Y265900D01*
G01X1097411Y270851D02*
Y267611D01*
G01X1096290Y271972D02*
X1097411Y270851D01*
G01X1155570Y274696D02*
X1157820D01*
G01X1147679Y276646D02*
X1147680Y276647D01*
G01X1145430Y276646D02*
X1147679D01*
G01X1142050Y274696D02*
X1144300D01*
G01X1112700Y299000D02*
X1113900Y297800D01*
G01X1110500Y299000D02*
X1112700D01*
G01X1152190Y284447D02*
X1154440D01*
G01X1145430Y288347D02*
X1147680D01*
G01X1135290Y313696D02*
X1137540D01*
G01X1147680Y280547D02*
X1145430D01*
G01X1138670D02*
X1140920D01*
G01X1130780Y317596D02*
X1128530D01*
G01X1138670Y288347D02*
X1140920D01*
G01X1152190Y292247D02*
X1154440D01*
G01X1111674Y286826D02*
X1116999D01*
G01X1110500Y288000D02*
X1111674Y286826D01*
G01X1130780Y333196D02*
X1128530D01*
G01X1112748Y289252D02*
X1110500Y291500D01*
G01X1115230Y289252D02*
X1112748D01*
G01X1152190Y280547D02*
X1154440D01*
G01X1107840Y325100D02*
X1109200D01*
G01X1106340Y323600D02*
X1107840Y325100D01*
G01X1106340Y322680D02*
Y323600D01*
G01X1155570Y286396D02*
X1157820D01*
G01X1154440Y288347D02*
X1152190D01*
G01X1145430Y292247D02*
X1147680D01*
G01X1138670Y315647D02*
X1140920D01*
G01X1142050Y282496D02*
X1144300D01*
G01X1130780Y321496D02*
X1128530D01*
G01X1111600Y302500D02*
X1110500D01*
G01X1116096Y298004D02*
X1111600Y302500D01*
G01X1116096Y295809D02*
Y298004D01*
G01X1142050Y290296D02*
X1144300D01*
G01X1135290Y286396D02*
X1137540D01*
G01X1112800Y322700D02*
X1113500Y323400D01*
G01X1109840Y322680D02*
X1112800Y322700D01*
G01X1113132Y292368D02*
Y291702D01*
G01X1110500Y295000D02*
X1113132Y292368D01*
G01X1130780Y325396D02*
X1128530D01*
G01X1131910Y331247D02*
X1134160D01*
G01X1148810Y286396D02*
X1151060D01*
G01X1135290Y301996D02*
X1137540D01*
G01X1138670Y284447D02*
X1140920D01*
G01X1145430D02*
X1147680D01*
G01X1131910Y319547D02*
X1134160D01*
G01X1142050Y298096D02*
X1144300D01*
G01X1112873Y282127D02*
X1110500Y284500D01*
G01X1113915Y282127D02*
X1112873D01*
G01X1114340Y281702D02*
X1113915Y282127D01*
G01X1114340Y280560D02*
Y281702D01*
G01X1155570Y282496D02*
X1157820D01*
G01X1148810Y337096D02*
X1151060D01*
G01X1155570Y376096D02*
X1157820D01*
G01X1108251Y344896D02*
X1110501D01*
G01X1151059Y372197D02*
X1151060Y372196D01*
G01X1148810Y372197D02*
X1151059D01*
G01X1148810Y376096D02*
X1151060D01*
G01X1142050Y387796D02*
X1144300D01*
G01X1120641Y342947D02*
X1118391D01*
G01X1145430Y370247D02*
X1147680D01*
G01X1145430Y381947D02*
X1147680D01*
G01X1155570Y364396D02*
X1157820D01*
G01X1147680Y374146D02*
X1145430D01*
G01X1138670Y342947D02*
X1140920D01*
G01X1156699Y403096D02*
Y401447D01*
G01X1142050Y383896D02*
X1144300D01*
G01X1155570Y372197D02*
X1157819D01*
G01X1135290Y356596D02*
X1137540D01*
G01X1142050Y379996D02*
X1144300D01*
G01X1157820Y368296D02*
X1155570D01*
G01X1154440Y374146D02*
X1152190D01*
G01X1138670Y354647D02*
X1140920D01*
G01X1154439Y370247D02*
X1154440Y370246D01*
G01X1152190Y370247D02*
X1154439D01*
G01X1145430Y378047D02*
X1147680D01*
G01X1155570Y383896D02*
X1157820D01*
G01X1158950Y405347D02*
X1156699Y403096D01*
G01X1217275Y129685D02*
X1218674Y131084D01*
G01X1217275Y127924D02*
Y129685D01*
G01Y120700D02*
Y127924D01*
G01X1218921Y119054D02*
X1217275Y120700D01*
G01X1202100Y203707D02*
X1202889Y204496D01*
G01X1202100Y202900D02*
Y203707D01*
G01X1203600Y201400D02*
X1202100Y202900D01*
G01X1210300Y201400D02*
X1203600D01*
G01X1211350Y200350D02*
X1210300Y201400D01*
G01X1212850Y200350D02*
X1211350D01*
G01X1213350Y200850D02*
X1212850Y200350D01*
G01X1214250Y200850D02*
X1213350D01*
G01X1214750Y200350D02*
X1214250Y200850D01*
G01X1215650Y200350D02*
X1214750D01*
G01X1216150Y200850D02*
X1215650Y200350D01*
G01X1217050Y200850D02*
X1216150D01*
G01X1217550Y200350D02*
X1217050Y200850D01*
G01X1222506Y200350D02*
X1217550D01*
G01X1190163Y203702D02*
X1189369Y204496D01*
G01X1190163Y200945D02*
Y203702D01*
G01X1192408Y198700D02*
X1190163Y200945D01*
G01X1199436Y198700D02*
X1192408D01*
G01X1204766Y193370D02*
X1199436Y198700D01*
G01X1209130Y193370D02*
X1204766D01*
G01X1210000Y192500D02*
X1209130Y193370D01*
G01X1207109Y211948D02*
X1202889Y212296D01*
G01X1225240Y211948D02*
X1207109D01*
G01X1192749Y203189D02*
Y202547D01*
G01X1192329Y203609D02*
X1192749Y203189D01*
G01X1191621Y203609D02*
X1192329D01*
G01X1191113Y203101D02*
X1191621Y203609D01*
G01X1191113Y201339D02*
Y203101D01*
G01X1192802Y199650D02*
X1191113Y201339D01*
G01X1199830Y199650D02*
X1192802D01*
G01X1202680Y196800D02*
X1199830Y199650D01*
G01X1203388Y196800D02*
X1202680D01*
G01X1204000Y196188D02*
X1203388Y196800D01*
G01X1204000Y195480D02*
Y196188D01*
G01X1205160Y194320D02*
X1204000Y195480D01*
G01X1208120Y194320D02*
X1205160D01*
G01X1209100Y195300D02*
X1208120Y194320D01*
G01X1210070Y195300D02*
X1209100D01*
G01X1210956Y199400D02*
X1222900D01*
G01X1209906Y200450D02*
X1210956Y199400D01*
G01X1203206Y200450D02*
X1209906D01*
G01X1201109Y202547D02*
X1203206Y200450D01*
G01X1199509Y202547D02*
X1201109D01*
G01X1199509Y209890D02*
Y210346D01*
G01X1200499Y208900D02*
X1199509Y209890D01*
G01X1201188Y208900D02*
X1200499D01*
G01X1202362Y210074D02*
X1201188Y208900D01*
G01X1203626Y210074D02*
X1202362D01*
G01X1205300Y208400D02*
X1203626Y210074D01*
G01X1206772Y208400D02*
X1205300D01*
G01X1208000Y207172D02*
X1206772Y208400D01*
G01X1208000Y206050D02*
Y207172D01*
G01X1208500Y205550D02*
X1208000Y206050D01*
G01X1209650Y205550D02*
X1208500D01*
G01X1210150Y206050D02*
X1209650Y205550D01*
G01X1211050Y206050D02*
X1210150D01*
G01X1211550Y205550D02*
X1211050Y206050D01*
G01X1216606Y205550D02*
X1211550D01*
G01X1218256Y207200D02*
X1216606Y205550D01*
G01X1219600Y207200D02*
X1218256D01*
G01X1207513Y213003D02*
X1206269Y214247D01*
G01X1226785Y213003D02*
X1207513D01*
G01X1217000Y204600D02*
X1218650Y206250D01*
G01X1205100Y204600D02*
X1217000D01*
G01X1203900Y205800D02*
X1205100Y204600D01*
G01X1203327Y206081D02*
X1203900Y205800D01*
G01X1200331Y207776D02*
X1203327Y206081D01*
G01X1199565Y208165D02*
X1200331Y207776D01*
G01X1196129Y208397D02*
X1199565Y208165D01*
G01X1162330Y274696D02*
X1164580D01*
G01X1158950Y276646D02*
X1161200D01*
G01X1175849Y266896D02*
X1178099D01*
G01X1167960Y276646D02*
X1165710D01*
G01X1172469Y241547D02*
X1174719D01*
G01X1172469Y264947D02*
X1174719D01*
G01X1175849Y251296D02*
X1178099D01*
G01X1169089Y270796D02*
X1171339D01*
G01X1179229Y253247D02*
X1181479D01*
G01X1169089Y278596D02*
X1171339D01*
G01X1175849Y262996D02*
X1178099D01*
G01X1162330Y255196D02*
X1164580D01*
G01X1169089Y262996D02*
X1171339D01*
G01X1158950Y268847D02*
X1161200D01*
G01X1175849Y239596D02*
X1178099D01*
G01X1165710Y264947D02*
X1162300D01*
G01X1172469Y276646D02*
X1174719D01*
G01X1167960Y257147D02*
X1165710D01*
G01X1158950Y272747D02*
X1161200D01*
G01X1167960Y335147D02*
X1165710D01*
G01X1169089Y340996D02*
X1171339D01*
G01X1162330Y282496D02*
X1164580D01*
G01X1169089D02*
X1171339D01*
G01X1158950Y280547D02*
X1161200D01*
G01X1169089Y329296D02*
X1171339D01*
G01X1172469Y331247D02*
X1174719D01*
G01X1179229Y323446D02*
X1181479D01*
G01X1172469Y327347D02*
X1174719D01*
G01X1169089Y337096D02*
X1171339D01*
G01X1169089Y333196D02*
X1171339D01*
G01X1196129Y321496D02*
X1198379D01*
G01X1175849D02*
X1178099D01*
G01X1172469Y319547D02*
X1174719D01*
G01X1175849Y333196D02*
X1178099D01*
G01X1175849Y329296D02*
X1178099D01*
G01X1167960Y284447D02*
X1165710D01*
G01X1194999Y323446D02*
X1192749D01*
G01X1179229Y331247D02*
X1181479D01*
G01X1172469Y323446D02*
X1174719D01*
G01X1181479Y315647D02*
X1179229D01*
G01X1167960Y280547D02*
X1165710D01*
G01X1175849Y325396D02*
X1178099D01*
G01X1162330Y368296D02*
X1164580D01*
G01X1162330Y360496D02*
X1164580D01*
G01X1169089Y352696D02*
X1171339D01*
G01X1167960Y346847D02*
X1165710D01*
G01X1158950Y401447D02*
X1161201D01*
G01X1167960Y354647D02*
X1165710D01*
G01X1196129Y348796D02*
X1198379D01*
G01X1157819Y372197D02*
X1157820Y372196D01*
G01X1194999Y350747D02*
X1192749D01*
G01X1158950Y358547D02*
X1161200D01*
G01X1164580Y376096D02*
X1162330D01*
G01X1158950Y354647D02*
X1161200D01*
G01X1167960Y350747D02*
X1165710D01*
G01X1158950Y366347D02*
X1161200D01*
G01X1162330Y364396D02*
X1164580D01*
G01X1158950Y362447D02*
X1161200D01*
G01X1195602Y408200D02*
X1197100D01*
G01X1192749Y405347D02*
X1195602Y408200D01*
G01X1196129Y403543D02*
Y403396D01*
G01X1197997Y405411D02*
X1196129Y403543D01*
G01X1198029Y405411D02*
X1197997D01*
G01X1255118Y3233D02*
Y-1743D01*
G01X1255120Y3233D02*
X1255118D01*
G01X1265159Y22923D02*
X1265157Y27899D01*
G01X1255118Y22923D02*
Y27899D01*
G01X1255120Y22923D02*
X1255118D01*
G01Y-14877D02*
Y-9901D01*
G01X1255120Y-14877D02*
X1255118D01*
G01X1265157Y-10240D02*
Y-9901D01*
G01X1265159Y-14877D02*
X1265157Y-10240D01*
G01X1255118Y78833D02*
Y73857D01*
G01X1255120Y78833D02*
X1255118D01*
G01Y41033D02*
Y36057D01*
G01X1255120Y41033D02*
X1255118D01*
G01Y60723D02*
Y65699D01*
G01X1255120Y60723D02*
X1255118D01*
G01X1265159D02*
X1265157Y65699D01*
G01X1271490Y104700D02*
Y109670D01*
G01X1267100Y138895D02*
Y138000D01*
G01X1268236Y140031D02*
X1267100Y138895D01*
G01X1268236Y141938D02*
Y140031D01*
G01X1278000Y133202D02*
Y134500D01*
G01X1277547Y132749D02*
X1278000Y133202D01*
G01X1264542Y132749D02*
X1277547D01*
G01X1263798Y133493D02*
X1264542Y132749D01*
G01X1252437Y131520D02*
Y140192D01*
G01X1249714Y128797D02*
X1252437Y131520D01*
G01X1247663Y128797D02*
X1249714D01*
G01X1243944Y125078D02*
X1247663Y128797D01*
G01X1234155Y125078D02*
X1243944D01*
G01X1230906Y121829D02*
X1234155Y125078D01*
G01X1230906Y119155D02*
Y121829D01*
G01X1268930Y105030D02*
X1268600Y104700D01*
G01X1268930Y109670D02*
Y105030D01*
G01X1228874Y140219D02*
X1225775D01*
G01X1228906Y140251D02*
X1228874Y140219D01*
G01X1245603Y133817D02*
X1248616D01*
G01X1242993Y136427D02*
X1245603Y133817D01*
G01X1242633Y136427D02*
X1242993D01*
G01X1237797Y141263D02*
X1242633Y136427D01*
G01X1237797Y143067D02*
Y141263D01*
G01X1233723Y147141D02*
X1237797Y143067D01*
G01X1231543Y147141D02*
X1233723D01*
G01X1228906Y144504D02*
X1231543Y147141D01*
G01X1228906Y140251D02*
Y144504D01*
G01X1264510Y109670D02*
X1266370D01*
G01X1263676Y108836D02*
X1264510Y109670D01*
G01X1261734Y108836D02*
X1263676D01*
G01X1262040Y135180D02*
X1260737Y133877D01*
G01X1264772Y135180D02*
X1262040D01*
G01X1265452Y134500D02*
X1264772Y135180D01*
G01X1267100Y134500D02*
X1265452D01*
G01X1225775Y133633D02*
Y136719D01*
G01X1223226Y131084D02*
X1225775Y133633D01*
G01X1218674Y131084D02*
X1223226D01*
G01X1268930Y122530D02*
X1268900Y122500D01*
G01X1268930Y127670D02*
Y122530D01*
G01X1263540Y120492D02*
X1260087Y123945D01*
G01X1266892Y120492D02*
X1263540D01*
G01X1268900Y122500D02*
X1266892Y120492D01*
G01X1270600Y140751D02*
Y138000D01*
G01X1269958Y141393D02*
X1270600Y140751D01*
G01X1269958Y143195D02*
Y141393D01*
G01X1269414Y143739D02*
X1269958Y143195D01*
G01X1265810Y143739D02*
X1269414D01*
G01X1263595Y141524D02*
X1265810Y143739D01*
G01X1263577Y141524D02*
X1263595D01*
G01X1261551Y139498D02*
X1263577Y141524D01*
G01X1256016Y139498D02*
X1261551D01*
G01X1253628Y141886D02*
X1256016Y139498D01*
G01X1251338Y141886D02*
X1253628D01*
G01X1250470Y141018D02*
X1251338Y141886D01*
G01X1250470Y137547D02*
Y141018D01*
G01X1270600Y134500D02*
Y138000D01*
G01X1245014Y132677D02*
X1241963D01*
G01X1245547Y132144D02*
X1245014Y132677D01*
G01X1249469Y132144D02*
X1245547D01*
G01X1251531Y134206D02*
X1249469Y132144D01*
G01X1251531Y136486D02*
Y134206D01*
G01X1250470Y137547D02*
X1251531Y136486D01*
G01X1241963Y131463D02*
X1240000Y129500D01*
G01X1241963Y132677D02*
Y131463D01*
G01X1278000Y141000D02*
Y145780D01*
G01X1271490Y122610D02*
Y127670D01*
G01X1271500Y122600D02*
X1271490Y122610D01*
G01X1271500Y122500D02*
Y122600D01*
G01X1221025Y141634D02*
Y136424D01*
G01X1230265Y150874D02*
X1221025Y141634D01*
G01X1234947Y150874D02*
X1230265D01*
G01X1237398Y148423D02*
X1234947Y150874D01*
G01X1237704Y148423D02*
X1237398D01*
G01X1255687Y141843D02*
X1257854D01*
G01X1254219Y143311D02*
X1255687Y141843D01*
G01X1249429Y143311D02*
X1254219D01*
G01X1244317Y148423D02*
X1249429Y143311D01*
G01X1237704Y148423D02*
X1244317D01*
G01X1274500Y142718D02*
Y141000D01*
G01X1271996Y145222D02*
X1274500Y142718D01*
G01X1265277Y145222D02*
X1271996D01*
G01X1263004Y142949D02*
X1265277Y145222D01*
G01X1262986Y142949D02*
X1263004D01*
G01X1261880Y141843D02*
X1262986Y142949D01*
G01X1257854Y141843D02*
X1261880D01*
G01X1274500Y138000D02*
Y134500D01*
G01Y141000D02*
Y138000D01*
G01X1233463Y143857D02*
Y136427D01*
G01X1232790Y144530D02*
X1233463Y143857D01*
G01X1230358Y136751D02*
X1228906D01*
G01X1230682Y136427D02*
X1230358Y136751D01*
G01X1233463Y136427D02*
X1230682D01*
G01X1223606Y201450D02*
X1222506Y200350D01*
G01X1224650Y201450D02*
X1223606D01*
G01X1225600Y202400D02*
X1224650Y201450D01*
G01X1226500Y202400D02*
X1225600D01*
G01X1226785Y210403D02*
X1225240Y211948D01*
G01X1225600Y199800D02*
X1226500D01*
G01X1224900Y200500D02*
X1225600Y199800D01*
G01X1224000Y200500D02*
X1224900D01*
G01X1222900Y199400D02*
X1224000Y200500D01*
G01X1220400Y208000D02*
X1219600Y207200D01*
G01X1221300Y208000D02*
X1220400D01*
G01Y205400D02*
X1221300D01*
G01X1219550Y206250D02*
X1220400Y205400D01*
G01X1218650Y206250D02*
X1219550D01*
G01X1271300Y511500D02*
Y510600D01*
G01X1272060Y512260D02*
X1271300Y511500D01*
G01X1272060Y513590D02*
Y512260D01*
G01X1269640Y508940D02*
X1268805D01*
G01X1271300Y510600D02*
X1269640Y508940D01*
G01X1255120Y523900D02*
Y518000D01*
G01X1275540Y511199D02*
Y513490D01*
G01X1274576Y510235D02*
X1275540Y511199D01*
G01X1273687Y509346D02*
X1274576Y510235D01*
G01X1273687Y507491D02*
Y509346D01*
G01X1269931Y499694D02*
X1267584D01*
G01X1271168Y500931D02*
X1269931Y499694D01*
G01X1272443Y500931D02*
X1271168D01*
G01X1273687Y502175D02*
X1272443Y500931D01*
G01X1273687Y503991D02*
Y502175D01*
G01X1265159Y523900D02*
X1265157Y528876D01*
G01X1269209Y505036D02*
X1268805Y505440D01*
G01X1269209Y501777D02*
Y505036D01*
G01X1277833Y507538D02*
X1276704D01*
G01X1283474Y501897D02*
X1277833Y507538D01*
G01X1276704Y502694D02*
Y504038D01*
G01X1273316Y499306D02*
X1276704Y502694D01*
G01X1271895Y499306D02*
X1273316D01*
G01X1271105Y498516D02*
X1271895Y499306D01*
G01X1265159Y561700D02*
X1265157Y566676D01*
G01X1255120Y561700D02*
Y555144D01*
G01Y542010D02*
Y537034D01*
G01Y579810D02*
Y574834D01*
G01X1265159Y599500D02*
X1265157Y604476D01*
G01X1255120Y599500D02*
Y593600D01*
G01Y612634D02*
Y617610D01*
G01X1327500Y64000D02*
X1330500Y61000D01*
G01X1327500Y65300D02*
Y64000D01*
G01X1337400Y72500D02*
Y72000D01*
G01X1335400Y74500D02*
X1337400Y72500D01*
G01X1334000Y74500D02*
X1335400D01*
G01X1338300Y72000D02*
X1337400D01*
G01X1345863Y64437D02*
X1338300Y72000D01*
G01X1340000Y78062D02*
Y83500D01*
G01X1343474Y74588D02*
X1340000Y78062D01*
G01X1341400Y83500D02*
X1340000D01*
G01X1342800Y84900D02*
X1341400Y83500D01*
G01X1317384Y84516D02*
X1317300Y84600D01*
G01X1317384Y81896D02*
Y84516D01*
G01X1336300Y61000D02*
X1334000D01*
G01X1336900Y61600D02*
X1336300Y61000D01*
G01X1340362Y58138D02*
X1336900Y61600D01*
G01X1347350Y58138D02*
X1340362D01*
G01X1340500Y74100D02*
X1341200Y73400D01*
G01X1340500Y75400D02*
Y74100D01*
G01X1337787Y78113D02*
X1340500Y75400D01*
G01X1336161Y78113D02*
X1337787D01*
G01X1335848Y77800D02*
X1336161Y78113D01*
G01X1334000Y77800D02*
X1335848D01*
G01X1334000D02*
Y80800D01*
G01X1341437Y73163D02*
X1341200Y73400D01*
G01X1344737Y73163D02*
X1341437D01*
G01X1338801Y66800D02*
X1338160D01*
G01X1344314Y61287D02*
X1338801Y66800D01*
G01X1336260Y68000D02*
X1334000D01*
G01X1337460Y66800D02*
X1336260Y68000D01*
G01X1338160Y66800D02*
X1337460D01*
G01X1336200Y58000D02*
X1334000D01*
G01X1337637Y56563D02*
X1336200Y58000D01*
G01X1347350Y56563D02*
X1337637D01*
G01X1330500Y83300D02*
X1330300Y83500D01*
G01X1330500Y80800D02*
Y83300D01*
G01X1334700Y71500D02*
X1334000D01*
G01X1335912Y70288D02*
X1334700Y71500D01*
G01X1338845Y70288D02*
X1335912D01*
G01X1341707Y67426D02*
X1338845Y70288D01*
G01X1341707Y66193D02*
Y67426D01*
G01X1345038Y62862D02*
X1341707Y66193D01*
G01X1330500Y65000D02*
X1327500Y68000D01*
G01X1330500Y64500D02*
Y65000D01*
G01X1342711Y59713D02*
X1341352Y61072D01*
G01X1337924Y64500D02*
X1334000D01*
G01X1341352Y61072D02*
X1337924Y64500D01*
G01X1330500Y68500D02*
Y68000D01*
G01X1328214Y70786D02*
X1330500Y68500D01*
G01X1327467Y70786D02*
X1328214D01*
G01X1327168Y58832D02*
Y61483D01*
G01X1328000Y58000D02*
X1327168Y58832D01*
G01X1330500Y58000D02*
X1328000D01*
G01X1330500Y74500D02*
Y71500D01*
G01X1329500Y74500D02*
X1326600Y77400D01*
G01X1330500Y74500D02*
X1329500D01*
G01X1326600Y73900D02*
Y77400D01*
G01X1325700Y73000D02*
X1326600Y73900D01*
G01X1325700Y62951D02*
Y73000D01*
G01X1327168Y61483D02*
X1325700Y62951D01*
G01X1339500Y94464D02*
Y93500D01*
G01X1341525Y96489D02*
X1339500Y94464D01*
G01X1322199Y79600D02*
X1308400D01*
G01X1324700Y82101D02*
X1322199Y79600D01*
G01X1324700Y84263D02*
Y82101D01*
G01X1330606Y90169D02*
X1324700Y84263D01*
G01X1334112Y90169D02*
X1330606D01*
G01X1337443Y93500D02*
X1334112Y90169D01*
G01X1339500Y93500D02*
X1337443D01*
G01X1339500D02*
X1343500D01*
G01X1341757Y96489D02*
X1341525D01*
G01X1340264Y274213D02*
X1334730Y279747D01*
G01X1347710Y274213D02*
X1340264D01*
G01X1339199Y281166D02*
X1341009Y279356D01*
G01X1345227Y275138D02*
X1341009Y279356D01*
G01X1322430Y286427D02*
X1314792D01*
G01X1331466Y295463D02*
X1322430Y286427D01*
G01X1338577Y295463D02*
X1331466D01*
G01X1342300Y291740D02*
X1338577Y295463D01*
G01X1315372Y284744D02*
X1314490Y283862D01*
G01X1323432Y284744D02*
X1315372D01*
G01X1333326Y294638D02*
X1323432Y284744D01*
G01X1338235Y294638D02*
X1333326D01*
G01X1339826Y293047D02*
X1338235Y294638D01*
G01X1339826Y287333D02*
Y293047D01*
G01X1349292Y277867D02*
X1339826Y287333D01*
G01X1334730Y281202D02*
Y279747D01*
G01X1332312Y283620D02*
X1334730Y281202D01*
G01X1332312Y289962D02*
Y283620D01*
G01X1334400Y292050D02*
X1332312Y289962D01*
G01X1338901Y286949D02*
X1349331Y276519D01*
G01X1338901Y292663D02*
Y286949D01*
G01X1337851Y293713D02*
X1338901Y292663D01*
G01X1333710Y293713D02*
X1337851D01*
G01X1330039Y290042D02*
X1333710Y293713D01*
G01X1330039Y279618D02*
Y290042D01*
G01X1328512Y297388D02*
X1315350Y310550D01*
G01X1339375Y297388D02*
X1328512D01*
G01X1349231Y287532D02*
X1339375Y297388D01*
G01X1311461Y314439D02*
X1315350Y310550D01*
G01X1302203Y314439D02*
X1311461D01*
G01X1336782Y281166D02*
X1339199D01*
G01X1333737Y284211D02*
X1336782Y281166D01*
G01X1333737Y288549D02*
Y284211D01*
G01X1337200Y292012D02*
X1333737Y288549D01*
G01X1304919Y296942D02*
X1302768D01*
G01X1305751Y296110D02*
X1304919Y296942D01*
G01X1307980Y296110D02*
X1305751D01*
G01X1311053Y293037D02*
X1307980Y296110D01*
G01X1323936Y293037D02*
X1311053D01*
G01X1327187Y296288D02*
X1323936Y293037D01*
G01X1338919Y296288D02*
X1327187D01*
G01X1347500Y287707D02*
X1338919Y296288D01*
G01X1337963Y282337D02*
X1335400Y284900D01*
G01X1342204Y282337D02*
X1337963D01*
G01X1342525Y434925D02*
X1340100Y432500D01*
G01X1298514Y434925D02*
X1300438Y433001D01*
G01X1297618Y434925D02*
X1298514D01*
G01X1338508Y511196D02*
Y510187D01*
G01X1341504Y514192D02*
X1338508Y511196D01*
G01X1343350Y514192D02*
X1341504D01*
G01X1287770Y501897D02*
X1283474D01*
G01X1335100Y505200D02*
Y507700D01*
G01X1335008Y507792D02*
Y510187D01*
G01X1335100Y507700D02*
X1335008Y507792D01*
G01X1283215Y581615D02*
X1282600Y581000D01*
G01X1283786Y581615D02*
X1283215D01*
G01X1284576Y580825D02*
X1283786Y581615D01*
G01X1289845Y580825D02*
X1284576D01*
G01X1293287Y583176D02*
X1289845Y580825D01*
G01X1296092Y585981D02*
X1293287Y583176D01*
G01X1296092Y611540D02*
Y585981D01*
G01X1283660Y582540D02*
X1282600Y583600D01*
G01X1284170Y582540D02*
X1283660D01*
G01X1284960Y581750D02*
X1284170Y582540D01*
G01X1289559Y581750D02*
X1284960D01*
G01X1292693Y583892D02*
X1289559Y581750D01*
G01X1295167Y586366D02*
X1292693Y583892D01*
G01X1295167Y611924D02*
Y586366D01*
G01X1299894Y615342D02*
X1296092Y611540D01*
G01X1306051Y615342D02*
X1299894D01*
G01X1307521Y616812D02*
X1306051Y615342D01*
G01X1311787Y616812D02*
X1307521D01*
G01X1314476Y619501D02*
X1311787Y616812D01*
G01X1295200Y611957D02*
X1295167Y611924D01*
G01X1295200Y612098D02*
Y611957D01*
G01X1299469Y616367D02*
X1295200Y612098D01*
G01X1305767Y616367D02*
X1299469D01*
G01X1307137Y617737D02*
X1305767Y616367D01*
G01X1311262Y617737D02*
X1307137D01*
G01X1312150Y618625D02*
X1311262Y617737D01*
G01X1312150Y619227D02*
Y618625D01*
G01X1311876Y619501D02*
X1312150Y619227D01*
G01X1385818Y2168D02*
X1387497Y489D01*
G01X1382926Y2168D02*
X1385818D01*
G01X1382050Y1292D02*
X1382926Y2168D01*
G01X1380038Y1292D02*
X1382050D01*
G01X1376220Y-2526D02*
X1380038Y1292D01*
G01X1375048Y-2526D02*
X1376220D01*
G01X1377148Y29498D02*
X1382100Y34450D01*
G01X1375359Y29498D02*
X1377148D01*
G01X1347350Y64437D02*
X1345863D01*
G01X1371591Y87109D02*
Y88967D01*
G01X1372300Y86400D02*
X1371591Y87109D01*
G01X1347612Y74588D02*
X1343474D01*
G01X1349913Y72287D02*
X1347612Y74588D01*
G01X1349913Y70150D02*
Y72287D01*
G01X1345561Y84900D02*
X1342800D01*
G01X1347400D02*
X1345561D01*
G01X1348280Y85780D02*
X1347400Y84900D01*
G01X1349540Y85780D02*
X1348280D01*
G01X1345800Y72100D02*
X1344737Y73163D01*
G01X1345800Y68306D02*
Y72100D01*
G01X1346519Y67587D02*
X1345800Y68306D01*
G01X1347350Y67587D02*
X1346519D01*
G01X1347350Y61287D02*
X1344314D01*
G01X1356213Y74713D02*
Y70150D01*
G01X1358410Y76910D02*
X1356213Y74713D01*
G01X1358410Y81910D02*
Y76910D01*
G01X1359500Y83000D02*
X1358410Y81910D01*
G01X1362395Y83000D02*
X1359500D01*
G01X1362690Y82705D02*
X1362395Y83000D01*
G01X1347350Y62862D02*
X1345038D01*
G01X1356220Y79420D02*
Y78330D01*
G01X1357100Y80300D02*
X1356220Y79420D01*
G01X1357100Y81400D02*
Y80300D01*
G01X1355500Y83000D02*
X1357100Y81400D01*
G01X1354638Y74638D02*
Y70150D01*
G01X1356220Y76220D02*
X1354638Y74638D01*
G01X1356220Y78330D02*
Y76220D01*
G01X1347350Y59713D02*
X1342711D01*
G01X1347500Y77000D02*
X1351500D01*
G01X1344000D02*
X1347500D01*
G01X1351488Y76988D02*
Y74000D01*
G01X1351500Y77000D02*
X1351488Y76988D01*
G01Y74000D02*
Y70150D01*
G01X1356140Y85780D02*
X1357000Y86640D01*
G01X1353040Y85780D02*
X1356140D01*
G01X1347500Y80500D02*
Y83000D01*
G01X1387800Y47800D02*
X1383500Y52100D01*
G01X1387800Y43900D02*
Y47800D01*
G01Y42550D02*
Y43900D01*
G01X1382100Y36850D02*
X1387800Y42550D01*
G01X1382100Y34450D02*
Y36850D01*
G01X1364700Y92450D02*
X1368591D01*
G01X1364700D02*
Y96440D01*
G01X1371574Y92450D02*
X1371591Y92467D01*
G01X1368591Y92450D02*
X1371574D01*
G01X1345257Y96489D02*
Y100000D01*
G01Y102257D02*
Y100000D01*
G01X1346592Y103592D02*
X1345257Y102257D01*
G01X1348550Y103592D02*
X1346592D01*
G01X1364700Y97450D02*
Y96440D01*
G01X1362653Y99497D02*
X1364700Y97450D01*
G01X1362653Y101300D02*
Y99497D01*
G01X1402500Y276550D02*
X1404947D01*
G01X1348739Y279587D02*
X1342300Y286026D01*
G01X1375086Y282585D02*
X1372088Y279587D01*
G01X1399138Y276550D02*
X1393103Y282585D01*
G01X1402500Y276550D02*
X1399138D01*
G01X1397944Y278911D02*
X1406141D01*
G01X1390368Y286487D02*
X1397944Y278911D01*
G01X1400160Y274361D02*
X1393021Y281500D01*
G01X1406575Y274361D02*
X1400160D01*
G01X1374016Y277867D02*
X1349292D01*
G01X1376393Y280244D02*
X1374016Y277867D01*
G01X1353016Y268907D02*
X1347710Y274213D01*
G01X1377164Y268907D02*
X1353016D01*
G01X1378659Y270402D02*
X1377164Y268907D01*
G01X1408280Y270402D02*
X1378659D01*
G01X1399776Y273436D02*
X1406959D01*
G01X1392762Y280450D02*
X1399776Y273436D01*
G01X1376488Y276519D02*
X1380419Y280450D01*
G01X1349331Y276519D02*
X1376488D01*
G01X1348094Y275138D02*
X1345227D01*
G01X1353400Y269832D02*
X1348094Y275138D01*
G01X1376676Y269832D02*
X1353400D01*
G01X1378171Y271327D02*
X1376676Y269832D01*
G01X1407896Y271327D02*
X1378171D01*
G01X1349130Y275411D02*
X1342204Y282337D01*
G01X1377650Y275411D02*
X1349130D01*
G01X1380239Y278000D02*
X1377650Y275411D01*
G01X1386750Y278000D02*
X1380239D01*
G01X1393361D02*
X1386750D01*
G01X1398850Y272511D02*
X1393361Y278000D01*
G01X1407343Y272511D02*
X1398850D01*
G01X1369785Y294975D02*
X1400500D01*
G01X1359710Y284900D02*
X1369785Y294975D01*
G01X1359000Y284900D02*
X1359710D01*
G01X1400500Y294975D02*
X1419417D01*
G01X1342300Y286026D02*
Y291740D01*
G01X1372088Y279587D02*
X1348739D01*
G01X1393103Y282585D02*
X1375086D01*
G01X1377821Y286487D02*
X1390368D01*
G01X1371746Y280412D02*
X1377821Y286487D01*
G01X1350588Y280412D02*
X1371746D01*
G01X1345700Y285300D02*
X1350588Y280412D01*
G01X1377649Y281500D02*
X1376393Y280244D01*
G01X1393021Y281500D02*
X1377649D01*
G01X1380419Y280450D02*
X1392762D01*
G01X1400429Y283085D02*
X1398926Y281582D01*
G01X1400429Y285365D02*
Y283085D01*
G01X1401376Y286312D02*
X1400429Y285365D01*
G01X1405627Y286312D02*
X1401376D01*
G01X1349231Y285817D02*
Y287532D01*
G01X1352711Y282337D02*
X1349231Y285817D01*
G01X1370948Y282337D02*
X1352711D01*
G01X1376659Y288048D02*
X1370948Y282337D01*
G01X1376659Y288092D02*
Y288048D01*
G01X1377042Y288475D02*
X1376659Y288092D01*
G01X1399334Y288475D02*
X1377042D01*
G01X1400072Y287737D02*
X1399334Y288475D01*
G01X1405036Y287737D02*
X1400072D01*
G01X1367938Y297138D02*
X1405800D01*
G01X1355800Y285000D02*
X1367938Y297138D01*
G01X1404400Y289900D02*
X1402900D01*
G01X1374100D02*
X1368200Y284000D01*
G01X1402900Y289900D02*
X1374100D01*
G01X1366720Y299320D02*
X1419164D01*
G01X1352400Y285000D02*
X1366720Y299320D01*
G01X1347500Y285499D02*
Y287707D01*
G01X1351762Y281237D02*
X1347500Y285499D01*
G01X1371404Y281237D02*
X1351762D01*
G01X1377542Y287375D02*
X1371404Y281237D01*
G01X1390647Y287375D02*
X1377542D01*
G01X1398286Y279736D02*
X1390647Y287375D01*
G01X1405799Y279736D02*
X1398286D01*
G01X1388045Y391745D02*
X1386210Y389910D01*
G01X1389700Y391745D02*
X1388045D01*
G01X1384900Y389100D02*
X1382899D01*
G01X1390100Y447200D02*
X1389900Y447400D01*
G01X1390100Y438550D02*
Y447200D01*
G01X1391300Y437350D02*
X1390100Y438550D01*
G01X1395300Y437350D02*
X1391300D01*
G01X1397985Y434665D02*
X1395300Y437350D01*
G01X1397985Y428624D02*
Y434665D01*
G01X1399284Y427325D02*
X1397985Y428624D01*
G01X1418375Y427325D02*
X1399284D01*
G01X1387618Y449682D02*
Y449925D01*
G01X1389900Y447400D02*
X1387618Y449682D01*
G01X1342600Y419100D02*
X1342500Y419000D01*
G01X1342600Y429925D02*
Y419100D01*
G01X1342618Y429925D02*
X1342600D01*
G01X1342618Y434925D02*
X1342525D01*
G01X1401863Y450584D02*
X1415874D01*
G01X1396204Y444925D02*
X1401863Y450584D01*
G01X1392618Y444925D02*
X1396204D01*
G01X1392525Y454925D02*
X1392618D01*
G01X1390100Y452500D02*
X1392525Y454925D01*
G01X1367618D02*
X1370100Y452500D01*
G01X1367675Y449925D02*
X1370100Y447500D01*
G01X1367618Y449925D02*
X1367675D01*
G01X1402287Y448992D02*
X1415450D01*
G01X1396795Y443500D02*
X1402287Y448992D01*
G01X1394249Y443500D02*
X1396795D01*
G01X1392618Y441869D02*
X1394249Y443500D01*
G01X1392618Y439925D02*
Y441869D01*
G01X1383000Y449552D02*
X1385100Y447500D01*
G01X1382618Y449925D02*
X1383000Y449552D01*
G01X1392618Y449925D02*
X1395100Y447500D01*
G01Y426999D02*
Y427500D01*
G01X1396399Y425700D02*
X1395100Y426999D01*
G01X1417701Y425700D02*
X1396399D01*
G01X1395100Y427500D02*
X1392618Y429925D01*
G01X1385043Y452500D02*
X1385100D01*
G01X1382618Y454925D02*
X1385043Y452500D01*
G01X1392488Y432500D02*
X1395100D01*
G01X1390700Y430712D02*
X1392488Y432500D01*
G01X1390700Y429100D02*
Y430712D01*
G01X1395750Y424050D02*
X1390700Y429100D01*
G01X1417052Y424050D02*
X1395750D01*
G01X1395100Y432500D02*
X1392618Y434925D01*
G01X1372618Y449925D02*
X1375100Y447500D01*
G01X1372618Y454925D02*
X1375100Y452500D01*
G01X1387618Y455018D02*
X1390100Y457500D01*
G01X1387618Y454925D02*
Y455018D01*
G01X1396792Y505879D02*
X1396871Y505800D01*
G01X1392953Y505879D02*
X1396792D01*
G01X1364575Y503973D02*
X1372600D01*
G01X1363000Y502398D02*
X1364575Y503973D01*
G01X1363000Y500500D02*
Y502398D01*
G01X1378705Y505879D02*
X1392953D01*
G01X1376799Y503973D02*
X1378705Y505879D01*
G01X1372600Y503973D02*
X1376799D01*
G01X1357453Y510147D02*
Y511900D01*
G01X1360500Y507100D02*
X1357453Y510147D01*
G01X1360500Y501500D02*
Y507100D01*
G01X1361500Y500500D02*
X1360500Y501500D01*
G01X1363000Y500500D02*
X1361500D01*
G01X1392953Y518012D02*
X1395242Y520301D01*
G01X1392953Y509379D02*
Y518012D01*
G01X1405447Y517811D02*
X1403027Y520231D01*
G01X1384264Y577143D02*
X1385486Y578365D01*
G01X1381780Y577143D02*
X1384264D01*
G01X1380991Y576354D02*
X1381780Y577143D01*
G01X1379359Y576354D02*
X1380991D01*
G01X1385486Y579500D02*
Y578365D01*
G01X1389066Y583080D02*
X1385486Y579500D01*
G01X1384750Y607950D02*
X1385800Y609000D01*
G01X1381150Y607950D02*
X1384750D01*
G01X1380754Y607554D02*
X1381150Y607950D01*
G01X1379359Y607554D02*
X1380754D01*
G01X1407422Y17283D02*
Y13139D01*
G01X1413721Y17283D02*
Y13139D01*
G01X1416871Y33849D02*
Y30669D01*
G01Y17283D02*
Y13139D01*
G01X1457300Y300D02*
X1452000Y-5000D01*
G01X1479243Y300D02*
X1457300D01*
G01X1456000Y83000D02*
X1457000Y82000D01*
G01X1456000Y84178D02*
Y83000D01*
G01X1453962Y86216D02*
X1456000Y84178D01*
G01X1451457Y86216D02*
X1453962D01*
G01X1450594Y85353D02*
X1451457Y86216D01*
G01X1446179Y85353D02*
X1450594D01*
G01X1453221Y72222D02*
Y73750D01*
G01X1451352Y70353D02*
X1453221Y72222D01*
G01X1446179Y70353D02*
X1451352D01*
G01X1450303Y80353D02*
X1453700Y83750D01*
G01X1446179Y80353D02*
X1450303D01*
G01X1451109Y75353D02*
X1446179D01*
G01X1451686Y75930D02*
X1451109Y75353D01*
G01X1454870Y75930D02*
X1451686D01*
G01X1455889Y74911D02*
X1454870Y75930D01*
G01X1455889Y73700D02*
Y74911D01*
G01X1420337Y42977D02*
Y45477D01*
G01X1453635Y90353D02*
X1446179D01*
G01X1455347Y92065D02*
X1453635Y90353D01*
G01X1416837Y42977D02*
Y45477D01*
G01X1453095Y95353D02*
X1446179D01*
G01X1453809Y94639D02*
X1453095Y95353D01*
G01X1449935Y105353D02*
X1446179D01*
G01X1452232Y107650D02*
X1449935Y105353D01*
G01X1452232Y109500D02*
Y107650D01*
G01X1450517Y143080D02*
X1451198Y143761D01*
G01X1445232Y143080D02*
X1450517D01*
G01X1449558Y148080D02*
X1451233Y146405D01*
G01X1445232Y148080D02*
X1449558D01*
G01X1448582Y168080D02*
X1445232D01*
G01X1451366Y165296D02*
X1448582Y168080D01*
G01X1449682Y175203D02*
X1451386Y173499D01*
G01X1449682Y176684D02*
Y175203D01*
G01X1448286Y178080D02*
X1449682Y176684D01*
G01X1445232Y178080D02*
X1448286D01*
G01X1441489Y248956D02*
X1471736D01*
G01X1433057Y257388D02*
X1441489Y248956D01*
G01X1451753Y267304D02*
X1453327Y268878D01*
G01X1461202Y276753D02*
X1462776Y278327D01*
G01X1438478Y273759D02*
Y280589D01*
G01X1435658Y270939D02*
X1438478Y273759D01*
G01X1424799Y270939D02*
X1435658D01*
G01X1415041Y280697D02*
X1424799Y270939D01*
G01X1404947Y276550D02*
X1409094Y280697D01*
G01X1464424Y273676D02*
X1462776Y272028D01*
G01X1458052Y276753D02*
X1459626Y278327D01*
G01X1426658Y274252D02*
Y287396D01*
G01X1437160Y273608D02*
Y281581D01*
G01X1435316Y271764D02*
X1437160Y273608D01*
G01X1425180Y271764D02*
X1435316D01*
G01X1422700Y274244D02*
X1425180Y271764D01*
G01X1422700Y277549D02*
Y274244D01*
G01X1420471Y279778D02*
X1422700Y277549D01*
G01X1406141Y278911D02*
X1408752Y281522D01*
G01X1448603Y267304D02*
X1450177Y268878D01*
G01X1410086Y277872D02*
X1406575Y274361D01*
G01X1416637Y277872D02*
X1410086D01*
G01X1424395Y270114D02*
X1416637Y277872D01*
G01X1436000Y270114D02*
X1424395D01*
G01X1439533Y273647D02*
X1436000Y270114D01*
G01X1439533Y279262D02*
Y273647D01*
G01X1443271Y283000D02*
X1439533Y279262D01*
G01X1411741Y273863D02*
X1408280Y270402D01*
G01X1414501Y273863D02*
X1411741D01*
G01X1430125Y258239D02*
X1414501Y273863D01*
G01X1430125Y253166D02*
Y258239D01*
G01X1431550Y251741D02*
X1430125Y253166D01*
G01X1431550Y245400D02*
Y251741D01*
G01X1431575Y245375D02*
X1431550Y245400D01*
G01X1431575Y245216D02*
Y245375D01*
G01X1435941Y240850D02*
X1431575Y245216D01*
G01X1438111Y240850D02*
X1435941D01*
G01X1443274Y246013D02*
X1438111Y240850D01*
G01X1463226Y246013D02*
X1443274D01*
G01X1468070Y241169D02*
X1463226Y246013D01*
G01X1454902Y270454D02*
X1456476Y272028D01*
G01X1442304Y273603D02*
X1443878Y275177D01*
G01X1451753Y270454D02*
X1453327Y272028D01*
G01X1440732Y275181D02*
X1443878Y278327D01*
G01X1440732Y273537D02*
Y275181D01*
G01X1436384Y269189D02*
X1440732Y273537D01*
G01X1423893Y269189D02*
X1436384D01*
G01X1423361Y269721D02*
X1423893Y269189D01*
G01X1416136Y276947D02*
X1423361Y269721D01*
G01X1410470Y276947D02*
X1416136D01*
G01X1406959Y273436D02*
X1410470Y276947D01*
G01X1448603Y276753D02*
X1450177Y278327D01*
G01X1445454Y267304D02*
X1447028Y268878D01*
G01X1451753Y273603D02*
X1453327Y275177D01*
G01X1456476Y265376D02*
Y268878D01*
G01X1455500Y264400D02*
X1456476Y265376D01*
G01X1450400Y264400D02*
X1455500D01*
G01X1449540Y263540D02*
X1450400Y264400D01*
G01X1449540Y260991D02*
Y263540D01*
G01X1450942Y259589D02*
X1449540Y260991D01*
G01X1450942Y255931D02*
Y259589D01*
G01X1450171Y255160D02*
X1450942Y255931D01*
G01X1448839Y255160D02*
X1450171D01*
G01X1464351Y276753D02*
X1465925Y278327D01*
G01X1411572Y275003D02*
X1407896Y271327D01*
G01X1414670Y275003D02*
X1411572D01*
G01X1431050Y258623D02*
X1414670Y275003D01*
G01X1431050Y253550D02*
Y258623D01*
G01X1432500Y252100D02*
X1431050Y253550D01*
G01X1432500Y245600D02*
Y252100D01*
G01X1436300Y241800D02*
X1432500Y245600D01*
G01X1437669Y241800D02*
X1436300D01*
G01X1443900Y248031D02*
X1437669Y241800D01*
G01X1477486Y248031D02*
X1443900D01*
G01X1458052Y273603D02*
X1459626Y275177D01*
G01X1452728Y243100D02*
Y243306D01*
G01X1456728Y239100D02*
X1452728Y243100D01*
G01X1475243Y239100D02*
X1456728D01*
G01X1459626Y268878D02*
X1458102Y270402D01*
G01X1459672Y272028D02*
X1459626D01*
G01X1461300Y270400D02*
X1459672Y272028D01*
G01X1424995Y273270D02*
Y287195D01*
G01X1425676Y272589D02*
X1424995Y273270D01*
G01X1431089Y272589D02*
X1425676D01*
G01X1433362Y274862D02*
X1431089Y272589D01*
G01X1433362Y278244D02*
Y274862D01*
G01X1458269Y240117D02*
X1475093D01*
G01X1453417Y244969D02*
X1458269Y240117D01*
G01X1452019Y244969D02*
X1453417D01*
G01X1443850Y236800D02*
X1452019Y244969D01*
G01X1441750Y236800D02*
X1443850D01*
G01X1463839Y252416D02*
X1460631D01*
G01X1464374Y251881D02*
X1463839Y252416D01*
G01X1465752Y251881D02*
X1464374D01*
G01X1464242Y270345D02*
X1465925Y272028D01*
G01X1464242Y260458D02*
Y270345D01*
G01X1467700Y257000D02*
X1464242Y260458D01*
G01X1410854Y276022D02*
X1407343Y272511D01*
G01X1414979Y276022D02*
X1410854D01*
G01X1426037Y264964D02*
X1414979Y276022D01*
G01X1437964Y264964D02*
X1426037D01*
G01X1443496Y259432D02*
X1437964Y264964D01*
G01X1443496Y254055D02*
Y259432D01*
G01X1444211Y253340D02*
X1443496Y254055D01*
G01X1446432Y253340D02*
X1444211D01*
G01X1446465Y253373D02*
X1446432Y253340D01*
G01X1447843Y253373D02*
X1446465D01*
G01X1447876Y253340D02*
X1447843Y253373D01*
G01X1448080Y253340D02*
X1447876D01*
G01X1450676Y250744D02*
X1448080Y253340D01*
G01X1471200Y250744D02*
X1450676D01*
G01X1462776Y316122D02*
Y318200D01*
G01X1424896Y337798D02*
X1413487Y349207D01*
G01X1424896Y300454D02*
Y337798D01*
G01X1419417Y294975D02*
X1424896Y300454D01*
G01X1442515Y284626D02*
X1443878D01*
G01X1438478Y280589D02*
X1442515Y284626D01*
G01X1409094Y280697D02*
X1415041D01*
G01X1445454Y279902D02*
X1447028Y281476D01*
G01X1442304Y292499D02*
X1443878Y290925D01*
G01X1430117Y289017D02*
X1432543Y291443D01*
G01X1430117Y287489D02*
Y289017D01*
G01X1440600Y293946D02*
X1443878Y297224D01*
G01X1435046Y293946D02*
X1440600D01*
G01X1432543Y291443D02*
X1435046Y293946D01*
G01X1448603Y301948D02*
X1450177Y300374D01*
G01X1447028Y294075D02*
X1448577Y295624D01*
G01X1461202Y311397D02*
X1462776Y309823D01*
G01X1459626Y294075D02*
X1458052Y295649D01*
G01X1451753Y301948D02*
X1453327Y300374D01*
G01X1448603Y289351D02*
X1450177Y290925D01*
G01X1442303Y301949D02*
X1443878Y300374D01*
G01X1441211Y301949D02*
X1442303D01*
G01X1426658Y287396D02*
X1441211Y301949D01*
G01X1461202Y279902D02*
X1462776Y281476D01*
G01X1451753Y311397D02*
X1453327Y309823D01*
G01X1458052Y314546D02*
X1459626Y312972D01*
G01X1441781Y286202D02*
X1445454D01*
G01X1437160Y281581D02*
X1441781Y286202D01*
G01X1418727Y281522D02*
X1420471Y279778D01*
G01X1408752Y281522D02*
X1418727D01*
G01X1445556Y314650D02*
X1447028Y316122D01*
G01X1442900Y314650D02*
X1445556D01*
G01X1440910Y316640D02*
X1442900Y314650D01*
G01X1440910Y316693D02*
Y316640D01*
G01X1445454Y289351D02*
X1447028Y290925D01*
G01X1445402Y283000D02*
X1443271D01*
G01X1447028Y284626D02*
X1445402Y283000D01*
G01X1442304Y289350D02*
X1443878Y287776D01*
G01X1451753Y314546D02*
X1453327Y312972D01*
G01X1458052Y308247D02*
X1459626Y306673D01*
G01X1454751Y292651D02*
X1453327Y294075D01*
G01X1405629Y281729D02*
X1404286D01*
G01X1408427Y284527D02*
X1405629Y281729D01*
G01X1415617Y284527D02*
X1408427D01*
G01X1464429Y323609D02*
X1467950Y327130D01*
G01X1457890Y320901D02*
X1464429Y323609D01*
G01X1456357Y319368D02*
X1457890Y320901D01*
G01X1448499Y319368D02*
X1456357D01*
G01X1447621Y320246D02*
X1448499Y319368D01*
G01X1447621Y320311D02*
Y320246D01*
G01X1440479Y320311D02*
X1447621D01*
G01X1431997Y311829D02*
X1440479Y320311D01*
G01X1431997Y297226D02*
Y311829D01*
G01X1431886Y297114D02*
X1431997Y297226D01*
G01X1419298Y284527D02*
X1431886Y297114D01*
G01X1415617Y284527D02*
X1419298D01*
G01X1461202Y283052D02*
X1462776Y284626D01*
G01X1451754Y283053D02*
X1453327Y284626D01*
G01X1458052Y305098D02*
X1459626Y303524D01*
G01X1463621Y324818D02*
X1467783Y328980D01*
G01X1458636Y322753D02*
X1463621Y324818D01*
G01X1457714Y321831D02*
X1458636Y322753D01*
G01X1457365Y321686D02*
X1457714Y321831D01*
G01X1457345Y321666D02*
X1457365Y321686D01*
G01X1439818Y321666D02*
X1457345D01*
G01X1430572Y312420D02*
X1439818Y321666D01*
G01X1430572Y297817D02*
Y312420D01*
G01X1419556Y286801D02*
X1430572Y297817D01*
G01X1408706Y286801D02*
X1419556D01*
G01X1406116D02*
X1405627Y286312D01*
G01X1408706Y286801D02*
X1406116D01*
G01X1458052Y298798D02*
X1459626Y297224D01*
G01X1450176Y284626D02*
X1448603Y283053D01*
G01X1450177Y284626D02*
X1450176D01*
G01X1450177Y294075D02*
X1451751Y295649D01*
G01X1443878Y294075D02*
X1445427Y295624D01*
G01X1406464Y289165D02*
X1405036Y287737D01*
G01X1419904Y289165D02*
X1406464D01*
G01X1429147Y298408D02*
X1419904Y289165D01*
G01X1429147Y313011D02*
Y298408D01*
G01X1442348Y326212D02*
X1429147Y313011D01*
G01X1445288Y326212D02*
X1442348D01*
G01X1448409Y323091D02*
X1445288Y326212D01*
G01X1456958Y323091D02*
X1448409D01*
G01X1457830Y323963D02*
X1456958Y323091D01*
G01X1458866Y324392D02*
X1457830Y323963D01*
G01X1458870Y324393D02*
X1458866Y324392D01*
G01X1461481Y325475D02*
X1458870Y324393D01*
G01X1462813Y326027D02*
X1461481Y325475D01*
G01X1469223Y332437D02*
X1462813Y326027D01*
G01X1423271Y337124D02*
X1411774Y348621D01*
G01X1423271Y301128D02*
Y337124D01*
G01X1419281Y297138D02*
X1423271Y301128D01*
G01X1405800Y297138D02*
X1419281D01*
G01X1461202Y305098D02*
X1462776Y303524D01*
G01X1405138Y290638D02*
X1404400Y289900D01*
G01X1419361Y290638D02*
X1405138D01*
G01X1427722Y298999D02*
X1419361Y290638D01*
G01X1427722Y319491D02*
Y298999D01*
G01X1436131Y327900D02*
X1427722Y319491D01*
G01X1443500Y327900D02*
X1436131D01*
G01X1461202Y314546D02*
X1462776Y312972D01*
G01X1464351Y311397D02*
X1465925Y309823D01*
G01X1454902Y301948D02*
X1456476Y300374D01*
G01X1421646Y336450D02*
X1410148Y347948D01*
G01X1421646Y301802D02*
Y336450D01*
G01X1419164Y299320D02*
X1421646Y301802D01*
G01X1458052Y279902D02*
X1459626Y281476D01*
G01X1448603Y308247D02*
X1450177Y306673D01*
G01X1458052Y289351D02*
X1459626Y290925D01*
G01X1439472Y312972D02*
X1443878D01*
G01X1435000Y308500D02*
X1439472Y312972D01*
G01X1435000Y297200D02*
Y308500D01*
G01X1424995Y287195D02*
X1435000Y297200D01*
G01X1408410Y282347D02*
X1405799Y279736D01*
G01X1418747Y282347D02*
X1408410D01*
G01X1433258Y296858D02*
X1418747Y282347D01*
G01X1433258Y311781D02*
Y296858D01*
G01X1439857Y318380D02*
X1433258Y311781D01*
G01X1443204Y318380D02*
X1439857D01*
G01X1444103Y319279D02*
X1443204Y318380D01*
G01X1447020Y319279D02*
X1444103D01*
G01X1448603Y317696D02*
X1447020Y319279D01*
G01X1426050Y365651D02*
Y418302D01*
G01X1416399Y356000D02*
X1426050Y365651D01*
G01X1414750Y356000D02*
X1416399D01*
G01X1413487Y354737D02*
X1414750Y356000D01*
G01X1413487Y349207D02*
Y354737D01*
G01X1462500Y386000D02*
X1460500D01*
G01X1463750Y387250D02*
X1462500Y386000D01*
G01X1470580Y387250D02*
X1463750D01*
G01X1455401Y385100D02*
X1453900D01*
G01X1455632Y384869D02*
X1455401Y385100D01*
G01X1456281Y384869D02*
X1455632D01*
G01X1456581Y384569D02*
X1456281Y384869D01*
G01X1456981Y384569D02*
X1456581D01*
G01X1453000Y382500D02*
Y381250D01*
G01X1453900Y383400D02*
X1453000Y382500D01*
G01X1453900Y385100D02*
Y383400D01*
G01X1450199Y382000D02*
X1446500D01*
G01X1450949Y381250D02*
X1450199Y382000D01*
G01X1453000Y381250D02*
X1450949D01*
G01X1462200Y352700D02*
X1467200Y347700D01*
G01X1462200Y353705D02*
Y352700D01*
G01X1460832Y355073D02*
X1462200Y353705D01*
G01X1460832Y357154D02*
Y355073D01*
G01X1459892Y358094D02*
X1460832Y357154D01*
G01X1456201Y358094D02*
X1459892D01*
G01X1453695Y360600D02*
X1456201Y358094D01*
G01X1440950Y360600D02*
X1453695D01*
G01X1439700Y361850D02*
X1440950Y360600D01*
G01X1439700Y370300D02*
Y361850D01*
G01X1441000Y371600D02*
X1444400D01*
G01X1439700Y370300D02*
X1441000Y371600D01*
G01X1456900Y387840D02*
Y387600D01*
G01X1454140Y390600D02*
X1456900Y387840D01*
G01X1453900Y390600D02*
X1454140D01*
G01X1453900D02*
Y394600D01*
G01X1450500Y394000D02*
X1446500D01*
G01X1451100Y394600D02*
X1450500Y394000D01*
G01X1453900Y394600D02*
X1451100D01*
G01X1465400Y357797D02*
X1466888Y356309D01*
G01X1466022Y359300D02*
X1465400Y358678D01*
G01X1459116Y356353D02*
X1459111D01*
G01X1459116Y356206D02*
Y356353D01*
G01X1458922Y356400D02*
X1459116Y356206D01*
G01X1455879Y356400D02*
X1458922D01*
G01X1453104Y359175D02*
X1455879Y356400D01*
G01X1439775Y359175D02*
X1453104D01*
G01X1435800Y363150D02*
X1439775Y359175D01*
G01X1435800Y377000D02*
Y363150D01*
G01X1436200Y377400D02*
X1435800Y377000D01*
G01X1436200Y411514D02*
Y377400D01*
G01X1463550Y365450D02*
X1458450D01*
G01X1465500Y363500D02*
X1463550Y365450D01*
G01X1463942Y359742D02*
X1465500Y361300D01*
G01X1458441Y365459D02*
X1458450Y365450D01*
G01X1453800Y365459D02*
X1458441D01*
G01X1462700Y392500D02*
X1460500D01*
G01X1464400Y390800D02*
X1462700Y392500D01*
G01X1446800Y373200D02*
X1445100Y374900D01*
G01X1446800Y368018D02*
Y373200D01*
G01X1449244Y355456D02*
X1450400Y354300D01*
G01X1437945Y355456D02*
X1449244D01*
G01X1430200Y363201D02*
X1437945Y355456D01*
G01X1430200Y402400D02*
Y363201D01*
G01X1431000Y403200D02*
X1430200Y402400D01*
G01X1463669Y393531D02*
X1467031D01*
G01X1461700Y395500D02*
X1463669Y393531D01*
G01X1461586Y382500D02*
X1464361Y385275D01*
G01X1460500Y382500D02*
X1461586D01*
G01X1446517Y353193D02*
X1447685Y352025D01*
G01X1434708Y353193D02*
X1446517D01*
G01X1427700Y360201D02*
X1434708Y353193D01*
G01X1427700Y361100D02*
Y360201D01*
G01Y421656D02*
Y361100D01*
G01X1453251Y356929D02*
Y356676D01*
G01X1452430Y357750D02*
X1453251Y356929D01*
G01X1439891Y357750D02*
X1452430D01*
G01X1433000Y364641D02*
X1439891Y357750D01*
G01X1433000Y384600D02*
Y364641D01*
G01X1433900Y385500D02*
X1433000Y384600D01*
G01X1434700Y386300D02*
X1433900Y385500D01*
G01X1434700Y410989D02*
Y386300D01*
G01X1424425Y366426D02*
Y418976D01*
G01X1415799Y357800D02*
X1424425Y366426D01*
G01X1414151Y357800D02*
X1415799D01*
G01X1411775Y355424D02*
X1414151Y357800D01*
G01X1411775Y355324D02*
Y355424D01*
G01X1411774Y355323D02*
X1411775Y355324D01*
G01X1411774Y348621D02*
Y355323D01*
G01X1458070Y373600D02*
X1457300D01*
G01X1464830Y380360D02*
X1458070Y373600D01*
G01X1469330Y380360D02*
X1464830D01*
G01X1456700Y373000D02*
X1454500D01*
G01X1457300Y373600D02*
X1456700Y373000D01*
G01X1464720Y382400D02*
X1464400Y382720D01*
G01X1474050Y382400D02*
X1464720D01*
G01X1422800Y367100D02*
Y418302D01*
G01X1415200Y359500D02*
X1422800Y367100D01*
G01X1413552Y359500D02*
X1415200D01*
G01X1410150Y356098D02*
X1413552Y359500D01*
G01X1410150Y355998D02*
Y356098D01*
G01X1410149Y355997D02*
X1410150Y355998D01*
G01X1410149Y349295D02*
Y355997D01*
G01X1410148Y349294D02*
X1410149Y349295D01*
G01X1410148Y347948D02*
Y349294D01*
G01X1455850Y362900D02*
X1453800D01*
G01X1456350Y362400D02*
X1455850Y362900D01*
G01X1456350Y361050D02*
Y362400D01*
G01X1456000Y360700D02*
X1456350Y361050D01*
G01X1428800Y363200D02*
Y422416D01*
G01X1437728Y354272D02*
X1428800Y363200D01*
G01X1447840Y354272D02*
X1437728D01*
G01X1449897Y352215D02*
X1447840Y354272D01*
G01X1451249Y352215D02*
X1449897D01*
G01X1452384Y353350D02*
X1451249Y352215D01*
G01X1453900Y353350D02*
X1452384D01*
G01X1433400Y399000D02*
Y410464D01*
G01X1432400Y398000D02*
X1433400Y399000D01*
G01X1432600Y397800D02*
X1432400Y398000D01*
G01X1432600Y391800D02*
Y397800D01*
G01X1431700Y390900D02*
X1432600Y391800D01*
G01X1431700Y363250D02*
Y390900D01*
G01X1438625Y356325D02*
X1431700Y363250D01*
G01X1451223Y356325D02*
X1438625D01*
G01X1452535Y355013D02*
X1451223Y356325D01*
G01X1455663Y355013D02*
X1452535D01*
G01X1457226Y353450D02*
X1455663Y355013D01*
G01X1459950Y353450D02*
X1457226D01*
G01X1460400Y353000D02*
X1459950Y353450D01*
G01X1426051Y419649D02*
X1418375Y427325D01*
G01X1426051Y418303D02*
Y419649D01*
G01X1426050Y418302D02*
X1426051Y418303D01*
G01X1433414Y414300D02*
X1436200Y411514D01*
G01X1433414Y426476D02*
Y414300D01*
G01X1420247Y439643D02*
X1433414Y426476D01*
G01X1420247Y446211D02*
Y439643D01*
G01X1415874Y450584D02*
X1420247Y446211D01*
G01X1459334Y427600D02*
X1455600D01*
G01X1460251Y428517D02*
X1459334Y427600D01*
G01X1454000Y426000D02*
X1455600Y427600D01*
G01X1453500Y426000D02*
X1454000D01*
G01X1452279Y424779D02*
X1453500Y426000D01*
G01X1451560Y424779D02*
X1452279D01*
G01X1442889Y423700D02*
X1439000Y427618D01*
G01X1448081Y423700D02*
X1442889D01*
G01X1449160Y424779D02*
X1448081Y423700D01*
G01X1451560Y424779D02*
X1449160D01*
G01X1431000Y406500D02*
Y403200D01*
G01Y410300D02*
Y406500D01*
G01X1430200Y411100D02*
X1431000Y410300D01*
G01X1430200Y423032D02*
Y411100D01*
G01X1412484Y440748D02*
X1430200Y423032D01*
G01X1412156Y437200D02*
X1427700Y421656D01*
G01X1409258Y437200D02*
X1412156D01*
G01X1408225Y438233D02*
X1409258Y437200D01*
G01X1432489Y413200D02*
X1434700Y410989D01*
G01X1432489Y425351D02*
Y413200D01*
G01X1418822Y439018D02*
X1432489Y425351D01*
G01X1418822Y445620D02*
Y439018D01*
G01X1415450Y448992D02*
X1418822Y445620D01*
G01X1456456Y422100D02*
X1455600D01*
G01X1461294Y426938D02*
X1456456Y422100D01*
G01X1455179Y421679D02*
X1451560D01*
G01X1455600Y422100D02*
X1455179Y421679D01*
G01X1447871Y419350D02*
X1445300D01*
G01X1450200Y421679D02*
X1447871Y419350D01*
G01X1451560Y421679D02*
X1450200D01*
G01X1424425Y418976D02*
X1417701Y425700D01*
G01X1422800Y418302D02*
X1417052Y424050D01*
G01X1410695Y438530D02*
X1408225Y441000D01*
G01X1412686Y438530D02*
X1410695D01*
G01X1428800Y422416D02*
X1412686Y438530D01*
G01X1417350Y438570D02*
X1412375Y443545D01*
G01X1417350Y438474D02*
Y438570D01*
G01X1431564Y424260D02*
X1417350Y438474D01*
G01X1431564Y412300D02*
Y424260D01*
G01X1433400Y410464D02*
X1431564Y412300D01*
G01X1464607Y508818D02*
X1464553Y508872D01*
G01X1470382Y508818D02*
X1464607D01*
G01X1464425Y509000D02*
X1459600D01*
G01X1464553Y508872D02*
X1464425Y509000D01*
G01X1432200Y522040D02*
X1431690Y521530D01*
G01X1432200Y524050D02*
Y522040D01*
G01X1415155Y523926D02*
X1414261Y524820D01*
G01X1415155Y521755D02*
Y523926D01*
G01X1414800Y521400D02*
X1415155Y521755D01*
G01X1415127Y525686D02*
X1414261Y524820D01*
G01X1415127Y530187D02*
Y525686D01*
G01X1416478Y522822D02*
X1417800Y521500D01*
G01X1416478Y528161D02*
Y522822D01*
G01X1431047Y517811D02*
X1405447D01*
G01X1434346Y521110D02*
X1431047Y517811D01*
G01X1434346Y526706D02*
Y521110D01*
G01X1439123Y545794D02*
Y545294D01*
G01X1436462Y548455D02*
X1439123Y545794D01*
G01X1436060Y548455D02*
X1436462D01*
G01X1423305Y534305D02*
X1423800Y534800D01*
G01X1421647Y534305D02*
X1423305D01*
G01X1429300Y538400D02*
X1432600D01*
G01X1426107Y541593D02*
X1429300Y538400D01*
G01X1424210Y541593D02*
X1426107D01*
G01X1429981Y546119D02*
X1428281D01*
G01X1431145Y544955D02*
X1429981Y546119D01*
G01X1432560Y544955D02*
X1431145D01*
G01X1427519Y546119D02*
X1428281D01*
G01X1426142Y544742D02*
X1427519Y546119D01*
G01X1424210Y544742D02*
X1426142D01*
G01X1423731Y527500D02*
X1422000D01*
G01X1423776Y527455D02*
X1423731Y527500D01*
G01X1425560Y527455D02*
X1423776D01*
G01X1420072Y531972D02*
X1419600Y531500D01*
G01X1420072Y534305D02*
Y531972D01*
G01X1419600Y529900D02*
X1422000Y527500D01*
G01X1419600Y531500D02*
Y529900D01*
G01X1429455Y541455D02*
X1429026Y541026D01*
G01X1432560Y541455D02*
X1429455D01*
G01X1426884Y543168D02*
X1429026Y541026D01*
G01X1424210Y543168D02*
X1426884D01*
G01X1428100Y548455D02*
X1429229D01*
G01X1425962Y546317D02*
X1428100Y548455D01*
G01X1424210Y546317D02*
X1425962D01*
G01X1429229Y548455D02*
X1432560D01*
G01X1415347Y530407D02*
X1415127Y530187D01*
G01X1415347Y534305D02*
Y530407D01*
G01X1428903Y535400D02*
X1428791Y535512D01*
G01X1432600Y535400D02*
X1428903D01*
G01X1425497Y540018D02*
X1424210D01*
G01X1428791Y536724D02*
X1425497Y540018D01*
G01X1428791Y535512D02*
Y536724D01*
G01X1431400Y551500D02*
X1432500D01*
G01X1430980Y551920D02*
X1431400Y551500D01*
G01X1428938Y551920D02*
X1430980D01*
G01X1427320Y550302D02*
X1428938Y551920D01*
G01X1427320Y549420D02*
Y550302D01*
G01X1425792Y547892D02*
X1427320Y549420D01*
G01X1424210Y547892D02*
X1425792D01*
G01X1438551Y543033D02*
X1438799Y542785D01*
G01X1438551Y543228D02*
Y543033D01*
G01X1436824Y544955D02*
X1438551Y543228D01*
G01X1436060Y544955D02*
X1436824D01*
G01X1416560Y529705D02*
X1417291Y528974D01*
G01X1416560Y532455D02*
Y529705D01*
G01X1416922Y532817D02*
X1416560Y532455D01*
G01X1416922Y534305D02*
Y532817D01*
G01X1417291Y528974D02*
X1416478Y528161D01*
G01X1438048Y539156D02*
X1439822Y537382D01*
G01X1438048Y540662D02*
Y539156D01*
G01X1437255Y541455D02*
X1438048Y540662D01*
G01X1436060Y541455D02*
X1437255D01*
G01X1430550Y527550D02*
X1432200D01*
G01X1430500Y527500D02*
X1430550Y527550D01*
G01X1428800Y527500D02*
X1430500D01*
G01X1427170Y530800D02*
X1426870D01*
G01X1428800Y529170D02*
X1427170Y530800D01*
G01X1428800Y527500D02*
Y529170D01*
G01X1425032Y536868D02*
X1424210D01*
G01X1425600Y536300D02*
X1425032Y536868D01*
G01X1425600Y532370D02*
Y536300D01*
G01X1426870Y531100D02*
X1425600Y532370D01*
G01X1426870Y530800D02*
Y531100D01*
G01X1436100Y535400D02*
Y538400D01*
G01X1438400Y535400D02*
X1439200Y534600D01*
G01X1436100Y535400D02*
X1438400D01*
G01X1436100Y528460D02*
X1434346Y526706D01*
G01X1436100Y535400D02*
Y528460D01*
G01X1515000Y-11100D02*
Y-15000D01*
G01X1516600Y-9500D02*
X1515000Y-11100D01*
G01X1516600Y-6500D02*
Y-9500D01*
G01X1512500Y-6500D02*
X1516600D01*
G01X1516900Y1000D02*
Y3500D01*
G01X1520100Y1000D02*
Y3500D01*
G01X1510000Y1000D02*
X1513700D01*
G01X1506300Y-2700D02*
X1510000Y1000D01*
G01X1506300Y-6600D02*
Y-2700D01*
G01X1525904Y30668D02*
X1524154Y28918D01*
G01X1542009Y30668D02*
X1525904D01*
G01X1526100Y-2500D02*
X1527600D01*
G01X1524800Y-1200D02*
X1526100Y-2500D01*
G01X1524800Y3500D02*
Y-1200D01*
G01X1521900Y25700D02*
Y27500D01*
G01X1514223Y18023D02*
X1521900Y25700D01*
G01X1510363Y18023D02*
X1514223D01*
G01X1494583Y2243D02*
X1510363Y18023D01*
G01X1487919Y2243D02*
X1494583D01*
G01X1485573Y4589D02*
X1487919Y2243D01*
G01X1485242Y4589D02*
X1485573D01*
G01X1523513Y5163D02*
X1569729D01*
G01X1522600Y4250D02*
X1523513Y5163D01*
G01X1522600Y-2075D02*
Y4250D01*
G01X1522175Y-2500D02*
X1522600Y-2075D01*
G01X1520100Y-2500D02*
X1522175D01*
G01X1520100D02*
X1516900D01*
G01D02*
X1513700D01*
G01X1509000Y-4218D02*
Y-6500D01*
G01X1510718Y-2500D02*
X1509000Y-4218D01*
G01X1513700Y-2500D02*
X1510718D01*
G01X1480243Y1300D02*
X1479243Y300D01*
G01X1494949Y1300D02*
X1480243D01*
G01X1510747Y17098D02*
X1494949Y1300D01*
G01X1516525Y17098D02*
X1510747D01*
G01X1521092Y21665D02*
X1516525Y17098D01*
G01X1513000Y8900D02*
X1567548D01*
G01X1512950Y8950D02*
X1513000Y8900D01*
G01X1511900Y7900D02*
X1512950Y8950D01*
G01X1511900Y3500D02*
Y7900D01*
G01X1525000Y-11200D02*
X1528500Y-7700D01*
G01X1525000Y-15000D02*
Y-11200D01*
G01X1491386Y143080D02*
X1482832D01*
G01X1492206Y143900D02*
X1491386Y143080D01*
G01X1493750Y143900D02*
X1492206D01*
G01X1496110D02*
X1493750D01*
G01X1496945Y143065D02*
X1496110Y143900D01*
G01X1498985Y143065D02*
X1496945D01*
G01X1489313Y105353D02*
X1489780Y105820D01*
G01X1483779Y105353D02*
X1489313D01*
G01X1503051Y150673D02*
X1507076D01*
G01X1502626Y151098D02*
X1503051Y150673D01*
G01X1502626Y155332D02*
Y151098D01*
G01X1501445Y156513D02*
X1502626Y155332D01*
G01X1487240Y95353D02*
X1483779D01*
G01X1490674Y98787D02*
X1487240Y95353D01*
G01X1492013Y156020D02*
Y155610D01*
G01X1493472Y157479D02*
X1492013Y156020D01*
G01X1498499Y154476D02*
X1495496Y157479D01*
G01X1498499Y153671D02*
Y154476D01*
G01X1500597Y151573D02*
X1498499Y153671D01*
G01X1500597Y150393D02*
Y151573D01*
G01X1501689Y149301D02*
X1500597Y150393D01*
G01X1501689Y147811D02*
Y149301D01*
G01X1502000Y147500D02*
X1501689Y147811D01*
G01X1487424Y100353D02*
X1483779D01*
G01X1489205Y102134D02*
X1487424Y100353D01*
G01X1489205Y103325D02*
Y102134D01*
G01X1489053Y103325D02*
X1489205D01*
G01X1524580Y210920D02*
X1529699D01*
G01X1520300Y215200D02*
X1524580Y210920D01*
G01X1510373Y215200D02*
X1520300D01*
G01X1509173Y214000D02*
X1510373Y215200D01*
G01X1505000Y214000D02*
X1509173D01*
G01X1525031Y183082D02*
X1538193D01*
G01X1517092Y191021D02*
X1525031Y183082D01*
G01X1517092Y193339D02*
Y191021D01*
G01X1515931Y194500D02*
X1517092Y193339D01*
G01X1511970Y194500D02*
X1515931D01*
G01X1510800Y193330D02*
X1511970Y194500D01*
G01X1502219Y211425D02*
X1500004Y209210D01*
G01X1508025Y211425D02*
X1502219D01*
G01X1510875Y214275D02*
X1508025Y211425D01*
G01X1518775Y214275D02*
X1510875D01*
G01X1524550Y208500D02*
X1518775Y214275D01*
G01X1533700Y208500D02*
X1524550D01*
G01X1499363Y208569D02*
X1500004Y209210D01*
G01X1480344Y208569D02*
X1499363D01*
G01X1479000Y207225D02*
X1480344Y208569D01*
G01X1525080Y205920D02*
X1529699D01*
G01X1517775Y213225D02*
X1525080Y205920D01*
G01X1511842Y213225D02*
X1517775D01*
G01X1507617Y209000D02*
X1511842Y213225D01*
G01X1505000Y209000D02*
X1507617D01*
G01X1521499Y200200D02*
X1520100D01*
G01X1523595Y198104D02*
X1521499Y200200D01*
G01X1523595Y188804D02*
Y198104D01*
G01X1524199Y188200D02*
X1523595Y188804D01*
G01X1529199Y188200D02*
X1524199D01*
G01X1498867Y156513D02*
X1501445D01*
G01X1496602Y158778D02*
X1498867Y156513D01*
G01X1496602Y160189D02*
Y158778D01*
G01X1494091Y162700D02*
X1496602Y160189D01*
G01X1493200Y162700D02*
X1494091D01*
G01X1487688Y178080D02*
X1482832D01*
G01X1489088Y176680D02*
X1487688Y178080D01*
G01X1511800Y209669D02*
X1512525Y208944D01*
G01X1511800Y211874D02*
Y209669D01*
G01X1512226Y212300D02*
X1511800Y211874D01*
G01X1514275Y212300D02*
X1512226D01*
G01X1514700Y211875D02*
X1514275Y212300D01*
G01X1514700Y200800D02*
Y211875D01*
G01X1515300Y200200D02*
X1514700Y200800D01*
G01X1516600Y200200D02*
X1515300D01*
G01X1486880Y173080D02*
X1482832D01*
G01X1488039Y174239D02*
X1486880Y173080D01*
G01X1489852Y174239D02*
X1488039D01*
G01X1492500Y176887D02*
X1489852Y174239D01*
G01X1510837Y203237D02*
X1512700Y205100D01*
G01X1510837Y198964D02*
Y203237D01*
G01X1511781Y198020D02*
X1510837Y198964D01*
G01X1517006Y198020D02*
X1511781D01*
G01X1521000Y194026D02*
X1517006Y198020D01*
G01X1521000Y188632D02*
Y194026D01*
G01X1525625Y184007D02*
X1521000Y188632D01*
G01X1538693Y184007D02*
X1525625D01*
G01X1516761Y203200D02*
X1516598Y203037D01*
G01X1519200Y203200D02*
X1516761D01*
G01X1521895Y206700D02*
X1519200D01*
G01X1525195Y203400D02*
X1521895Y206700D01*
G01X1538500Y203400D02*
X1525195D01*
G01X1495496Y157479D02*
X1493472D01*
G01X1506492Y230966D02*
X1534524D01*
G01X1503783Y233675D02*
X1506492Y230966D01*
G01X1498478Y233675D02*
X1503783D01*
G01X1471736Y248956D02*
X1474520Y251740D01*
G01X1489649Y273500D02*
X1487972Y275177D01*
G01X1492529Y273500D02*
X1489649D01*
G01X1492753Y273724D02*
X1492529Y273500D01*
G01X1487008Y247916D02*
X1486926Y247834D01*
G01X1497076Y247916D02*
X1487008D01*
G01X1506564Y238428D02*
X1497076Y247916D01*
G01X1516944Y238428D02*
X1506564D01*
G01X1519677Y241161D02*
X1516944Y238428D01*
G01X1521102Y241161D02*
X1519677D01*
G01X1522613Y239650D02*
X1521102Y241161D01*
G01X1534322Y239650D02*
X1522613D01*
G01X1486147Y251800D02*
X1484700D01*
G01X1486276Y251929D02*
X1486147Y251800D01*
G01X1495209Y251929D02*
X1486276D01*
G01X1505048Y242090D02*
X1495209Y251929D01*
G01X1513150Y242090D02*
X1505048D01*
G01X1513642Y241598D02*
X1513150Y242090D01*
G01X1515102Y241598D02*
X1513642D01*
G01X1516090Y242586D02*
X1515102Y241598D01*
G01X1519206Y242586D02*
X1516090D01*
G01X1521183Y244563D02*
X1519206Y242586D01*
G01X1524289Y244563D02*
X1521183D01*
G01X1525263Y243589D02*
X1524289Y244563D01*
G01X1525263Y243586D02*
Y243589D01*
G01X1526263Y242586D02*
X1525263Y243586D01*
G01X1538014Y242586D02*
X1526263D01*
G01X1473798Y276753D02*
X1472224Y278327D01*
G01X1476948Y273603D02*
X1475374Y275177D01*
G01X1505541Y228672D02*
X1533573D01*
G01X1503040Y231173D02*
X1505541Y228672D01*
G01X1499559Y231173D02*
X1503040D01*
G01X1469075Y267663D02*
X1469829Y266909D01*
G01X1469075Y268878D02*
Y267663D01*
G01X1473798Y270454D02*
X1472224Y272028D01*
G01X1474836Y241169D02*
X1468070D01*
G01X1476072Y242405D02*
X1474836Y241169D01*
G01X1481549Y242405D02*
X1476072D01*
G01X1486791Y237163D02*
X1481549Y242405D01*
G01X1502913Y237163D02*
X1486791D01*
G01X1504135Y235941D02*
X1502913Y237163D01*
G01X1518099Y235941D02*
X1504135D01*
G01X1519990Y234050D02*
X1518099Y235941D01*
G01X1523398Y234050D02*
X1519990D01*
G01X1525611Y236263D02*
X1523398Y234050D01*
G01X1532685Y236263D02*
X1525611D01*
G01X1476948Y270454D02*
X1475374Y272028D01*
G01X1500672Y219250D02*
X1500346Y219576D01*
G01X1502850Y219250D02*
X1500672D01*
G01X1503946Y220346D02*
X1502850Y219250D01*
G01X1503946Y221770D02*
Y220346D01*
G01X1500346Y219576D02*
X1498022Y221900D01*
G01X1480098Y267304D02*
X1478524Y268878D01*
G01X1486397Y270454D02*
X1484823Y272028D01*
G01X1507446Y223254D02*
Y221770D01*
G01X1506500Y224200D02*
X1507446Y223254D01*
G01X1502800Y224200D02*
X1506500D01*
G01X1500622Y226378D02*
X1502800Y224200D01*
G01X1497678Y226378D02*
X1500622D01*
G01X1495300Y224000D02*
X1497678Y226378D01*
G01X1507466Y221750D02*
X1507446Y221770D01*
G01X1511000Y221750D02*
X1507466D01*
G01X1522080Y220920D02*
X1529699D01*
G01X1521250Y221750D02*
X1522080Y220920D01*
G01X1518000Y221750D02*
X1521250D01*
G01X1518000D02*
X1511000D01*
G01X1505547Y272028D02*
X1491122D01*
G01X1505768Y272249D02*
X1505547Y272028D01*
G01X1507003Y272249D02*
X1505768D01*
G01X1496395Y277300D02*
X1497082Y277987D01*
G01X1492022Y277300D02*
X1496395D01*
G01X1491686Y276964D02*
X1492022Y277300D01*
G01X1489335Y276964D02*
X1491686D01*
G01X1487972Y278327D02*
X1489335Y276964D01*
G01X1475374Y266025D02*
Y268878D01*
G01X1475799Y265600D02*
X1475374Y266025D01*
G01X1494880Y265600D02*
X1475799D01*
G01X1503619Y256861D02*
X1494880Y265600D01*
G01X1503619Y254117D02*
Y256861D01*
G01X1504374Y253362D02*
X1503619Y254117D01*
G01X1504374Y246210D02*
Y253362D01*
G01X1503842Y245678D02*
X1504374Y246210D01*
G01X1472224Y266468D02*
Y268878D01*
G01X1475146Y263546D02*
X1472224Y266468D01*
G01X1495378Y263546D02*
X1475146D01*
G01X1501210Y257714D02*
X1495378Y263546D01*
G01X1501210Y254557D02*
Y257714D01*
G01X1499472Y252819D02*
X1501210Y254557D01*
G01X1499472Y250370D02*
Y252819D01*
G01X1487068Y238449D02*
X1477486Y248031D01*
G01X1503169Y238449D02*
X1487068D01*
G01X1504752Y236866D02*
X1503169Y238449D01*
G01X1518554Y236866D02*
X1504752D01*
G01X1520390Y235030D02*
X1518554Y236866D01*
G01X1523069Y235030D02*
X1520390D01*
G01X1525227Y237188D02*
X1523069Y235030D01*
G01X1533069Y237188D02*
X1525227D01*
G01X1491188Y229800D02*
X1489061Y231927D01*
G01X1497687Y229800D02*
X1491188D01*
G01X1498608Y228879D02*
X1497687Y229800D01*
G01X1502089Y228879D02*
X1498608D01*
G01X1504590Y226378D02*
X1502089Y228879D01*
G01X1532622Y226378D02*
X1504590D01*
G01X1476798Y240655D02*
X1475243Y239100D01*
G01X1480333Y240655D02*
X1476798D01*
G01X1489061Y231927D02*
X1480333Y240655D01*
G01X1476948Y276753D02*
X1475374Y278327D01*
G01X1492276Y276331D02*
X1491122Y275177D01*
G01X1496386Y276331D02*
X1492276D01*
G01X1496393Y276324D02*
X1496386Y276331D01*
G01X1499324Y276324D02*
X1496393D01*
G01X1506500Y283500D02*
X1499324Y276324D01*
G01X1506876Y231891D02*
X1534908D01*
G01X1502529Y236238D02*
X1506876Y231891D01*
G01X1485917Y236238D02*
X1502529D01*
G01X1480675Y241480D02*
X1485917Y236238D01*
G01X1476456Y241480D02*
X1480675D01*
G01X1475093Y240117D02*
X1476456Y241480D01*
G01X1466787Y252916D02*
X1465752Y251881D01*
G01X1466787Y253589D02*
Y252916D01*
G01X1467700Y254502D02*
X1466787Y253589D01*
G01X1467700Y255900D02*
Y254502D01*
G01Y255900D02*
Y257000D01*
G01X1472613Y252157D02*
X1471200Y250744D01*
G01X1472613Y255837D02*
Y252157D01*
G01X1472433Y256017D02*
X1472613Y255837D01*
G01X1472433Y258775D02*
Y256017D01*
G01X1466006Y265202D02*
X1472433Y258775D01*
G01X1466006Y265300D02*
Y265202D01*
G01X1491960Y337409D02*
Y342710D01*
G01X1492993Y336376D02*
X1491960Y337409D01*
G01X1496400Y336376D02*
X1492993D01*
G01X1520750Y311800D02*
Y314300D01*
G01X1520972Y311578D02*
X1520750Y311800D01*
G01X1520972Y308617D02*
Y311578D01*
G01X1477000Y339396D02*
Y343750D01*
G01X1481133Y335263D02*
X1477000Y339396D01*
G01X1483374Y335263D02*
X1481133D01*
G01X1485337Y333300D02*
X1483374Y335263D01*
G01X1487000Y333300D02*
X1485337D01*
G01X1480000Y340100D02*
Y343750D01*
G01X1479678Y339778D02*
X1480000Y340100D01*
G01X1479678Y339648D02*
Y339778D01*
G01X1481210Y338116D02*
X1479678Y339648D01*
G01X1481210Y338102D02*
Y338116D01*
G01X1482386Y336926D02*
X1481210Y338102D01*
G01X1480098Y301948D02*
X1478524Y300374D01*
G01X1466823Y317020D02*
X1465925Y316122D01*
G01X1466823Y320088D02*
Y317020D01*
G01X1466970Y320235D02*
X1466823Y320088D01*
G01X1489546Y317696D02*
X1487972Y316122D01*
G01X1487974Y303524D02*
X1487972D01*
G01X1489700Y305250D02*
X1487974Y303524D01*
G01X1491626Y305250D02*
X1489700D01*
G01X1492500Y306124D02*
X1491626Y305250D01*
G01X1494426Y306124D02*
X1492500D01*
G01X1497430Y303120D02*
X1494426Y306124D01*
G01X1497509Y303120D02*
X1497430D01*
G01X1472224Y306673D02*
X1473798Y308247D01*
G01X1486397D02*
X1484823Y306673D01*
G01X1499000Y342079D02*
X1499829Y341250D01*
G01X1516000Y306057D02*
X1520972D01*
G01X1514416Y307641D02*
X1516000Y306057D01*
G01X1511955Y307641D02*
X1514416D01*
G01X1511955Y310641D02*
Y307641D01*
G01X1517074Y332646D02*
X1528055D01*
G01X1516552Y333168D02*
X1517074Y332646D01*
G01X1509118Y333168D02*
X1516552D01*
G01X1505240Y329290D02*
X1509118Y333168D01*
G01X1501514Y329290D02*
X1505240D01*
G01X1501274Y329050D02*
X1501514Y329290D01*
G01X1498910Y329050D02*
X1501274D01*
G01X1493016Y323156D02*
X1498910Y329050D01*
G01X1478992Y323156D02*
X1493016D01*
G01X1478556Y323592D02*
X1478992Y323156D01*
G01X1469568Y323592D02*
X1478556D01*
G01X1468594Y322618D02*
X1469568Y323592D01*
G01X1468594Y317568D02*
Y322618D01*
G01X1467712Y316686D02*
X1468594Y317568D01*
G01X1467712Y308460D02*
Y316686D01*
G01X1465925Y306673D02*
X1467712Y308460D01*
G01X1491122Y306821D02*
Y306673D01*
G01X1495651Y311350D02*
X1491122Y306821D01*
G01X1491147Y309823D02*
X1491122D01*
G01X1492700Y311376D02*
X1491147Y309823D01*
G01X1492624Y303524D02*
X1491122D01*
G01X1493500Y304400D02*
X1492624Y303524D01*
G01X1518073Y334996D02*
X1527580D01*
G01X1517551Y335518D02*
X1518073Y334996D01*
G01X1508143Y335518D02*
X1517551D01*
G01X1506960Y334335D02*
X1508143Y335518D01*
G01X1503142Y334335D02*
X1506960D01*
G01X1500397Y331590D02*
X1503142Y334335D01*
G01X1491390Y331590D02*
X1500397D01*
G01X1487825Y328025D02*
X1491390Y331590D01*
G01X1477975Y328025D02*
X1487825D01*
G01X1474300Y331700D02*
X1477975Y328025D01*
G01X1474300Y338002D02*
Y331700D01*
G01X1473139Y339163D02*
X1474300Y338002D01*
G01X1472059Y339163D02*
X1473139D01*
G01X1470837Y340385D02*
X1472059Y339163D01*
G01X1470837Y353649D02*
Y340385D01*
G01X1471706Y337500D02*
X1472450D01*
G01X1469350Y339856D02*
X1471706Y337500D01*
G01X1469350Y343148D02*
Y339856D01*
G01X1483247Y314546D02*
X1481673Y312972D01*
G01X1482550Y332272D02*
Y333600D01*
G01X1480229Y329951D02*
X1482550Y332272D01*
G01X1479349Y329951D02*
X1480229D01*
G01X1478726Y330574D02*
X1479349Y329951D01*
G01X1478726Y331454D02*
Y330574D01*
G01X1480359Y333087D02*
X1478726Y331454D01*
G01X1480359Y333967D02*
Y333087D01*
G01X1479736Y334590D02*
X1480359Y333967D01*
G01X1478856Y334590D02*
X1479736D01*
G01X1477123Y332857D02*
X1478856Y334590D01*
G01X1476443Y332857D02*
X1477123D01*
G01X1475820Y333480D02*
X1476443Y332857D01*
G01X1475820Y334560D02*
Y333480D01*
G01X1477253Y335993D02*
X1475820Y334560D01*
G01X1477253Y337073D02*
Y335993D01*
G01X1475000Y339326D02*
X1477253Y337073D01*
G01X1475000Y346500D02*
Y339326D01*
G01X1484823Y316123D02*
X1486396Y317696D01*
G01X1484823Y316122D02*
Y316123D01*
G01X1478524Y318900D02*
Y316122D01*
G01X1507476Y302789D02*
X1504453D01*
G01X1507503Y302816D02*
X1507476Y302789D01*
G01X1510476Y302816D02*
X1507503D01*
G01X1513476D02*
X1510476D01*
G01X1515803Y303497D02*
X1520972D01*
G01X1514150Y305150D02*
X1515803Y303497D01*
G01X1507459Y305150D02*
X1514150D01*
G01X1505935Y306674D02*
X1507459Y305150D01*
G01X1482585Y340856D02*
X1483000Y341271D01*
G01X1483247Y286202D02*
X1481673Y287776D01*
G01X1476948Y311397D02*
X1475374Y309823D01*
G01X1488324Y297224D02*
X1487972D01*
G01X1489900Y298800D02*
X1488324Y297224D01*
G01X1492669Y298800D02*
X1489900D01*
G01X1493069Y299200D02*
X1492669Y298800D01*
G01X1496900Y299200D02*
X1493069D01*
G01X1501550Y294550D02*
X1496900Y299200D01*
G01X1501550Y293750D02*
Y294550D01*
G01X1483247Y283052D02*
X1481673Y284626D01*
G01X1512733Y295817D02*
X1520972D01*
G01X1512733Y294768D02*
Y295817D01*
G01X1512182Y294217D02*
X1512733Y294768D01*
G01X1512182Y293317D02*
Y294217D01*
G01X1515763Y322793D02*
X1516910Y323940D01*
G01X1515763Y321103D02*
Y322793D01*
G01X1514789Y320129D02*
X1515763Y321103D01*
G01X1513411Y320129D02*
X1514789D01*
G01X1513193Y320347D02*
X1513411Y320129D01*
G01X1513043Y320347D02*
X1513193D01*
G01X1511460Y321930D02*
X1513043Y320347D01*
G01X1503910Y321930D02*
X1511460D01*
G01X1501850Y319870D02*
X1503910Y321930D01*
G01X1500840Y319870D02*
X1501850D01*
G01X1486397Y314546D02*
X1484823Y312972D01*
G01X1526881Y324947D02*
X1530573D01*
G01X1524176Y327652D02*
X1526881Y324947D01*
G01X1521513Y327652D02*
X1524176D01*
G01X1480098Y314546D02*
X1478524Y312972D01*
G01X1476750Y314348D02*
X1475374Y312972D01*
G01X1476750Y319257D02*
Y314348D01*
G01X1477900Y320407D02*
X1476750Y319257D01*
G01X1497194Y320407D02*
X1477900D01*
G01X1502028Y315573D02*
X1497194Y320407D01*
G01X1505044Y315573D02*
X1502028D01*
G01X1505869Y316398D02*
X1505044Y315573D01*
G01X1505869Y318669D02*
Y316398D01*
G01X1513600Y289100D02*
X1528900D01*
G01X1513046Y289654D02*
X1513600Y289100D01*
G01X1509566Y289654D02*
X1513046D01*
G01X1509479Y289741D02*
X1509566Y289654D01*
G01X1506396Y289741D02*
X1509479D01*
G01X1493333Y285565D02*
X1491122Y287776D01*
G01X1499865Y285565D02*
X1493333D01*
G01X1504041Y289741D02*
X1499865Y285565D01*
G01X1506396Y289741D02*
X1504041D01*
G01X1471562Y325923D02*
Y325531D01*
G01X1470355Y327130D02*
X1471562Y325923D01*
G01X1467950Y327130D02*
X1470355D01*
G01X1507792Y307641D02*
X1508455D01*
G01X1505923Y309510D02*
X1507792Y307641D01*
G01X1517115Y327645D02*
Y330005D01*
G01X1516910Y327440D02*
X1517115Y327645D01*
G01X1473798Y279902D02*
X1472224Y281476D01*
G01X1469845Y316892D02*
X1469075Y316122D01*
G01X1469845Y319137D02*
Y316892D01*
G01X1472565Y321857D02*
X1469845Y319137D01*
G01X1479124Y321857D02*
X1472565D01*
G01X1479598Y322331D02*
X1479124Y321857D01*
G01X1493358Y322331D02*
X1479598D01*
G01X1499252Y328225D02*
X1493358Y322331D01*
G01X1501616Y328225D02*
X1499252D01*
G01X1501801Y328410D02*
X1501616Y328225D01*
G01X1505573Y328410D02*
X1501801D01*
G01X1509506Y332343D02*
X1505573Y328410D01*
G01X1516176Y332343D02*
X1509506D01*
G01X1516754Y331765D02*
X1516176Y332343D01*
G01X1518313Y331765D02*
X1516754D01*
G01X1520970Y329108D02*
X1518313Y331765D01*
G01X1524606Y329108D02*
X1520970D01*
G01X1525051Y329553D02*
X1524606Y329108D01*
G01X1480098Y311397D02*
X1478524Y309823D01*
G01X1510987Y324163D02*
Y325669D01*
G01X1513140Y322010D02*
X1510987Y324163D01*
G01X1513882Y322010D02*
X1513140D01*
G01X1514100Y321792D02*
X1513882Y322010D01*
G01X1492974Y300374D02*
X1491122D01*
G01X1493400Y300800D02*
X1492974Y300374D01*
G01X1516161Y298377D02*
X1520972D01*
G01X1515222Y299316D02*
X1516161Y298377D01*
G01X1513476Y299316D02*
X1515222D01*
G01X1493680Y339820D02*
Y341430D01*
G01X1494776Y338724D02*
X1493680Y339820D01*
G01X1495445Y338724D02*
X1494776D01*
G01X1473798Y301948D02*
X1472224Y300374D01*
G01X1476948Y305098D02*
X1475374Y303524D01*
G01X1501274Y337474D02*
X1498600Y334800D01*
G01X1502142Y337474D02*
X1501274D01*
G01X1503246Y338578D02*
X1502142Y337474D01*
G01X1503246Y340094D02*
Y338578D01*
G01X1502000Y341340D02*
X1503246Y340094D01*
G01X1484754Y319203D02*
X1481673Y316122D01*
G01X1494697Y319203D02*
X1484754D01*
G01X1499393Y314507D02*
X1494697Y319203D01*
G01X1507569Y314507D02*
X1499393D01*
G01X1507766Y314704D02*
X1507569Y314507D01*
G01X1513145Y314704D02*
X1507766D01*
G01X1514067Y315626D02*
X1513145Y314704D01*
G01X1493700Y281476D02*
X1491122D01*
G01X1491748Y284000D02*
X1491122Y284626D01*
G01X1496700Y284000D02*
X1491748D01*
G01X1498850Y281850D02*
X1496700Y284000D01*
G01X1498850Y280741D02*
Y281850D01*
G01X1499681Y279910D02*
X1498850Y280741D01*
G01X1470649Y311397D02*
X1469075Y309823D01*
G01X1484823Y303524D02*
X1486397Y305098D01*
G01X1517482Y333571D02*
X1528439D01*
G01X1516960Y334093D02*
X1517482Y333571D01*
G01X1508734Y334093D02*
X1516960D01*
G01X1507551Y332910D02*
X1508734Y334093D01*
G01X1503825Y332910D02*
X1507551D01*
G01X1501080Y330165D02*
X1503825Y332910D01*
G01X1491981Y330165D02*
X1501080D01*
G01X1485897Y324081D02*
X1491981Y330165D01*
G01X1479490Y324081D02*
X1485897D01*
G01X1478585Y324986D02*
X1479490Y324081D01*
G01X1475494Y324986D02*
X1478585D01*
G01X1471500Y328980D02*
X1475494Y324986D01*
G01X1467783Y328980D02*
X1471500D01*
G01X1491254Y293943D02*
X1493268D01*
G01X1491122Y294075D02*
X1491254Y293943D01*
G01X1483247Y311397D02*
X1481673Y309823D01*
G01X1486397Y298798D02*
X1484823Y297224D01*
G01X1485325Y290925D02*
X1484823D01*
G01X1486800Y292400D02*
X1485325Y290925D01*
G01X1491800Y292400D02*
X1486800D01*
G01X1492400Y291800D02*
X1491800Y292400D01*
G01X1496000Y291800D02*
X1492400D01*
G01X1499300Y288500D02*
X1496000Y291800D01*
G01X1499974Y288500D02*
X1499300D01*
G01X1499987Y288487D02*
X1499974Y288500D01*
G01X1483247Y301948D02*
X1481673Y300374D01*
G01X1494272Y312972D02*
X1491122D01*
G01X1495846Y314546D02*
X1494272Y312972D01*
G01X1495699Y314546D02*
X1495846D01*
G01X1470649Y279902D02*
X1469075Y281476D01*
G01X1471064Y332437D02*
X1469223D01*
G01X1476901Y326600D02*
X1471064Y332437D01*
G01X1479559Y326600D02*
X1476901D01*
G01X1480098Y326061D02*
X1479559Y326600D01*
G01X1483506Y326061D02*
X1480098D01*
G01X1489546Y308247D02*
X1487972Y306673D01*
G01X1484823Y294075D02*
X1486397Y295649D01*
G01X1470649Y301948D02*
X1469075Y300374D01*
G01X1478524Y294075D02*
X1480098Y295649D01*
G01X1476948Y298798D02*
X1475374Y297224D01*
G01X1523887Y325093D02*
X1521513D01*
G01X1524710Y324270D02*
X1523887Y325093D01*
G01X1524710Y321640D02*
Y324270D01*
G01X1523812Y320742D02*
X1524710Y321640D01*
G01X1521778Y320742D02*
X1523812D01*
G01X1519360Y318324D02*
X1521778Y320742D01*
G01X1518864Y318324D02*
X1519360D01*
G01X1518060Y317520D02*
X1518864Y318324D01*
G01X1476948Y289351D02*
X1475374Y290925D01*
G01X1499723Y298526D02*
Y300106D01*
G01X1500832Y297417D02*
X1499723Y298526D01*
G01X1507001Y297417D02*
X1500832D01*
G01X1507476Y297892D02*
X1507001Y297417D01*
G01X1507476Y299289D02*
Y297892D01*
G01X1476948Y308247D02*
X1475374Y306673D01*
G01X1495224Y297224D02*
X1495300Y297300D01*
G01X1491122Y297224D02*
X1495224D01*
G01X1516112Y285000D02*
X1514500D01*
G01X1517818Y286706D02*
X1516112Y285000D01*
G01X1518006Y286706D02*
X1517818D01*
G01X1513000Y283500D02*
X1506500D01*
G01X1514500Y285000D02*
X1513000Y283500D01*
G01X1497328Y306372D02*
X1497179D01*
G01X1501145Y302555D02*
X1497328Y306372D01*
G01X1501145Y301316D02*
Y302555D01*
G01X1503172Y299289D02*
X1501145Y301316D01*
G01X1504453Y299289D02*
X1503172D01*
G01X1489498Y283100D02*
X1487972Y284626D01*
G01X1494900Y283100D02*
X1489498D01*
G01X1496600Y281400D02*
X1494900Y283100D01*
G01X1489497Y295600D02*
X1487972Y294075D01*
G01X1494100Y295600D02*
X1489497D01*
G01X1495800Y293900D02*
X1494100Y295600D01*
G01X1496900Y293900D02*
X1495800D01*
G01X1527301Y338500D02*
X1523250D01*
G01Y341100D02*
X1523000Y341350D01*
G01X1523250Y338500D02*
Y341100D01*
G01X1508455Y310641D02*
Y313041D01*
G01X1473798Y314546D02*
X1472224Y312972D01*
G01X1491960Y342710D02*
X1493000Y343750D01*
G01X1504600Y394635D02*
X1505075Y394414D01*
G01X1503125Y395320D02*
X1504600Y394635D01*
G01X1487525Y381800D02*
X1489475Y380894D01*
G01X1487525Y402080D02*
X1489475Y401174D01*
G01X1495325Y377514D02*
X1493375Y378420D01*
G01X1487525Y397794D02*
X1485575Y398700D01*
G01X1501900Y358500D02*
X1504509Y361109D01*
G01X1501900Y356750D02*
Y358500D01*
G01X1500165Y355015D02*
X1501900Y356750D01*
G01X1500165Y351415D02*
Y355015D01*
G01X1496000Y347250D02*
X1500165Y351415D01*
G01X1504600Y401395D02*
X1505075Y401174D01*
G01X1503125Y402080D02*
X1504600Y401395D01*
G01X1512520Y354158D02*
Y355283D01*
G01X1514000Y352678D02*
X1512520Y354158D01*
G01X1514000Y347250D02*
Y352678D01*
G01X1522625Y381800D02*
X1524575Y380894D01*
G01X1491425Y402080D02*
X1493375Y401174D01*
G01X1491425Y381800D02*
X1493375Y380894D01*
G01X1499000Y343750D02*
Y342079D01*
G01X1518725Y397794D02*
X1516775Y398700D01*
G01X1491999Y361287D02*
X1488479Y357767D01*
G01X1491999Y366529D02*
Y361287D01*
G01X1491615Y366913D02*
X1491999Y366529D01*
G01X1472415Y389085D02*
X1470580Y387250D01*
G01X1526525Y395320D02*
X1527500Y394868D01*
G01X1520675Y391940D02*
X1522625Y391034D01*
G01X1487525Y395320D02*
X1489475Y394414D01*
G01X1527145Y356616D02*
X1524746Y354217D01*
G01X1526657Y360842D02*
X1527145Y360354D01*
G01X1526657Y367227D02*
Y360842D01*
G01X1526336Y367548D02*
X1526657Y367227D01*
G01X1526336Y368940D02*
Y367548D01*
G01X1526934Y369538D02*
X1526336Y368940D01*
G01X1526934Y370989D02*
Y369538D01*
G01X1527500Y371555D02*
X1526934Y370989D01*
G01X1490001Y364489D02*
X1488479Y362967D01*
G01X1490001Y366132D02*
Y364489D01*
G01X1489609Y366524D02*
X1490001Y366132D01*
G01X1504600Y387875D02*
X1505075Y387654D01*
G01X1503125Y388560D02*
X1504600Y387875D01*
G01X1494950Y351050D02*
X1496000Y350000D01*
G01X1494950Y353000D02*
Y351050D01*
G01X1499225Y397794D02*
X1497275Y398700D01*
G01X1495325Y397794D02*
X1493375Y398700D01*
G01X1494950Y357678D02*
Y356500D01*
G01X1495552Y358280D02*
X1494950Y357678D01*
G01X1495552Y364865D02*
Y358280D01*
G01X1471438Y354250D02*
X1470837Y353649D01*
G01X1472500Y354250D02*
X1471438D01*
G01X1510925Y381800D02*
X1512875Y380894D01*
G01X1467200Y345298D02*
X1469350Y343148D01*
G01X1467200Y347700D02*
Y345298D01*
G01X1499225Y381800D02*
X1501175Y380894D01*
G01X1482300Y391800D02*
X1484600Y394100D01*
G01X1481178Y391800D02*
X1482300D01*
G01X1479629Y393349D02*
X1481178Y391800D01*
G01X1479629Y393653D02*
Y393349D01*
G01X1478889Y394393D02*
X1479629Y393653D01*
G01X1477843Y394393D02*
X1478889D01*
G01X1477250Y393800D02*
X1477843Y394393D01*
G01X1475768Y393800D02*
X1477250D01*
G01X1475098Y393130D02*
X1475768Y393800D01*
G01X1491425Y395320D02*
X1493375Y394414D01*
G01X1472500Y347250D02*
Y350750D01*
G01X1474250Y347250D02*
X1475000Y346500D01*
G01X1472500Y347250D02*
X1474250D01*
G01Y350750D02*
X1472500D01*
G01X1476500Y353000D02*
X1474250Y350750D01*
G01X1476500Y356750D02*
Y353000D01*
G01X1476075Y357175D02*
X1476500Y356750D01*
G01X1469635Y357175D02*
X1476075D01*
G01X1469013Y356553D02*
X1469635Y357175D01*
G01X1469013Y350522D02*
Y356553D01*
G01X1468391Y349900D02*
X1469013Y350522D01*
G01X1467510Y349900D02*
X1468391D01*
G01X1466888Y350522D02*
X1467510Y349900D01*
G01X1466888Y356309D02*
Y350522D01*
G01X1465400Y358678D02*
Y357797D01*
G01X1476078Y359300D02*
X1466022D01*
G01X1476700Y359922D02*
X1476078Y359300D01*
G01X1476700Y360803D02*
Y359922D01*
G01X1476078Y361425D02*
X1476700Y360803D01*
G01X1469922Y361425D02*
X1476078D01*
G01X1469300Y362047D02*
X1469922Y361425D01*
G01X1469300Y362928D02*
Y362047D01*
G01X1469922Y363550D02*
X1469300Y362928D01*
G01X1476075Y363550D02*
X1469922D01*
G01X1476500Y363975D02*
X1476075Y363550D01*
G01X1476500Y366500D02*
Y363975D01*
G01X1479750Y369750D02*
X1476500Y366500D01*
G01X1479750Y370752D02*
Y369750D01*
G01X1497275Y385180D02*
X1499225Y384274D01*
G01X1510925Y402080D02*
X1512875Y401174D01*
G01X1526525Y388560D02*
X1528475Y387654D01*
G01X1483000Y341271D02*
Y343750D01*
G01X1484268D02*
X1483000D01*
G01X1485051Y344533D02*
X1484268Y343750D01*
G01X1485051Y346530D02*
Y344533D01*
G01X1485771Y347250D02*
X1485051Y346530D01*
G01X1487000Y347250D02*
X1485771D01*
G01X1492824Y367530D02*
X1492067Y368287D01*
G01X1492824Y360096D02*
Y367530D01*
G01X1490339Y357611D02*
X1492824Y360096D01*
G01X1490339Y356932D02*
Y357611D01*
G01X1487000Y353593D02*
X1490339Y356932D01*
G01X1487000Y347250D02*
Y353593D01*
G01X1465500Y361300D02*
Y363500D01*
G01X1485575Y391940D02*
X1483868Y390233D01*
G01X1522625Y377514D02*
X1520675Y378420D01*
G01X1499225Y402080D02*
X1501175Y401174D01*
G01X1516775Y385180D02*
X1518725Y384274D01*
G01X1497275Y391940D02*
X1499225Y391034D01*
G01X1526525Y402080D02*
X1528475Y401174D01*
G01X1476902Y397067D02*
X1478366D01*
G01X1475535Y395700D02*
X1476902Y397067D01*
G01X1471300Y395700D02*
X1475535D01*
G01X1470800Y395200D02*
X1471300Y395700D01*
G01X1468700Y395200D02*
X1470800D01*
G01X1467031Y393531D02*
X1468700Y395200D01*
G01X1490927Y362815D02*
X1488479Y360367D01*
G01X1490927Y366372D02*
Y362815D01*
G01X1490826Y366473D02*
X1490927Y366372D01*
G01X1490826Y366474D02*
Y366473D01*
G01X1490098Y367202D02*
X1490826Y366474D01*
G01X1522625Y384274D02*
X1520675Y385180D01*
G01X1524575Y387654D02*
X1522625Y388560D01*
G01X1480000Y348165D02*
Y347250D01*
G01X1479251Y348914D02*
X1480000Y348165D01*
G01X1479251Y350752D02*
Y348914D01*
G01X1483211Y354712D02*
X1479251Y350752D01*
G01X1484212Y354712D02*
X1483211D01*
G01X1486000Y356500D02*
X1484212Y354712D01*
G01X1486000Y364500D02*
Y356500D01*
G01X1499225Y395320D02*
X1501175Y394414D01*
G01X1505400Y350587D02*
Y357732D01*
G01X1502063Y347250D02*
X1505400Y350587D01*
G01X1502000Y347250D02*
X1502063D01*
G01X1510925Y388560D02*
X1512875Y387654D01*
G01X1490000Y347714D02*
Y347250D01*
G01X1491814Y349528D02*
X1490000Y347714D01*
G01X1491814Y357883D02*
Y349528D01*
G01X1493756Y359825D02*
X1491814Y357883D01*
G01X1493756Y367815D02*
Y359825D01*
G01X1494481Y368540D02*
X1493756Y367815D01*
G01X1493680Y341430D02*
X1496000Y343750D01*
G01X1517000Y349597D02*
X1517367Y349964D01*
G01X1517000Y347250D02*
Y349597D01*
G01X1516960Y350371D02*
X1517367Y349964D01*
G01X1516960Y352580D02*
Y350371D01*
G01X1487525Y377514D02*
X1485575Y378420D01*
G01X1477000Y350517D02*
Y347250D01*
G01X1481500Y355017D02*
X1477000Y350517D01*
G01X1481500Y365500D02*
Y355017D01*
G01X1502000Y343750D02*
Y341340D01*
G01X1508975Y391940D02*
X1510925Y391034D01*
G01X1520865Y359187D02*
Y361500D01*
G01X1522043Y358009D02*
X1520865Y359187D01*
G01X1522043Y352696D02*
Y358009D01*
G01X1523000Y351739D02*
X1522043Y352696D01*
G01X1523000Y347250D02*
Y351739D01*
G01X1526525Y381800D02*
X1528475Y380894D01*
G01X1487525Y388560D02*
X1489475Y387654D01*
G01X1518942Y359099D02*
Y361258D01*
G01X1518690Y358847D02*
X1518942Y359099D01*
G01X1518690Y355937D02*
Y358847D01*
G01X1520248Y354379D02*
X1518690Y355937D01*
G01X1520425Y354379D02*
X1520248D01*
G01X1520429D02*
X1520425D01*
G01X1520000Y353954D02*
Y347250D01*
G01X1520425Y354379D02*
X1520000Y353954D01*
G01X1519889Y357338D02*
Y363635D01*
G01X1520158Y357069D02*
X1519889Y357338D01*
G01X1520313Y357069D02*
X1520158D01*
G01X1514825Y402080D02*
X1516775Y401174D01*
G01X1514825Y395320D02*
X1516775Y394414D01*
G01X1510925Y395320D02*
X1512875Y394414D01*
G01X1505500Y384983D02*
X1507025Y384274D01*
G01X1505300Y385076D02*
X1505500Y384983D01*
G01X1505075Y385180D02*
X1505300Y385076D01*
G01X1494656Y359251D02*
Y365457D01*
G01X1493000Y357595D02*
X1494656Y359251D01*
G01X1493000Y347250D02*
Y357595D01*
G01X1527275Y397500D02*
X1526659D01*
G01X1510925Y377514D02*
X1508975Y378420D01*
G01X1474113Y394800D02*
X1473083Y393770D01*
G01X1476434Y394800D02*
X1474113D01*
G01X1476732Y395098D02*
X1476434Y394800D01*
G01X1518111Y363949D02*
X1518000Y364060D01*
G01X1518111Y360970D02*
Y363949D01*
G01X1516960Y359819D02*
X1518111Y360970D01*
G01X1516960Y356080D02*
Y359819D01*
G01X1471220Y378470D02*
X1469330Y380360D01*
G01X1473270Y378470D02*
X1471220D01*
G01X1474150Y379350D02*
X1473270Y378470D01*
G01X1480000Y379350D02*
X1474150D01*
G01X1503878Y364717D02*
Y368287D01*
G01X1508975Y385180D02*
X1510925Y384274D01*
G01X1518725Y402080D02*
X1520675Y401174D01*
G01X1493375Y391940D02*
X1495325Y391034D01*
G01X1476411Y384761D02*
X1474050Y382400D01*
G01X1476411Y385738D02*
Y384761D01*
G01X1475410Y386739D02*
X1476411Y385738D01*
G01X1475410Y387690D02*
Y386739D01*
G01X1476380Y388660D02*
X1475410Y387690D01*
G01X1477833Y388660D02*
X1476380D01*
G01X1478366Y389193D02*
X1477833Y388660D01*
G01X1499225Y377514D02*
X1497275Y378420D01*
G01X1507025Y377514D02*
X1505075Y378420D01*
G01X1514825Y388560D02*
X1516775Y387654D01*
G01X1522625Y395320D02*
X1520675Y394414D01*
G01X1503700Y358850D02*
X1505536Y360686D01*
G01X1503700Y356630D02*
Y358850D01*
G01X1501140Y354070D02*
X1503700Y356630D01*
G01X1501140Y349390D02*
Y354070D01*
G01X1499000Y347250D02*
X1501140Y349390D01*
G01X1516775Y391940D02*
X1518725Y391034D01*
G01X1511000Y347250D02*
Y350627D01*
G01D02*
X1511614Y351241D01*
G01X1499225Y388560D02*
X1501175Y387654D01*
G01X1505500Y391743D02*
X1507025Y391034D01*
G01X1505300Y391836D02*
X1505500Y391743D01*
G01X1505075Y391940D02*
X1505300Y391836D01*
G01X1526000Y349814D02*
Y347250D01*
G01X1525561Y350253D02*
X1526000Y349814D01*
G01X1524114Y360983D02*
Y363985D01*
G01X1523034Y359903D02*
X1524114Y360983D01*
G01X1523034Y353378D02*
Y359903D01*
G01X1525561Y350851D02*
X1523034Y353378D01*
G01X1525561Y350253D02*
Y350851D01*
G01X1493375Y385180D02*
X1495325Y384274D01*
G01X1518725Y377514D02*
X1516775Y378420D01*
G01X1491425Y388560D02*
X1493375Y387654D01*
G01X1509200Y351601D02*
X1510807Y353208D01*
G01X1509200Y348450D02*
Y351601D01*
G01X1508000Y347250D02*
X1509200Y348450D01*
G01X1510925Y397794D02*
X1508975Y398700D01*
G01X1514825Y381800D02*
X1516775Y380894D01*
G01X1507154Y349404D02*
Y353100D01*
G01X1505000Y347250D02*
X1507154Y349404D01*
G01X1522625Y397794D02*
X1520675Y398700D01*
G01X1523000Y341350D02*
Y343750D01*
G01X1485575Y385180D02*
X1487525Y384274D01*
G01X1526525Y462920D02*
X1528475Y463826D01*
G01X1499225Y408840D02*
X1501175Y407934D01*
G01X1497275Y446020D02*
X1499225Y446926D01*
G01X1497749Y412000D02*
X1499225Y411314D01*
G01X1497275Y412220D02*
X1497749Y412000D01*
G01X1521800Y445100D02*
X1523375Y443525D01*
G01X1526525D02*
X1524950Y445100D01*
G01X1526525Y446675D02*
X1524950Y448250D01*
G01X1507625Y446675D02*
X1509200Y448250D01*
G01X1510775Y449825D02*
X1509200Y451400D01*
G01D02*
X1507625Y449825D01*
G01X1497275Y452780D02*
X1499225Y453686D01*
G01X1504600Y408155D02*
X1505075Y407934D01*
G01X1503125Y408840D02*
X1504600Y408155D01*
G01X1497275Y439260D02*
X1499225Y440166D01*
G01X1497162Y418928D02*
X1495325Y418074D01*
G01X1497275Y418980D02*
X1497162Y418928D01*
G01X1507600Y463187D02*
X1508975Y463826D01*
G01X1507025Y462920D02*
X1507600Y463187D01*
G01X1499225Y422360D02*
X1501175Y421454D01*
G01X1497791Y425500D02*
X1499225Y424834D01*
G01X1497319Y425719D02*
X1497791Y425500D01*
G01X1497275Y425740D02*
X1497319Y425719D01*
G01X1510925Y462920D02*
X1512875Y463826D01*
G01X1497275Y405460D02*
X1499225Y404554D01*
G01X1500559Y428500D02*
X1501175Y428214D01*
G01X1500246Y428646D02*
X1500559Y428500D01*
G01X1499904Y428804D02*
X1500246Y428646D01*
G01X1499225Y429120D02*
X1499904Y428804D01*
G01X1505300Y405356D02*
X1507025Y404554D01*
G01X1505075Y405460D02*
X1505300Y405356D01*
G01X1518725Y476440D02*
X1520675Y477346D01*
G01X1511183Y469800D02*
X1512875Y470586D01*
G01X1510925Y469680D02*
X1511183Y469800D01*
G01X1472040Y507160D02*
X1470382Y508818D01*
G01X1473408Y507160D02*
X1472040D01*
G01X1475128Y505440D02*
X1473408Y507160D01*
G01X1475128Y498242D02*
Y505440D01*
G01X1476383Y496987D02*
X1475128Y498242D01*
G01X1476383Y495957D02*
Y496987D01*
G01X1478298Y494042D02*
X1476383Y495957D01*
G01X1478298Y493513D02*
Y494042D01*
G01X1510912Y467200D02*
X1510925Y467206D01*
G01X1508975Y466300D02*
X1510912Y467200D01*
G01X1507012D02*
X1507025Y467206D01*
G01X1505500Y466497D02*
X1507012Y467200D01*
G01X1505300Y466404D02*
X1505500Y466497D01*
G01X1505075Y466300D02*
X1505300Y466404D01*
G01X1514812Y467200D02*
X1514825Y467206D01*
G01X1512875Y466300D02*
X1514812Y467200D01*
G01X1475837Y619171D02*
X1475883Y619217D01*
G01X1475837Y618568D02*
Y619171D01*
G01X1477431Y616974D02*
X1475837Y618568D01*
G01X1477431Y615130D02*
Y616974D01*
G01X1512969Y618291D02*
X1511204Y620056D01*
G01X1512969Y616398D02*
Y618291D01*
G01X1580398Y-600D02*
X1583398D01*
G01X1579367Y431D02*
X1577398D01*
G01X1580398Y-600D02*
X1579367Y431D01*
G01X1580500Y5502D02*
X1580398Y5400D01*
G01X1586547Y5502D02*
X1580500D01*
G01X1579864Y3337D02*
X1583398D01*
G01X1579270Y3931D02*
X1579864Y3337D01*
G01X1577398Y3931D02*
X1579270D01*
G01X1527600Y1000D02*
Y3500D01*
G01X1548400Y2000D02*
X1549800Y3400D01*
G01X1548400Y900D02*
Y2000D01*
G01X1540000Y-2500D02*
X1543500D01*
G01X1540000Y-10000D02*
X1535000Y-15000D01*
G01X1540000Y-2500D02*
Y-10000D01*
G01X1534000Y1000D02*
Y3500D01*
G01X1564400Y2200D02*
X1563200Y3400D01*
G01X1564400Y900D02*
Y2200D01*
G01X1554800Y900D02*
Y3400D01*
G01X1570300Y-6800D02*
X1573300D01*
G01X1575000Y-10900D02*
Y-15000D01*
G01X1573300Y-9200D02*
X1575000Y-10900D01*
G01X1573300Y-6800D02*
Y-9200D01*
G01X1530800Y1000D02*
Y3500D01*
G01X1584000Y-12600D02*
X1589000D01*
G01X1581947Y-10547D02*
X1584000Y-12600D01*
G01X1581947Y-6702D02*
Y-10547D01*
G01X1536074Y-2500D02*
X1534000D01*
G01X1536500Y-2926D02*
X1536074Y-2500D01*
G01X1536500Y-6500D02*
Y-2926D01*
G01X1534000Y-2500D02*
X1530800D01*
G01D02*
X1527600D01*
G01X1579900Y-2569D02*
X1583398D01*
G01X1579400Y-3069D02*
X1579900Y-2569D01*
G01X1577398Y-3069D02*
X1579400D01*
G01X1577398Y-1832D02*
Y-3069D01*
G01X1576972Y-1406D02*
X1577398Y-1832D01*
G01X1571500Y-1406D02*
X1576972D01*
G01X1561200Y2700D02*
X1560500Y3400D01*
G01X1561200Y900D02*
Y2700D01*
G01X1566200Y-2600D02*
X1564400D01*
G01X1568600Y-5000D02*
X1566200Y-2600D01*
G01X1580599Y-5000D02*
X1568600D01*
G01X1581062Y-4537D02*
X1580599Y-5000D01*
G01X1583398Y-4537D02*
X1581062D01*
G01X1558000Y-3800D02*
Y-2600D01*
G01X1558737Y-4537D02*
X1558000Y-3800D01*
G01X1562737Y-4537D02*
X1558737D01*
G01X1565000Y-6800D02*
X1562737Y-4537D01*
G01X1566800Y-6800D02*
X1565000D01*
G01X1561200Y-2600D02*
X1564400D01*
G01X1558000D02*
X1561200D01*
G01X1554300Y-6200D02*
X1551300D01*
G01X1555000Y-10400D02*
Y-15000D01*
G01X1554300Y-9700D02*
X1555000Y-10400D01*
G01X1554300Y-6200D02*
Y-9700D01*
G01X1589000Y-16100D02*
X1586500D01*
G01X1579985Y1369D02*
X1583398D01*
G01X1579154Y2200D02*
X1579985Y1369D01*
G01X1572692Y2200D02*
X1579154D01*
G01X1569729Y5163D02*
X1572692Y2200D01*
G01X1566300Y3100D02*
X1566000Y3400D01*
G01X1566300Y-700D02*
Y3100D01*
G01X1568669Y-3069D02*
X1566300Y-700D01*
G01X1573898Y-3069D02*
X1568669D01*
G01X1551600Y2700D02*
X1552300Y3400D01*
G01X1551600Y900D02*
Y2700D01*
G01X1543500Y1000D02*
Y3400D01*
G01X1571969Y431D02*
X1569000Y3400D01*
G01X1573898Y431D02*
X1571969D01*
G01X1554800Y-3800D02*
Y-2600D01*
G01X1555400Y-4400D02*
X1554800Y-3800D01*
G01X1557044Y-4400D02*
X1555400D01*
G01X1557800Y-5156D02*
X1557044Y-4400D01*
G01X1557800Y-6200D02*
Y-5156D01*
G01X1554800Y-2600D02*
X1551600D01*
G01D02*
X1548400D01*
G01X1546900D02*
X1548400D01*
G01X1546599Y-2299D02*
X1546900Y-2600D01*
G01X1546599Y3199D02*
Y-2299D01*
G01X1546800Y3400D02*
X1546599Y3199D01*
G01X1558000Y900D02*
Y3400D01*
G01X1572517Y3931D02*
X1573898D01*
G01X1567548Y8900D02*
X1572517Y3931D01*
G01X1540000Y1000D02*
Y3400D01*
G01X1584447Y-6702D02*
X1586547D01*
G01X1533000Y-6500D02*
X1528500D01*
G01Y-7700D02*
Y-6500D01*
G01X1574780Y90992D02*
X1570923Y94849D01*
G01X1582500Y92500D02*
Y94500D01*
G01X1584500Y90500D02*
X1582500Y92500D01*
G01X1586500Y90500D02*
X1584500D01*
G01X1586500Y94500D02*
X1588021Y96021D01*
G01X1586500Y85207D02*
X1587359Y84348D01*
G01X1586500Y87000D02*
Y85207D01*
G01X1572978Y91190D02*
X1568702Y95466D01*
G01X1572978Y90381D02*
Y91190D01*
G01X1580823Y82536D02*
X1572978Y90381D01*
G01X1582157Y82536D02*
X1580823D01*
G01X1583374Y81319D02*
X1582157Y82536D01*
G01X1558145Y94418D02*
X1557679Y94800D01*
G01X1559481Y87705D02*
X1558145Y94418D01*
G01X1562162Y83695D02*
X1559481Y87705D01*
G01X1574309Y76691D02*
X1562162Y83695D01*
G01X1581761Y69239D02*
X1574309Y76691D01*
G01X1584192Y69239D02*
X1581761D01*
G01X1590356Y63075D02*
X1584192Y69239D01*
G01X1579292Y131104D02*
X1579290D01*
G01X1579292Y131465D02*
Y131104D01*
G01X1580365Y132538D02*
X1579292Y131465D01*
G01X1581810Y132538D02*
X1580365D01*
G01X1584900Y109030D02*
X1588930D01*
G01X1580890Y105020D02*
X1584900Y109030D01*
G01X1577928Y102058D02*
X1580890Y105020D01*
G01X1573506Y102058D02*
X1577928D01*
G01X1570923Y99475D02*
X1573506Y102058D01*
G01X1570923Y94849D02*
Y99475D01*
G01X1582508Y115679D02*
X1584183D01*
G01X1582502Y115685D02*
X1582508Y115679D01*
G01X1580920Y115685D02*
X1582502D01*
G01X1585846Y115679D02*
X1584183D01*
G01X1585856Y115669D02*
X1585846Y115679D01*
G01X1587222Y115669D02*
X1585856D01*
G01X1589800D02*
X1587222D01*
G01X1585750Y149600D02*
X1589305D01*
G01X1585750Y151940D02*
Y149600D01*
G01X1581995Y155695D02*
X1585750Y151940D01*
G01X1576646Y161044D02*
X1581995Y155695D01*
G01X1541821Y126067D02*
X1542000Y126246D01*
G01X1536801Y126067D02*
X1541821D01*
G01X1588683Y123613D02*
X1591439D01*
G01X1586100Y121030D02*
X1588683Y123613D01*
G01X1579680Y121030D02*
X1586100D01*
G01X1579410Y120760D02*
X1579680Y121030D01*
G01X1585500Y94500D02*
X1582500D01*
G01X1588021Y96021D02*
X1591478D01*
G01X1585500Y94500D02*
X1586500D01*
G01X1581190Y108590D02*
X1582500Y109900D01*
G01X1577200Y108590D02*
X1581190D01*
G01X1584183Y111583D02*
Y112179D01*
G01X1582500Y109900D02*
X1584183Y111583D01*
G01X1540346Y122130D02*
X1536801D01*
G01X1541068Y121408D02*
X1540346Y122130D01*
G01X1541068Y120232D02*
Y121408D01*
G01X1542100Y119200D02*
X1541068Y120232D01*
G01X1584963Y154596D02*
Y156782D01*
G01X1588859Y150700D02*
X1584963Y154596D01*
G01X1573874Y140959D02*
Y143959D01*
G01X1588150Y140550D02*
X1592816D01*
G01X1585824Y138224D02*
X1588150Y140550D01*
G01X1577273Y138224D02*
X1585824D01*
G01X1574538Y140959D02*
X1577273Y138224D01*
G01X1573874Y140959D02*
X1574538D01*
G01X1568702Y102851D02*
X1570023Y104172D01*
G01X1568702Y95466D02*
Y102851D01*
G01X1572395Y106544D02*
Y110754D01*
G01X1570023Y104172D02*
X1572395Y106544D01*
G01X1533021Y133941D02*
X1531678Y135284D01*
G01X1536801Y133941D02*
X1533021D01*
G01X1588439Y154572D02*
X1586547Y156464D01*
G01X1569333Y140959D02*
X1567981Y139607D01*
G01X1570374Y140959D02*
X1569333D01*
G01X1540502Y124098D02*
X1536801D01*
G01X1542900Y121700D02*
X1540502Y124098D01*
G01X1588575Y139525D02*
X1587664Y138614D01*
G01X1594725Y139525D02*
X1588575D01*
G01X1573892Y137921D02*
X1573854Y137959D01*
G01X1573892Y134959D02*
Y137921D01*
G01X1576032Y137959D02*
X1573854D01*
G01X1576692Y137299D02*
X1576032Y137959D01*
G01X1586349Y137299D02*
X1576692D01*
G01X1587664Y138614D02*
X1586349Y137299D01*
G01X1569245Y137959D02*
X1570354D01*
G01X1567968Y136682D02*
X1569245Y137959D01*
G01X1585310Y128100D02*
Y129538D01*
G01X1584070Y126860D02*
X1585310Y128100D01*
G01X1578441Y126860D02*
X1584070D01*
G01X1576891Y128410D02*
X1578441Y126860D01*
G01X1576731Y128410D02*
X1576891D01*
G01X1588510Y130663D02*
X1597837D01*
G01X1586435D02*
X1588510D01*
G01X1585310Y129538D02*
X1586435Y130663D01*
G01X1539492Y135909D02*
X1536801D01*
G01X1540820Y134581D02*
X1539492Y135909D01*
G01X1540820Y133954D02*
Y134581D01*
G01X1541453Y133321D02*
X1540820Y133954D01*
G01X1542685Y133321D02*
X1541453D01*
G01X1586048Y131800D02*
X1585310Y132538D01*
G01X1593420Y131800D02*
X1586048D01*
G01X1585000Y134100D02*
Y135538D01*
G01X1585310Y133790D02*
X1585000Y134100D01*
G01X1585310Y132538D02*
Y133790D01*
G01X1580244Y129538D02*
X1579310Y128604D01*
G01X1581810Y129538D02*
X1580244D01*
G01X1557679Y94800D02*
X1556200D01*
G01X1581700Y217095D02*
Y215770D01*
G01X1581275Y217520D02*
X1581700Y217095D01*
G01X1577096Y217520D02*
X1581275D01*
G01X1572271Y222345D02*
X1577096Y217520D01*
G01X1588599Y169038D02*
X1592122D01*
G01X1578005Y228302D02*
X1589274Y217033D01*
G01X1572920Y195920D02*
X1567299D01*
G01X1573750Y196750D02*
X1572920Y195920D01*
G01X1579000Y196750D02*
X1573750D01*
G01X1588599Y165801D02*
Y164538D01*
G01X1587900Y166500D02*
X1588599Y165801D01*
G01X1582667Y166500D02*
X1587900D01*
G01X1577311Y171856D02*
X1582667Y166500D01*
G01X1571665Y171856D02*
X1577311D01*
G01X1569244Y169435D02*
X1571665Y171856D01*
G01X1561055Y169435D02*
X1569244D01*
G01X1558042Y172448D02*
X1561055Y169435D01*
G01X1567841Y161044D02*
X1576646D01*
G01X1563309Y165576D02*
X1567841Y161044D01*
G01X1559944Y165576D02*
X1563309D01*
G01X1554022Y171498D02*
X1559944Y165576D01*
G01X1554010Y171498D02*
X1554022D01*
G01X1554010Y171510D02*
Y171498D01*
G01X1554009Y171511D02*
X1554010Y171510D01*
G01X1554009Y172277D02*
Y171511D01*
G01X1554010Y172278D02*
X1554009Y172277D01*
G01X1554010Y173053D02*
Y172278D01*
G01X1549235Y177828D02*
X1554010Y173053D01*
G01X1543447Y177828D02*
X1549235D01*
G01X1538193Y183082D02*
X1543447Y177828D01*
G01X1535000Y207200D02*
X1533700Y208500D01*
G01X1529699Y187700D02*
X1529199Y188200D01*
G01X1529699Y185920D02*
Y187700D01*
G01X1575996Y178750D02*
X1579000D01*
G01X1571716Y183030D02*
X1575996Y178750D01*
G01X1563630Y183030D02*
X1571716D01*
G01X1558160Y188500D02*
X1563630Y183030D01*
G01X1558160Y188663D02*
Y188500D01*
G01X1557979Y188844D02*
X1558160Y188663D01*
G01X1588500Y187229D02*
X1591361Y190090D01*
G01X1588500Y180500D02*
Y187229D01*
G01X1586006Y178006D02*
X1588500Y180500D01*
G01X1581993Y178006D02*
X1586006D01*
G01X1580443Y176456D02*
X1581993Y178006D01*
G01X1572672Y176456D02*
X1580443D01*
G01X1572671Y176457D02*
X1572672Y176456D01*
G01X1570687Y176457D02*
X1572671D01*
G01X1567609Y173379D02*
X1570687Y176457D01*
G01X1566053Y173379D02*
X1567609D01*
G01X1551718Y187714D02*
X1566053Y173379D01*
G01X1551718Y193546D02*
Y187714D01*
G01X1554548Y196376D02*
X1551718Y193546D01*
G01X1554548Y207697D02*
Y196376D01*
G01X1533573Y228672D02*
X1554548Y207697D01*
G01X1585201Y170800D02*
Y172162D01*
G01X1585099Y170698D02*
X1585201Y170800D01*
G01X1585099Y169038D02*
Y170698D01*
G01X1586461Y167375D02*
X1589325D01*
G01X1585099Y168737D02*
X1586461Y167375D01*
G01X1585099Y169038D02*
Y168737D01*
G01X1553000Y164500D02*
Y162900D01*
G01X1553500Y165000D02*
X1553000Y164500D01*
G01X1553500Y165400D02*
Y165000D01*
G01X1565102Y171085D02*
X1561538Y174649D01*
G01X1568560Y171085D02*
X1565102D01*
G01X1571637Y174162D02*
X1568560Y171085D01*
G01X1581542Y174162D02*
X1571637D01*
G01X1582690Y175310D02*
X1581542Y174162D01*
G01X1586555Y175310D02*
X1582690D01*
G01X1591500Y180255D02*
X1586555Y175310D01*
G01X1576830Y215770D02*
X1571680Y220920D01*
G01X1578200Y215770D02*
X1576830D01*
G01X1553000Y157500D02*
X1553500Y157000D01*
G01X1553000Y159400D02*
Y157500D01*
G01X1584963Y156782D02*
X1580377Y161368D01*
G01X1543947Y178753D02*
X1538693Y184007D01*
G01X1549619Y178753D02*
X1543947D01*
G01X1554935Y173437D02*
X1549619Y178753D01*
G01X1554935Y171894D02*
Y173437D01*
G01X1560190Y166639D02*
X1554935Y171894D01*
G01X1563555Y166639D02*
X1560190D01*
G01X1568224Y161970D02*
X1563555Y166639D01*
G01X1573119Y161970D02*
X1568224D01*
G01X1574500Y163351D02*
X1573119Y161970D01*
G01X1578394Y163351D02*
X1574500D01*
G01X1580377Y161368D02*
X1578394Y163351D01*
G01X1547663Y197631D02*
X1552063Y202031D01*
G01X1547663Y193242D02*
Y197631D01*
G01X1546022Y191601D02*
X1547663Y193242D01*
G01X1546022Y184931D02*
Y191601D01*
G01X1556760Y174193D02*
X1546022Y184931D01*
G01X1556760Y174142D02*
Y174193D01*
G01X1556776Y174126D02*
X1556760Y174142D01*
G01X1559512Y174126D02*
X1556776D01*
G01X1563378Y170260D02*
X1559512Y174126D01*
G01X1568902Y170260D02*
X1563378D01*
G01X1571578Y172936D02*
X1568902Y170260D01*
G01X1581548Y172936D02*
X1571578D01*
G01X1582437Y173825D02*
X1581548Y172936D01*
G01X1587874Y173825D02*
X1582437D01*
G01X1588701Y172998D02*
X1587874Y173825D01*
G01X1588701Y172162D02*
Y172998D01*
G01X1588176Y157600D02*
X1591736Y161160D01*
G01X1588501Y161362D02*
X1589686Y162547D01*
G01X1588501Y160877D02*
Y161362D01*
G01X1586547Y158923D02*
X1588501Y160877D01*
G01X1586547Y156464D02*
Y158923D01*
G01X1535301Y210109D02*
Y223699D01*
G01X1541000Y204410D02*
X1535301Y210109D01*
G01X1541000Y183009D02*
Y204410D01*
G01X1544256Y179753D02*
X1541000Y183009D01*
G01X1550033Y179753D02*
X1544256D01*
G01X1555935Y173851D02*
X1550033Y179753D01*
G01X1555935Y172203D02*
Y173851D01*
G01X1560179Y167959D02*
X1555935Y172203D01*
G01X1566939Y167959D02*
X1560179D01*
G01X1569478Y165420D02*
X1566939Y167959D01*
G01X1577634Y165420D02*
X1569478D01*
G01X1578516Y164538D02*
X1577634Y165420D01*
G01X1585099Y164538D02*
X1578516D01*
G01X1585099Y163100D02*
Y164538D01*
G01X1585001Y163002D02*
X1585099Y163100D01*
G01X1585001Y161362D02*
Y163002D01*
G01X1539200Y202700D02*
X1538500Y203400D01*
G01X1539200Y192322D02*
Y202700D01*
G01X1538578Y191700D02*
X1539200Y192322D01*
G01X1537697Y191700D02*
X1538578D01*
G01X1537075Y192322D02*
X1537697Y191700D01*
G01X1537075Y198078D02*
Y192322D01*
G01X1536453Y198700D02*
X1537075Y198078D01*
G01X1535572Y198700D02*
X1536453D01*
G01X1534950Y198078D02*
X1535572Y198700D01*
G01X1534950Y193850D02*
Y198078D01*
G01X1534400Y193300D02*
X1534950Y193850D01*
G01X1530425Y193300D02*
X1534400D01*
G01X1529699Y192574D02*
X1530425Y193300D01*
G01X1529699Y190920D02*
Y192574D01*
G01X1578200Y208700D02*
Y210770D01*
G01X1581068Y205832D02*
X1578200Y208700D01*
G01X1584632Y205832D02*
X1581068D01*
G01X1588000Y209200D02*
X1584632Y205832D01*
G01X1588000Y216291D02*
Y209200D01*
G01X1584621Y219670D02*
X1588000Y216291D01*
G01X1569780Y215920D02*
X1567299D01*
G01X1574930Y210770D02*
X1569780Y215920D01*
G01X1578200Y210770D02*
X1574930D01*
G01X1584700Y203400D02*
X1593020Y211720D01*
G01X1559700Y203400D02*
X1584700D01*
G01X1558000Y205100D02*
X1559700Y203400D01*
G01X1578330Y185920D02*
X1579000Y185250D01*
G01X1567299Y185920D02*
X1578330D01*
G01X1579000Y185250D02*
Y182250D01*
G01X1572245Y222345D02*
X1572271D01*
G01X1570540Y224050D02*
X1572245Y222345D01*
G01X1541440Y224050D02*
X1570540D01*
G01X1534524Y230966D02*
X1541440Y224050D01*
G01X1578005Y240864D02*
Y228302D01*
G01X1576038Y242831D02*
X1578005Y240864D01*
G01X1570051Y242831D02*
X1576038D01*
G01X1565762Y238542D02*
X1570051Y242831D01*
G01X1565762Y231688D02*
Y238542D01*
G01X1562012Y227938D02*
X1565762Y231688D01*
G01X1546034Y227938D02*
X1562012D01*
G01X1537972Y236000D02*
X1546034Y227938D01*
G01X1537972Y236000D02*
X1534322Y239650D01*
G01X1542212Y238388D02*
X1538014Y242586D01*
G01X1543717Y238388D02*
X1542212D01*
G01X1545802Y236303D02*
X1543717Y238388D01*
G01X1545802Y233529D02*
Y236303D01*
G01X1561000Y258900D02*
Y260400D01*
G01X1557400Y255300D02*
X1561000Y258900D01*
G01X1554400Y255300D02*
X1557400D01*
G01X1571876Y259194D02*
Y255800D01*
G01X1569590Y261480D02*
X1571876Y259194D01*
G01X1562080Y261480D02*
X1569590D01*
G01X1561000Y260400D02*
X1562080Y261480D01*
G01X1542860Y226088D02*
X1532685Y236263D01*
G01X1563844Y226088D02*
X1542860D01*
G01X1572730Y234974D02*
X1563844Y226088D01*
G01X1572730Y235931D02*
Y234974D01*
G01X1571680Y220920D02*
X1567299D01*
G01X1543244Y227013D02*
X1533069Y237188D01*
G01X1562396Y227013D02*
X1543244D01*
G01X1570272Y234889D02*
X1562396Y227013D01*
G01X1557500Y262511D02*
Y260400D01*
G01X1555480Y264531D02*
X1557500Y262511D01*
G01X1550750Y264531D02*
X1555480D01*
G01X1535301Y223699D02*
X1532622Y226378D01*
G01X1577323Y219670D02*
X1584621D01*
G01X1576000Y220993D02*
X1577323Y219670D01*
G01X1576000Y223210D02*
Y220993D01*
G01X1575608Y223602D02*
X1576000Y223210D01*
G01X1574422Y223602D02*
X1575608D01*
G01X1573800Y224224D02*
X1574422Y223602D01*
G01X1573800Y225105D02*
Y224224D01*
G01X1574422Y225727D02*
X1573800Y225105D01*
G01X1576215Y225727D02*
X1574422D01*
G01X1576837Y226349D02*
X1576215Y225727D01*
G01X1576837Y227230D02*
Y226349D01*
G01X1576215Y227852D02*
X1576837Y227230D01*
G01X1572822Y227852D02*
X1576215D01*
G01X1572300Y228374D02*
X1572822Y227852D01*
G01X1572300Y229399D02*
Y228374D01*
G01X1572878Y229977D02*
X1572300Y229399D01*
G01X1576155Y229977D02*
X1572878D01*
G01X1576580Y230402D02*
X1576155Y229977D01*
G01X1576580Y239220D02*
Y230402D01*
G01X1574900Y240900D02*
X1576580Y239220D01*
G01X1574560Y234270D02*
Y237660D01*
G01X1565265Y224975D02*
X1574560Y234270D01*
G01X1541824Y224975D02*
X1565265D01*
G01X1534908Y231891D02*
X1541824Y224975D01*
G01X1559301Y335000D02*
X1560500D01*
G01X1558640Y335661D02*
X1559301Y335000D01*
G01X1558640Y339838D02*
Y335661D01*
G01X1559213Y340411D02*
X1558640Y339838D01*
G01X1559213Y341789D02*
Y340411D01*
G01X1558730Y283070D02*
X1593513D01*
G01X1556710Y285090D02*
X1558730Y283070D01*
G01X1556710Y286844D02*
Y285090D01*
G01X1557667Y287801D02*
X1556710Y286844D01*
G01X1561432Y287801D02*
X1557667D01*
G01X1562070Y288439D02*
X1561432Y287801D01*
G01X1562070Y292930D02*
Y288439D01*
G01X1561335Y293665D02*
X1562070Y292930D01*
G01X1551527Y293665D02*
X1561335D01*
G01X1550800Y294392D02*
X1551527Y293665D01*
G01X1550800Y296200D02*
Y294392D01*
G01X1550389Y306057D02*
X1544472D01*
G01X1551672Y307340D02*
X1550389Y306057D01*
G01X1552456Y307340D02*
X1551672D01*
G01X1554025Y308909D02*
X1552456Y307340D01*
G01X1552913Y324987D02*
X1552000Y325900D01*
G01X1552913Y316988D02*
Y324987D01*
G01X1550500Y314575D02*
X1552913Y316988D01*
G01X1550500Y313102D02*
Y314575D01*
G01X1548761Y311363D02*
X1550500Y313102D01*
G01X1547383Y311363D02*
X1548761D01*
G01X1546587Y312159D02*
X1547383Y311363D01*
G01X1546587Y316504D02*
Y312159D01*
G01X1543316Y319775D02*
X1546587Y316504D01*
G01X1542356Y319775D02*
X1543316D01*
G01X1538002Y324129D02*
X1542356Y319775D01*
G01X1536572Y324129D02*
X1538002D01*
G01X1528055Y332646D02*
X1536572Y324129D01*
G01X1548515Y333823D02*
X1547398D01*
G01X1549900Y332438D02*
X1548515Y333823D01*
G01X1549900Y329613D02*
Y332438D01*
G01X1552000Y327513D02*
X1549900Y329613D01*
G01X1552000Y325900D02*
Y327513D01*
G01X1569638Y340062D02*
X1566850Y342850D01*
G01X1574290Y340062D02*
X1569638D01*
G01X1575613Y338739D02*
X1574290Y340062D01*
G01X1575613Y329122D02*
Y338739D01*
G01X1569917Y323426D02*
X1575613Y329122D01*
G01X1568581Y323426D02*
X1569917D01*
G01X1568581Y320786D02*
Y323426D01*
G01X1570124Y319243D02*
X1568581Y320786D01*
G01X1570124Y315850D02*
Y319243D01*
G01X1570688Y315286D02*
X1570124Y315850D01*
G01X1574081Y315286D02*
X1570688D01*
G01X1574497Y314870D02*
X1574081Y315286D01*
G01X1574497Y306948D02*
Y314870D01*
G01X1579400Y302045D02*
X1574497Y306948D01*
G01X1579400Y300900D02*
Y302045D01*
G01X1582637Y297663D02*
X1579400Y300900D01*
G01X1582989Y297663D02*
X1582637D01*
G01X1584200Y296452D02*
X1582989Y297663D01*
G01X1584200Y291033D02*
Y296452D01*
G01X1581597Y288430D02*
X1584200Y291033D01*
G01X1573300Y288430D02*
X1581597D01*
G01X1572377Y287507D02*
X1573300Y288430D01*
G01X1572377Y287104D02*
Y287507D01*
G01X1572336Y287063D02*
X1572377Y287104D01*
G01X1550700Y298500D02*
X1553750D01*
G01X1548017Y295817D02*
X1550700Y298500D01*
G01X1544472Y295817D02*
X1548017D01*
G01X1543957Y342207D02*
Y340823D01*
G01X1548000Y285400D02*
Y283250D01*
G01X1548400Y285800D02*
X1548000Y285400D01*
G01X1548400Y285830D02*
Y285800D01*
G01X1548199Y285830D02*
X1548400D01*
G01X1541476Y324600D02*
X1542200D01*
G01X1539597Y326479D02*
X1541476Y324600D01*
G01X1537547Y326479D02*
X1539597D01*
G01X1529029Y334997D02*
X1537547Y326479D01*
G01X1527581Y334997D02*
X1529029D01*
G01X1527580Y334996D02*
X1527581Y334997D01*
G01X1581000Y326000D02*
X1581941D01*
G01X1579250Y327750D02*
X1581000Y326000D01*
G01X1577500Y327750D02*
X1579250D01*
G01X1577500Y330750D02*
Y327750D01*
G01X1576596D02*
X1577500D01*
G01X1572588Y323742D02*
X1576596Y327750D01*
G01X1572588Y322014D02*
Y323742D01*
G01X1558506Y308909D02*
X1557525D01*
G01X1559914Y310317D02*
X1558506Y308909D01*
G01X1559997Y310317D02*
X1559914D01*
G01X1528337Y340143D02*
Y341837D01*
G01X1529344Y339136D02*
X1528337Y340143D01*
G01X1531864Y339136D02*
X1529344D01*
G01X1538274Y332726D02*
X1531864Y339136D01*
G01X1539802Y332726D02*
X1538274D01*
G01X1543578Y328950D02*
X1539802Y332726D01*
G01X1544650Y328950D02*
X1543578D01*
G01X1546200Y327400D02*
X1544650Y328950D01*
G01X1546200Y323969D02*
Y327400D01*
G01X1548024Y322145D02*
X1546200Y323969D01*
G01X1559000Y298500D02*
X1557250D01*
G01X1559500Y299000D02*
X1559000Y298500D01*
G01X1559500Y304001D02*
Y299000D01*
G01X1563882Y308383D02*
X1559500Y304001D01*
G01X1564400Y308383D02*
X1563882D01*
G01X1538500Y340900D02*
X1538000Y341400D01*
G01X1538500Y336843D02*
Y340900D01*
G01X1539683Y335660D02*
X1538500Y336843D01*
G01X1540900Y335660D02*
X1539683D01*
G01X1544760Y331800D02*
X1540900Y335660D01*
G01X1547561Y331800D02*
X1544760D01*
G01X1548000Y331361D02*
X1547561Y331800D01*
G01X1584500Y337875D02*
Y333000D01*
G01X1584218Y338157D02*
X1584500Y337875D01*
G01X1584218Y338433D02*
Y338157D01*
G01X1583884Y338767D02*
X1584218Y338433D01*
G01X1583794Y338767D02*
X1583884D01*
G01X1584500Y330000D02*
Y333000D01*
G01X1585250Y329250D02*
X1584500Y330000D01*
G01X1591500Y329250D02*
X1585250D01*
G01X1565940Y309750D02*
X1567500D01*
G01X1564616Y311074D02*
X1565940Y309750D01*
G01X1564436Y311074D02*
X1564616D01*
G01X1564427Y311083D02*
X1564436Y311074D01*
G01X1564426Y311084D02*
X1564427Y311083D01*
G01X1561706Y311084D02*
X1564426D01*
G01X1559980Y312810D02*
X1561706Y311084D01*
G01X1559980Y317620D02*
Y312810D01*
G01X1569164Y309750D02*
X1567500D01*
G01X1571914Y312500D02*
X1569164Y309750D01*
G01X1573000Y312500D02*
X1571914D01*
G01X1555061Y317620D02*
X1559980D01*
G01X1551425Y313984D02*
X1555061Y317620D01*
G01X1551425Y312718D02*
Y313984D01*
G01X1549145Y310438D02*
X1551425Y312718D01*
G01X1546999Y310438D02*
X1549145D01*
G01X1545662Y311775D02*
X1546999Y310438D01*
G01X1545662Y316120D02*
Y311775D01*
G01X1543082Y318700D02*
X1545662Y316120D01*
G01X1540252Y318700D02*
X1543082D01*
G01X1540089Y318537D02*
X1540252Y318700D01*
G01X1538711Y318537D02*
X1540089D01*
G01X1538685Y318563D02*
X1538711Y318537D01*
G01X1538642Y318563D02*
X1538685D01*
G01X1536805Y320400D02*
X1538642Y318563D01*
G01X1532357Y320400D02*
X1536805D01*
G01X1531565Y321192D02*
X1532357Y320400D01*
G01X1531565Y323955D02*
Y321192D01*
G01X1530573Y324947D02*
X1531565Y323955D01*
G01X1533829Y296029D02*
X1534400D01*
G01X1531726Y293926D02*
X1533829Y296029D01*
G01X1531726Y291926D02*
Y293926D01*
G01X1528900Y289100D02*
X1531726Y291926D01*
G01X1575645Y319149D02*
Y320664D01*
G01X1575220Y318724D02*
X1575645Y319149D01*
G01X1571649Y318724D02*
X1575220D01*
G01X1571224Y318299D02*
X1571649Y318724D01*
G01X1571224Y317500D02*
Y318299D01*
G01X1571649Y317075D02*
X1571224Y317500D01*
G01X1575220Y317075D02*
X1571649D01*
G01X1575645Y316650D02*
X1575220Y317075D01*
G01X1575645Y315171D02*
Y316650D01*
G01X1576897Y313919D02*
X1575645Y315171D01*
G01X1576897Y313317D02*
Y313919D01*
G01X1575853Y312273D02*
X1576897Y313317D01*
G01X1575853Y311671D02*
Y312273D01*
G01X1576454Y311070D02*
X1575853Y311671D01*
G01X1577056Y311070D02*
X1576454D01*
G01X1580120Y314134D02*
X1577056Y311070D01*
G01X1580722Y314134D02*
X1580120D01*
G01X1581323Y313533D02*
X1580722Y314134D01*
G01X1581323Y312931D02*
Y313533D01*
G01X1578259Y309867D02*
X1581323Y312931D01*
G01X1578259Y309265D02*
Y309867D01*
G01X1578860Y308664D02*
X1578259Y309265D01*
G01X1579462Y308664D02*
X1578860D01*
G01X1580503Y309705D02*
X1579462Y308664D01*
G01X1581119Y309705D02*
X1580503D01*
G01X1581800Y309024D02*
X1581119Y309705D01*
G01X1581800Y303924D02*
Y309024D01*
G01X1581375Y303499D02*
X1581800Y303924D01*
G01X1580953Y303499D02*
X1581375D01*
G01X1580528Y303074D02*
X1580953Y303499D01*
G01X1580528Y302224D02*
Y303074D01*
G01X1580953Y301799D02*
X1580528Y302224D01*
G01X1581375Y301799D02*
X1580953D01*
G01X1581800Y301374D02*
X1581375Y301799D01*
G01X1581800Y299809D02*
Y301374D01*
G01X1583021Y298588D02*
X1581800Y299809D01*
G01X1583373Y298588D02*
X1583021D01*
G01X1585125Y296836D02*
X1583373Y298588D01*
G01X1585125Y295547D02*
Y296836D01*
G01X1591622Y289050D02*
X1585125Y295547D01*
G01X1587185Y291081D02*
X1590369Y287897D01*
G01X1586583Y291081D02*
X1587185D01*
G01X1585982Y290480D02*
X1586583Y291081D01*
G01X1585982Y289878D02*
Y290480D01*
G01X1589795Y286065D02*
X1585982Y289878D01*
G01X1560500Y343750D02*
Y338500D01*
G01X1573500D02*
X1573950Y338050D01*
G01X1560500Y338500D02*
X1573500D01*
G01X1585300Y302701D02*
X1586385Y301616D01*
G01X1585300Y311721D02*
Y302701D01*
G01X1588549Y314970D02*
X1585300Y311721D01*
G01X1588549Y316114D02*
Y314970D01*
G01X1589523Y317088D02*
X1588549Y316114D01*
G01X1583491Y343782D02*
X1594006Y333267D01*
G01X1587400Y300601D02*
X1586385Y301616D01*
G01X1587400Y294759D02*
Y300601D01*
G01X1606856Y275303D02*
X1587400Y294759D01*
G01X1577500Y340400D02*
X1576500Y341400D01*
G01X1577500Y334250D02*
Y340400D01*
G01X1556500Y340050D02*
X1557550Y341100D01*
G01X1556500Y338250D02*
Y340050D01*
G01X1557550Y341100D02*
X1556500Y342150D01*
G01X1547800Y316600D02*
X1549000D01*
G01X1543700Y320700D02*
X1547800Y316600D01*
G01X1542740Y320700D02*
X1543700D01*
G01X1538386Y325054D02*
X1542740Y320700D01*
G01X1536956Y325054D02*
X1538386D01*
G01X1528439Y333571D02*
X1536956Y325054D01*
G01X1572331Y328553D02*
Y331926D01*
G01X1571232Y327454D02*
X1572331Y328553D01*
G01X1568422Y327454D02*
X1571232D01*
G01X1566918Y325950D02*
X1568422Y327454D01*
G01X1566918Y318782D02*
Y325950D01*
G01X1568970Y316730D02*
X1566918Y318782D01*
G01X1568970Y313331D02*
Y316730D01*
G01X1568524Y312885D02*
X1568970Y313331D01*
G01X1581370Y284531D02*
X1594084D01*
G01X1581077Y284824D02*
X1581370Y284531D01*
G01X1581077Y284825D02*
Y284824D01*
G01X1588600Y294726D02*
X1607198Y276128D01*
G01X1588600Y305000D02*
Y294726D01*
G01X1586125Y307475D02*
X1588600Y305000D01*
G01X1586125Y309894D02*
Y307475D01*
G01X1588322Y312091D02*
X1586125Y309894D01*
G01X1589517Y312091D02*
X1588322D01*
G01X1540957Y340981D02*
Y340823D01*
G01X1542500Y342524D02*
X1540957Y340981D01*
G01X1557250Y302813D02*
Y301500D01*
G01X1556599Y303464D02*
X1557250Y302813D01*
G01X1551405Y303464D02*
X1556599D01*
G01X1551028Y303087D02*
X1551405Y303464D01*
G01X1550619Y303087D02*
X1551028D01*
G01X1564831Y329230D02*
Y331926D01*
G01X1563902Y328301D02*
X1564831Y329230D01*
G01X1560923Y328301D02*
X1563902D01*
G01X1560024Y329200D02*
X1560923Y328301D01*
G01X1548231Y303497D02*
X1544472D01*
G01X1549830Y305096D02*
X1548231Y303497D01*
G01X1550065Y305096D02*
X1549830D01*
G01X1550068Y305099D02*
X1550065Y305096D01*
G01X1550598Y305099D02*
X1550068D01*
G01X1550999Y305500D02*
X1550598Y305099D01*
G01X1553750Y305500D02*
X1550999D01*
G01X1536100Y336916D02*
Y339000D01*
G01X1538864Y334152D02*
X1536100Y336916D01*
G01X1540392Y334152D02*
X1538864D01*
G01X1544169Y330375D02*
X1540392Y334152D01*
G01X1545416Y330375D02*
X1544169D01*
G01X1545806Y329985D02*
X1545416Y330375D01*
G01X1545815Y329985D02*
X1545806D01*
G01X1548334Y327466D02*
X1545815Y329985D01*
G01X1548334Y325497D02*
Y327466D01*
G01X1536100Y341100D02*
Y339000D01*
G01X1535000Y342200D02*
X1536100Y341100D01*
G01X1558217Y305500D02*
X1557250D01*
G01X1560400Y307683D02*
X1558217Y305500D01*
G01X1580600Y292730D02*
X1578790Y290920D01*
G01X1580600Y294808D02*
Y292730D01*
G01X1580277Y295131D02*
X1580600Y294808D01*
G01X1580277Y296509D02*
Y295131D01*
G01X1580600Y296832D02*
X1580277Y296509D01*
G01X1580600Y297500D02*
Y296832D01*
G01X1578600Y299500D02*
X1580600Y297500D01*
G01X1577500Y299500D02*
X1578600D01*
G01X1577500Y302000D02*
Y299500D01*
G01X1576000Y303500D02*
X1577500Y302000D01*
G01X1573000Y303500D02*
X1576000D01*
G01X1577107Y291724D02*
X1574447D01*
G01X1577911Y290920D02*
X1577107Y291724D01*
G01X1578790Y290920D02*
X1577911D01*
G01X1565947Y288847D02*
Y287974D01*
G01X1567230Y290130D02*
X1565947Y288847D01*
G01X1567230Y291610D02*
Y290130D01*
G01X1565450Y293390D02*
X1567230Y291610D01*
G01X1563664Y293390D02*
X1565450D01*
G01X1563034Y294020D02*
X1563664Y293390D01*
G01X1563034Y299466D02*
Y294020D01*
G01X1562000Y300500D02*
X1563034Y299466D01*
G01X1562000Y303000D02*
Y300500D01*
G01X1563750Y306250D02*
X1567500D01*
G01X1562000Y304500D02*
X1563750Y306250D01*
G01X1562000Y303000D02*
Y304500D01*
G01X1547651Y339746D02*
Y341751D01*
G01X1548477Y298377D02*
X1544472D01*
G01X1551600Y301500D02*
X1548477Y298377D01*
G01X1553750Y301500D02*
X1551600D01*
G01X1554800Y341100D02*
X1553500Y342400D01*
G01Y339800D02*
X1554800Y341100D01*
G01X1553500Y338250D02*
Y339800D01*
G01X1527751Y338050D02*
X1527301Y338500D01*
G01X1531687Y338050D02*
X1527751D01*
G01X1537836Y331901D02*
X1531687Y338050D01*
G01X1539224Y331901D02*
X1537836D01*
G01X1543000Y328125D02*
X1539224Y331901D01*
G01X1543875Y328125D02*
X1543000D01*
G01X1545375Y326625D02*
X1543875Y328125D01*
G01X1545375Y321449D02*
Y326625D01*
G01X1547882Y318942D02*
X1545375Y321449D01*
G01X1562669Y381800D02*
X1561625D01*
G01X1563575Y380894D02*
X1562669Y381800D01*
G01X1558760Y342242D02*
X1559213Y341789D01*
G01X1558760Y352100D02*
Y342242D01*
G01X1557534Y353326D02*
X1558760Y352100D01*
G01X1557534Y353400D02*
Y353326D01*
G01X1553825Y377514D02*
X1551875Y378420D01*
G01X1565192Y377669D02*
X1565525Y377514D01*
G01X1563575Y378420D02*
X1565192Y377669D01*
G01X1569425Y388560D02*
X1571375Y387654D01*
G01X1528475Y385180D02*
X1530425Y384274D01*
G01X1535000Y349003D02*
Y347250D01*
G01X1533993Y350010D02*
X1535000Y349003D01*
G01X1533993Y350860D02*
Y350010D01*
G01X1529857Y354996D02*
X1533993Y350860D01*
G01X1529857Y360308D02*
Y354996D01*
G01X1531177Y361628D02*
X1529857Y360308D01*
G01X1549925Y381800D02*
X1551875Y380894D01*
G01X1557725Y397794D02*
X1555775Y398700D01*
G01X1584270Y392430D02*
X1582382D01*
G01X1589134Y387566D02*
X1584270Y392430D01*
G01X1552400Y353400D02*
X1554069Y355069D01*
G01X1552400Y350500D02*
Y353400D01*
G01Y348747D02*
Y350500D01*
G01X1553500Y347647D02*
X1552400Y348747D01*
G01X1553500Y347250D02*
Y347647D01*
G01X1532375Y391940D02*
X1534325Y391034D01*
G01X1530760Y355691D02*
X1535557Y350894D01*
G01X1530760Y359868D02*
Y355691D01*
G01X1531852Y360960D02*
X1530760Y359868D01*
G01X1538000Y348451D02*
Y347250D01*
G01X1535557Y350894D02*
X1538000Y348451D01*
G01X1569425Y397794D02*
X1567475Y398700D01*
G01X1545000Y398270D02*
X1546025Y397794D01*
G01X1544075Y398700D02*
X1545000Y398270D01*
G01X1528475Y394415D02*
Y394414D01*
G01X1527500Y394868D02*
X1528475Y394415D01*
G01X1580341Y347907D02*
X1590913D01*
G01X1572722Y355526D02*
X1580341Y347907D01*
G01X1572721Y355526D02*
X1572722D01*
G01X1569707Y358540D02*
X1572721Y355526D01*
G01X1569707Y360789D02*
Y358540D01*
G01X1569395Y361101D02*
X1569707Y360789D01*
G01X1537343Y371738D02*
Y373189D01*
G01X1536080Y370475D02*
X1537343Y371738D01*
G01X1536080Y369376D02*
Y370475D01*
G01X1536593Y368863D02*
X1536080Y369376D01*
G01X1536593Y358700D02*
Y368863D01*
G01X1537693Y357600D02*
X1536593Y358700D01*
G01X1541750Y357600D02*
X1537693D01*
G01X1542834Y356516D02*
X1541750Y357600D01*
G01X1542834Y355740D02*
Y356516D01*
G01X1542932Y355740D02*
X1542834D01*
G01X1557725Y377514D02*
X1555775Y378420D01*
G01X1527145Y360354D02*
Y356616D01*
G01X1582903Y394591D02*
X1594014D01*
G01X1559626Y394437D02*
X1559675Y394414D01*
G01X1557725Y395320D02*
X1559626Y394437D01*
G01X1566850Y347700D02*
Y344350D01*
G01X1557360Y357190D02*
X1566850Y347700D01*
G01Y342850D02*
Y344350D01*
G01X1546025Y395320D02*
X1547975Y394414D01*
G01X1538225Y381800D02*
X1540175Y380894D01*
G01X1565192Y397949D02*
X1565525Y397794D01*
G01X1563575Y398700D02*
X1565192Y397949D01*
G01X1545500Y343750D02*
X1543957Y342207D01*
G01X1547300Y345050D02*
Y350658D01*
G01X1546000Y343750D02*
X1547300Y345050D01*
G01X1545500Y343750D02*
X1546000D01*
G01X1547300Y352975D02*
X1547872Y353547D01*
G01X1547300Y350658D02*
Y352975D01*
G01X1585811Y356737D02*
X1590531D01*
G01X1580049Y362499D02*
X1585811Y356737D01*
G01X1580049Y368496D02*
Y362499D01*
G01X1565192Y391189D02*
X1565525Y391034D01*
G01X1563575Y391940D02*
X1565192Y391189D01*
G01X1534400Y388525D02*
X1536275Y387654D01*
G01X1534325Y388560D02*
X1534400Y388525D01*
G01X1586215Y366524D02*
X1605150Y347589D01*
G01X1586215Y373267D02*
Y366524D01*
G01X1583276Y376206D02*
X1586215Y373267D01*
G01X1546025Y388560D02*
X1547975Y387654D01*
G01X1562266Y361644D02*
Y363959D01*
G01X1563240Y360670D02*
X1562266Y361644D01*
G01X1563240Y358759D02*
Y360670D01*
G01X1570850Y351149D02*
X1563240Y358759D01*
G01X1572259Y351149D02*
X1570850D01*
G01X1577976Y345432D02*
X1572259Y351149D01*
G01X1589887Y345432D02*
X1577976D01*
G01X1540175Y378420D02*
X1542300Y376717D01*
G01X1529000Y342500D02*
Y343750D01*
G01X1528337Y341837D02*
X1529000Y342500D01*
G01X1553300Y391278D02*
X1553825Y391034D01*
G01X1552944Y391444D02*
X1553300Y391278D01*
G01X1551875Y391940D02*
X1552944Y391444D01*
G01X1542125Y397794D02*
X1540175Y398700D01*
G01X1567475Y385180D02*
X1570289Y384368D01*
G01X1538000Y341400D02*
Y343750D01*
G01X1555577Y352924D02*
Y355142D01*
G01X1557500Y351001D02*
X1555577Y352924D01*
G01X1557500Y350500D02*
Y351001D01*
G01X1556500Y348400D02*
Y347250D01*
G01X1557500Y349400D02*
X1556500Y348400D01*
G01X1557500Y350500D02*
Y349400D01*
G01X1555775Y391940D02*
X1557725Y391034D01*
G01Y381800D02*
X1559675Y380894D01*
G01X1549925Y402080D02*
X1551875Y401174D01*
G01X1561625Y388560D02*
X1563575Y387654D01*
G01X1557725Y388560D02*
X1559675Y387654D01*
G01X1561625Y395320D02*
X1563575Y394414D01*
G01X1584409Y386690D02*
X1592500Y378599D01*
G01X1564200Y349099D02*
X1556350Y356949D01*
G01X1564200Y344300D02*
Y349099D01*
G01X1563650Y343750D02*
X1564200Y344300D01*
G01X1560500Y343750D02*
X1563650D01*
G01X1569425Y395320D02*
X1571375Y394414D01*
G01X1587140Y375988D02*
X1584876Y378252D01*
G01X1587140Y366908D02*
Y375988D01*
G01X1606575Y347473D02*
X1587140Y366908D01*
G01X1549925Y388560D02*
X1551875Y387654D01*
G01X1577048Y343782D02*
X1583491D01*
G01X1572655Y348175D02*
X1577048Y343782D01*
G01X1569413Y348175D02*
X1572655D01*
G01X1560565Y357023D02*
X1569413Y348175D01*
G01X1568859Y347350D02*
X1558477Y357732D01*
G01X1570550Y347350D02*
X1568859D01*
G01X1576500Y341400D02*
X1570550Y347350D01*
G01X1556500Y342150D02*
Y343750D01*
G01X1589502Y399233D02*
X1587683Y397414D01*
G01X1534400Y402045D02*
X1536275Y401174D01*
G01X1534325Y402080D02*
X1534400Y402045D01*
G01X1529000Y348294D02*
Y347250D01*
G01X1529869Y349163D02*
X1529000Y348294D01*
G01X1529869Y351515D02*
Y349163D01*
G01X1528042Y353342D02*
X1529869Y351515D01*
G01X1528042Y356063D02*
Y353342D01*
G01X1567475Y391940D02*
X1569425Y391034D01*
G01X1534325Y384274D02*
X1532375Y385180D01*
G01X1577634Y344607D02*
X1589545D01*
G01X1572442Y349799D02*
X1577634Y344607D01*
G01X1570619Y349799D02*
X1572442D01*
G01X1561353Y359065D02*
X1570619Y349799D01*
G01X1561353Y366831D02*
Y359065D01*
G01X1561163Y367021D02*
X1561353Y366831D01*
G01X1538225Y388560D02*
X1540175Y387654D01*
G01X1538225Y395320D02*
X1540175Y394414D01*
G01X1532375Y378420D02*
X1534325Y377514D01*
G01X1579555Y347082D02*
X1590571D01*
G01X1568726Y357911D02*
X1579555Y347082D01*
G01X1568726Y360149D02*
Y357911D01*
G01X1567362Y361513D02*
X1568726Y360149D01*
G01X1566553Y361513D02*
X1567362D01*
G01X1564925Y363141D02*
X1566553Y361513D01*
G01X1564925Y363696D02*
Y363141D01*
G01X1528475Y398700D02*
X1527275Y397500D01*
G01X1567475Y378420D02*
X1569584Y378002D01*
G01X1541921Y351896D02*
X1540980Y350955D01*
G01X1541921Y353429D02*
Y351896D01*
G01X1542622Y354130D02*
X1541921Y353429D01*
G01X1544014Y354130D02*
X1542622D01*
G01X1544539Y354655D02*
X1544014Y354130D01*
G01X1544539Y359866D02*
Y354655D01*
G01X1544907Y360234D02*
X1544539Y359866D01*
G01X1544907Y360813D02*
Y360234D01*
G01X1546406Y362312D02*
X1544907Y360813D01*
G01X1542500Y343750D02*
Y342524D01*
G01X1541249Y343750D02*
X1542500D01*
G01X1540254Y344745D02*
X1541249Y343750D01*
G01X1540254Y350229D02*
Y344745D01*
G01X1540980Y350955D02*
X1540254Y350229D01*
G01X1538225Y402080D02*
X1540175Y401174D01*
G01X1580307Y389193D02*
X1579902D01*
G01X1581876Y387624D02*
X1580307Y389193D01*
G01X1584676Y387624D02*
X1581876D01*
G01X1593344Y378956D02*
X1584676Y387624D01*
G01X1584107Y371593D02*
X1583400Y372300D01*
G01X1584107Y361941D02*
Y371593D01*
G01X1585985Y360063D02*
X1584107Y361941D01*
G01X1589789Y360063D02*
X1585985D01*
G01X1534400Y395285D02*
X1536275Y394414D01*
G01X1534325Y395320D02*
X1534400Y395285D01*
G01X1534325Y397794D02*
X1532375Y398700D01*
G01X1564735Y359596D02*
Y360626D01*
G01X1566257Y358074D02*
X1564735Y359596D01*
G01X1566499Y358074D02*
X1566257D01*
G01X1568223Y356350D02*
X1566499Y358074D01*
G01X1568224Y356350D02*
X1568223D01*
G01X1569048Y355526D02*
X1568224Y356350D01*
G01X1569049Y355526D02*
X1569048D01*
G01X1578318Y346257D02*
X1569049Y355526D01*
G01X1590229Y346257D02*
X1578318D01*
G01X1590815Y377785D02*
X1583984Y384616D01*
G01X1562960Y401460D02*
X1563575Y401174D01*
G01X1561625Y402080D02*
X1562960Y401460D01*
G01X1565525Y402080D02*
X1567475Y401174D01*
G01X1535000Y343750D02*
Y342200D01*
G01X1584180Y385719D02*
X1591640Y378259D01*
G01X1581268Y385719D02*
X1584180D01*
G01X1580568Y386419D02*
X1581268Y385719D01*
G01X1579249Y386419D02*
X1580568D01*
G01X1578791Y385961D02*
X1579249Y386419D01*
G01X1577745Y385961D02*
X1578791D01*
G01X1576634Y387072D02*
X1577745Y385961D01*
G01X1576634Y389193D02*
Y387072D01*
G01X1574200Y356684D02*
Y361365D01*
G01X1581552Y349332D02*
X1574200Y356684D01*
G01X1591504Y349332D02*
X1581552D01*
G01X1528475Y391940D02*
X1530425Y391034D01*
G01Y377514D02*
X1528475Y378420D01*
G01X1588565Y377052D02*
X1584712Y380905D01*
G01X1588565Y367499D02*
Y377052D01*
G01X1606032Y350032D02*
X1588565Y367499D01*
G01X1569425Y381800D02*
X1571585Y382230D01*
G01X1551434Y349405D02*
X1550639Y350200D01*
G01X1551434Y348184D02*
Y349405D01*
G01X1550500Y347250D02*
X1551434Y348184D01*
G01X1550639Y359958D02*
X1551964Y361283D01*
G01X1550639Y350200D02*
Y359958D01*
G01X1549925Y395320D02*
X1551875Y394414D01*
G01X1564003Y362600D02*
X1566922Y359681D01*
G01X1548343Y342443D02*
X1548100Y342200D01*
G01X1548343Y344926D02*
Y342443D01*
G01X1547651Y341751D02*
X1548100Y342200D01*
G01X1553500Y342400D02*
Y343750D01*
G01X1583921Y352854D02*
X1591482D01*
G01X1579400Y357375D02*
X1583921Y352854D01*
G01X1579400Y359900D02*
Y357375D01*
G01X1578040Y361260D02*
X1579400Y359900D01*
G01X1575790Y361260D02*
X1578040D01*
G01X1557725Y402080D02*
X1559675Y401174D01*
G01X1553825Y397794D02*
X1551875Y398700D01*
G01X1589990Y377210D02*
X1585101Y382099D01*
G01X1563575Y385180D02*
X1565525Y384274D01*
G01X1534400Y381765D02*
X1536275Y380894D01*
G01X1534325Y381800D02*
X1534400Y381765D01*
G01X1562894Y449990D02*
X1563575Y450306D01*
G01X1561625Y449400D02*
X1562894Y449990D01*
G01X1585776Y415319D02*
X1590819D01*
G01X1585394Y414937D02*
X1585776Y415319D01*
G01X1569425Y435880D02*
X1571375Y436786D01*
G01X1579902Y452185D02*
X1583208D01*
G01X1567475Y443546D02*
X1565525Y442640D01*
G01X1563404Y418900D02*
X1561625Y418074D01*
G01X1563575Y418980D02*
X1563404Y418900D01*
G01X1559600Y450631D02*
X1559595D01*
G01X1559600Y450800D02*
Y450631D01*
G01X1559675Y450875D02*
X1559600Y450800D01*
G01X1559675Y452780D02*
Y450875D01*
G01X1551875Y459540D02*
X1553825Y460446D01*
G01X1586371Y447822D02*
X1591528D01*
G01X1584330Y445781D02*
X1586371Y447822D01*
G01X1585312Y421076D02*
X1585560Y421324D01*
G01X1580289Y421076D02*
X1585312D01*
G01X1579902Y420689D02*
X1580289Y421076D01*
G01X1585354Y416323D02*
X1589909D01*
G01X1584706Y415675D02*
X1585354Y416323D01*
G01X1588800Y429914D02*
X1588099D01*
G01X1589386Y430500D02*
X1588800Y429914D01*
G01X1559675Y446020D02*
X1561625Y446926D01*
G01X1557725Y456160D02*
X1559675Y457066D01*
G01X1588541Y454935D02*
X1589106Y455500D01*
G01X1583804Y454935D02*
X1588541D01*
G01X1586627Y434228D02*
X1596238D01*
G01X1586599Y434200D02*
X1586627Y434228D01*
G01X1586572Y434200D02*
X1586599D01*
G01X1585232Y432860D02*
X1586572Y434200D01*
G01X1580262Y432860D02*
X1585232D01*
G01X1579902Y432500D02*
X1580262Y432860D01*
G01X1588241Y453825D02*
X1597245D01*
G01X1588066Y454000D02*
X1588241Y453825D01*
G01X1536275Y459540D02*
X1538225Y460446D01*
G01X1585480Y417348D02*
X1589142D01*
G01X1535975Y415175D02*
X1537550Y413600D01*
G01X1583957Y458157D02*
X1591828D01*
G01X1583414Y458700D02*
X1583957Y458157D01*
G01X1579200Y458700D02*
X1583414D01*
G01X1578591Y458091D02*
X1579200Y458700D01*
G01X1578268Y458091D02*
X1578591D01*
G01X1587954Y407000D02*
X1585674Y404720D01*
G01X1592800Y407000D02*
X1587954D01*
G01X1544075Y459540D02*
X1546025Y460446D01*
G01X1545425Y434075D02*
X1547000Y435650D01*
G01X1539125Y434075D02*
X1540700Y435650D01*
G01X1539125Y437225D02*
X1540700Y438800D01*
G01X1537550D02*
X1535975Y437225D01*
G01X1532825Y446675D02*
X1534400Y448250D01*
G01X1535975Y443525D02*
X1537550Y445100D01*
G01X1529675Y443525D02*
X1531250Y445100D01*
G01X1534400D02*
X1532825Y443525D01*
G01X1540700Y448250D02*
X1539125Y446675D01*
G01X1531250Y448250D02*
X1529675Y446675D01*
G01X1579902Y416752D02*
X1583208D01*
G01X1587864Y443560D02*
X1593570D01*
G01X1585841Y441537D02*
X1587864Y443560D01*
G01X1579270Y441537D02*
X1585841D01*
G01X1578813Y441080D02*
X1579270Y441537D01*
G01X1577745Y441080D02*
X1578813D01*
G01X1576482Y442343D02*
X1577745Y441080D01*
G01X1575000Y442343D02*
X1576482D01*
G01X1568298Y446402D02*
X1569425Y446926D01*
G01X1567475Y446020D02*
X1568298Y446402D01*
G01X1565192Y453531D02*
X1565525Y453686D01*
G01X1564844Y453370D02*
X1565192Y453531D01*
G01X1563575Y452780D02*
X1564844Y453370D01*
G01X1582120Y446280D02*
X1582300Y446100D01*
G01X1578268Y446280D02*
X1582120D01*
G01X1556000Y439365D02*
X1557725Y440166D01*
G01X1555775Y439260D02*
X1556000Y439365D01*
G01X1592162Y438012D02*
X1584628D01*
G01X1534400Y413600D02*
Y413500D01*
G01X1532825Y415175D02*
X1534400Y413600D01*
G01X1569425Y442640D02*
X1571375Y443546D01*
G01X1565525Y435880D02*
X1567475Y436786D01*
G01X1559675Y405460D02*
Y407934D01*
G01X1578268Y426594D02*
X1581939D01*
G01X1586255Y448905D02*
X1590933D01*
G01X1585598Y448248D02*
X1586255Y448905D01*
G01X1586068Y406524D02*
X1583945D01*
G01X1587389Y407845D02*
X1586068Y406524D01*
G01X1590752Y407845D02*
X1587389D01*
G01X1555775Y405460D02*
X1557725Y404554D01*
G01X1555775Y459540D02*
X1557725Y460446D01*
G01X1567475Y439260D02*
X1569425Y440166D01*
G01X1540175Y459540D02*
X1542125Y460446D01*
G01X1579902Y404941D02*
X1583208D01*
G01X1567475Y452780D02*
X1569425Y453686D01*
G01X1592780Y436568D02*
X1587942D01*
G01X1559675Y439260D02*
X1561625Y440166D01*
G01X1555775Y412220D02*
Y414694D01*
G01X1586338Y435138D02*
X1593484D01*
G01X1585800Y434600D02*
X1586338Y435138D01*
G01X1542125Y462920D02*
X1544075Y463826D01*
G01X1587324Y429036D02*
X1595845D01*
G01X1557725Y408840D02*
X1555775Y407934D01*
G01X1567300Y418899D02*
X1565525Y418074D01*
G01X1567475Y418980D02*
X1567300Y418899D01*
G01X1588327Y406000D02*
X1586302Y403975D01*
G01X1593200Y406000D02*
X1588327D01*
G01X1565525Y476440D02*
X1567475Y477346D01*
G01X1542112Y467200D02*
X1542125Y467206D01*
G01X1540175Y466300D02*
X1542112Y467200D01*
G01X1538483Y469800D02*
X1540175Y470586D01*
G01X1538225Y469680D02*
X1538483Y469800D01*
G01X1561625Y469680D02*
X1563575Y470586D01*
G01X1587970Y493500D02*
X1589399D01*
G01X1581570Y499900D02*
X1587970Y493500D01*
G01X1570932Y499900D02*
X1581570D01*
G01X1569460Y501372D02*
X1570932Y499900D01*
G01X1566948Y501372D02*
X1569460D01*
G01X1566207Y500631D02*
X1566948Y501372D01*
G01X1566207Y497889D02*
Y500631D01*
G01X1565700Y497382D02*
X1566207Y497889D01*
G01X1565700Y496136D02*
Y497382D01*
G01X1566870Y494966D02*
X1565700Y496136D01*
G01X1566870Y493445D02*
Y494966D01*
G01X1559675Y473060D02*
X1561625Y473966D01*
G01X1565192Y473811D02*
X1565525Y473966D01*
G01X1564844Y473650D02*
X1565192Y473811D01*
G01X1563575Y473060D02*
X1564844Y473650D01*
G01X1556788Y586222D02*
X1558987Y588421D01*
G01X1555394Y586222D02*
X1556788D01*
G01X1554358Y587258D02*
X1555394Y586222D01*
G01X1565389Y584389D02*
Y585721D01*
G01X1564300Y583300D02*
X1565389Y584389D01*
G01X1562500Y583300D02*
X1564300D01*
G01X1552415Y585163D02*
X1550990Y586588D01*
G01X1557361Y585163D02*
X1552415D01*
G01X1560562Y588364D02*
X1557361Y585163D01*
G01X1564000Y586800D02*
X1562500D01*
G01X1565500Y588300D02*
X1564000Y586800D01*
G01X1562500Y587700D02*
Y586800D01*
G01X1563712Y588912D02*
X1562500Y587700D01*
G01X1574500Y592400D02*
X1572950Y593950D01*
G01X1574500Y591000D02*
Y592400D01*
G01X1571050Y595850D02*
X1565287D01*
G01X1572950Y593950D02*
X1571050Y595850D01*
G01X1541813Y612587D02*
X1540700Y613700D01*
G01X1545613Y612587D02*
X1541813D01*
G01X1547188Y611012D02*
X1545613Y612587D01*
G01X1548550Y611012D02*
X1547188D01*
G01X1558987Y588421D02*
Y595850D01*
G01X1569799Y598000D02*
X1572495D01*
G01X1569386Y598413D02*
X1569799Y598000D01*
G01X1567850Y598413D02*
X1569386D01*
G01X1574560Y597340D02*
X1575790D01*
G01X1573900Y598000D02*
X1574560Y597340D01*
G01X1572495Y598000D02*
X1573900D01*
G01X1567851Y599989D02*
X1567850Y599988D01*
G01X1569987Y599989D02*
X1567851D01*
G01X1570200Y599776D02*
X1569987Y599989D01*
G01X1574526Y599776D02*
X1570200D01*
G01X1575790Y601040D02*
X1574526Y599776D01*
G01X1560562Y595850D02*
Y588364D01*
G01X1572213Y607090D02*
X1573520D01*
G01X1571416Y606293D02*
X1572213Y607090D01*
G01X1571383Y606293D02*
X1571416D01*
G01X1571377Y606287D02*
X1571383Y606293D01*
G01X1567850Y606287D02*
X1571377D01*
G01X1571324Y590831D02*
X1571493Y591000D01*
G01X1568212Y590831D02*
X1571324D01*
G01X1563712Y590349D02*
Y595850D01*
G01X1565500Y589700D02*
Y588300D01*
G01X1566631Y590831D02*
X1565500Y589700D01*
G01X1568212Y590831D02*
X1566631D01*
G01X1563712Y590349D02*
Y588912D01*
G01X1578010Y607060D02*
X1577000D01*
G01X1578800Y607850D02*
X1578010Y607060D01*
G01X1581522Y607850D02*
X1578800D01*
G01X1584971Y611299D02*
X1581522Y607850D01*
G01X1587490Y611299D02*
X1584971D01*
G01X1577000Y606060D02*
Y607060D01*
G01X1575653Y604713D02*
X1577000Y606060D01*
G01X1567850Y604713D02*
X1575653D01*
G01X1599133Y-2569D02*
X1601102Y-600D01*
G01X1595602Y-2569D02*
X1599133D01*
G01X1595602Y5702D02*
Y3337D01*
G01X1596000Y6100D02*
X1595602Y5702D01*
G01X1601400Y6100D02*
X1596000D01*
G01X1602100Y5400D02*
X1601400Y6100D01*
G01X1602100Y398D02*
Y5400D01*
G01X1601102Y-600D02*
X1602100Y398D01*
G01X1595602Y-6698D02*
Y-4537D01*
G01X1592500Y-9800D02*
X1595602Y-6698D01*
G01X1592500Y-12600D02*
Y-9800D01*
G01X1603900Y-12600D02*
X1592500D01*
G01X1605500Y-11000D02*
X1603900Y-12600D01*
G01X1605500Y-3600D02*
Y-11000D01*
G01X1593758Y-16100D02*
X1595004Y-17346D01*
G01X1592500Y-16100D02*
X1593758D01*
G01X1597570Y1369D02*
X1595602D01*
G01X1598602Y2401D02*
X1597570Y1369D01*
G01X1598602Y3437D02*
Y2401D01*
G01Y-600D02*
X1595602D01*
G01X1590431Y-6702D02*
X1592531D01*
G01X1647552Y75875D02*
X1645578Y77849D01*
G01X1648625Y75875D02*
X1647552D01*
G01X1650700Y73800D02*
X1648625Y75875D01*
G01X1640391Y91501D02*
X1636785Y95107D01*
G01X1640391Y81099D02*
Y91501D01*
G01X1642808Y78682D02*
X1640391Y81099D01*
G01X1644745Y78682D02*
X1642808D01*
G01X1645578Y77849D02*
X1644745Y78682D01*
G01X1643629Y91322D02*
Y86808D01*
G01X1643478Y91473D02*
X1643629Y91322D01*
G01X1592500Y90500D02*
X1589500D01*
G01X1592750Y90750D02*
X1592500Y90500D01*
G01X1595500Y90750D02*
X1592750D01*
G01X1595500Y93590D02*
Y90750D01*
G01X1594480Y94610D02*
X1595500Y93590D01*
G01X1602000Y87250D02*
Y84500D01*
G01X1624655Y77794D02*
X1619139D01*
G01X1627489Y74960D02*
X1624655Y77794D01*
G01X1619139D02*
X1619124D01*
G01X1614366Y86248D02*
Y87329D01*
G01X1613334Y85216D02*
X1614366Y86248D01*
G01X1613334Y83599D02*
Y85216D01*
G01X1619139Y77794D02*
X1613334Y83599D01*
G01X1597867Y105054D02*
Y93900D01*
G01X1598849Y92918D02*
Y90788D01*
G01X1597867Y93900D02*
X1598849Y92918D01*
G01X1640607Y77751D02*
X1640578D01*
G01X1642694Y75664D02*
X1640607Y77751D01*
G01X1646426Y75664D02*
X1642694D01*
G01X1647500Y74590D02*
X1646426Y75664D01*
G01X1647500Y73800D02*
Y74590D01*
G01X1639292Y91149D02*
X1635960Y94481D01*
G01X1639292Y79037D02*
Y91149D01*
G01X1640578Y77751D02*
X1639292Y79037D01*
G01X1634977Y94174D02*
Y96860D01*
G01X1636500Y92651D02*
X1634977Y94174D01*
G01X1636500Y91000D02*
Y92651D01*
G01X1608750Y90500D02*
Y96250D01*
G01X1598137Y79650D02*
X1597987Y79500D01*
G01X1601150Y79650D02*
X1598137D01*
G01X1604067Y82567D02*
X1601150Y79650D01*
G01X1607419Y82567D02*
X1604067D01*
G01X1608750Y83898D02*
X1607419Y82567D01*
G01X1608750Y90500D02*
Y83898D01*
G01X1647588Y88912D02*
Y94322D01*
G01X1649900Y86600D02*
X1647588Y88912D01*
G01X1649900Y85250D02*
Y86600D01*
G01X1647588Y96641D02*
Y94322D01*
G01X1633663Y75236D02*
X1630411Y78488D01*
G01X1633663Y72837D02*
Y75236D01*
G01X1633674Y72826D02*
X1633663Y72837D01*
G01X1633674Y72811D02*
Y72826D01*
G01X1634648Y71837D02*
X1633674Y72811D01*
G01X1634663Y71837D02*
X1634648D01*
G01X1634874Y71626D02*
X1634663Y71837D01*
G01X1635815Y71626D02*
X1634874D01*
G01X1637989Y73800D02*
X1635815Y71626D01*
G01X1643900Y73800D02*
X1637989D01*
G01X1633874Y87874D02*
Y102732D01*
G01X1629500Y83500D02*
X1633874Y87874D01*
G01X1629500Y79399D02*
Y83500D01*
G01X1630411Y78488D02*
X1629500Y79399D01*
G01X1648866Y76900D02*
X1651000D01*
G01X1647991Y77775D02*
X1648866Y76900D01*
G01X1647991Y78496D02*
Y77775D01*
G01X1646000Y80487D02*
X1647991Y78496D01*
G01X1646000Y92922D02*
Y80487D01*
G01X1645475Y93447D02*
X1646000Y92922D01*
G01X1645475Y93457D02*
Y93447D01*
G01X1644824Y94108D02*
X1645475Y93457D01*
G01X1644824Y98191D02*
Y94108D01*
G01X1647500Y68750D02*
Y70300D01*
G01X1649300Y66950D02*
X1647500Y68750D01*
G01X1649300Y66813D02*
Y66950D01*
G01X1650876Y65237D02*
X1649300Y66813D01*
G01X1601067Y93063D02*
Y94620D01*
G01X1602000Y92130D02*
X1601067Y93063D01*
G01X1602000Y90750D02*
Y92130D01*
G01X1645500Y70300D02*
X1643900D01*
G01X1645837Y69963D02*
X1645500Y70300D01*
G01X1645837Y69012D02*
Y69963D01*
G01X1648276Y66573D02*
X1645837Y69012D01*
G01X1648276Y65221D02*
Y66573D01*
G01X1649900Y78600D02*
Y81750D01*
G01X1596900Y85850D02*
Y84500D01*
G01X1595500Y87250D02*
X1596900Y85850D01*
G01X1634000Y81000D02*
X1635302Y79698D01*
G01X1634000Y83624D02*
Y81000D01*
G01X1636500Y86124D02*
X1634000Y83624D01*
G01X1636500Y87500D02*
Y86124D01*
G01X1635302Y73535D02*
X1635337Y73500D01*
G01X1635302Y79698D02*
Y73535D01*
G01X1607075Y97000D02*
X1604000Y93925D01*
G01X1630386Y41746D02*
Y41448D01*
G01X1632000Y43360D02*
X1630386Y41746D01*
G01X1632000Y47500D02*
Y43360D01*
G01X1625500Y92002D02*
Y90250D01*
G01X1627498Y94000D02*
X1625500Y92002D01*
G01X1627498Y94000D02*
X1627040Y94458D01*
G01X1631006Y93500D02*
X1632006Y94500D01*
G01X1630000Y93500D02*
X1631006D01*
G01X1628500Y92000D02*
X1630000Y93500D01*
G01X1628500Y90000D02*
Y92000D01*
G01X1632006Y94500D02*
X1630405Y96101D01*
G01X1613650Y69321D02*
X1615115Y70786D01*
G01X1611311Y69321D02*
X1613650D01*
G01X1610941Y69691D02*
X1611311Y69321D01*
G01X1607051Y69691D02*
X1610941D01*
G01X1600199D02*
X1607051D01*
G01X1596189Y73701D02*
X1600199Y69691D01*
G01X1593599Y73701D02*
X1596189D01*
G01X1591600Y75700D02*
X1593599Y73701D01*
G01X1593200Y63075D02*
X1590356D01*
G01X1597425D02*
X1593200D01*
G01X1599000Y61500D02*
X1597425Y63075D01*
G01X1643629Y80529D02*
X1643500Y80400D01*
G01X1643629Y83308D02*
Y80529D01*
G01X1600148Y151711D02*
X1602717D01*
G01X1602118Y113317D02*
X1602717Y113916D01*
G01X1593217Y113317D02*
X1602118D01*
G01X1588930Y109030D02*
X1593217Y113317D01*
G01X1615316Y142296D02*
Y142262D01*
G01X1616900Y143880D02*
X1615316Y142296D01*
G01X1624764Y110766D02*
X1626339Y109191D01*
G01X1600148Y142262D02*
X1602717D01*
G01X1631064Y110766D02*
X1632615Y109215D01*
G01X1639973Y103928D02*
X1640512Y104467D01*
G01X1639973Y101859D02*
Y103928D01*
G01X1636785Y98671D02*
X1639973Y101859D01*
G01X1636785Y95107D02*
Y98671D01*
G01X1649961Y110766D02*
X1651536Y109191D01*
G01X1612166Y139113D02*
X1610591Y140688D01*
G01X1607401Y146947D02*
X1609016Y148562D01*
G01Y142262D02*
X1607441Y143837D01*
G01X1601465Y131335D02*
X1600900Y131900D01*
G01X1604388Y131335D02*
X1601465D01*
G01X1605867Y132814D02*
X1604388Y131335D01*
G01X1649961Y117066D02*
X1651536Y115491D01*
G01X1629400Y109280D02*
X1629487D01*
G01X1627914Y110766D02*
X1629400Y109280D01*
G01X1593675Y95415D02*
X1594480Y94610D01*
G01X1593675Y102626D02*
Y95415D01*
G01X1598666Y107617D02*
X1593675Y102626D01*
G01X1602717Y107617D02*
X1598666D01*
G01X1610591Y146987D02*
X1612166Y145412D01*
G01Y148562D02*
X1610591Y150137D01*
G01X1609016Y100416D02*
Y104467D01*
G01X1608000Y99400D02*
X1609016Y100416D01*
G01X1626339Y118641D02*
Y118651D01*
G01X1624764Y117066D02*
X1626339Y118641D01*
G01X1641770Y112658D02*
Y112340D01*
G01X1640512Y113916D02*
X1641770Y112658D01*
G01X1589841Y115710D02*
X1589800Y115669D01*
G01X1592800Y115710D02*
X1589841D01*
G01X1599951Y114300D02*
X1602717Y117066D01*
G01X1596300Y114300D02*
X1599951D01*
G01X1594890Y115710D02*
X1596300Y114300D01*
G01X1592800Y115710D02*
X1594890D01*
G01X1609016Y151711D02*
X1607441Y153286D01*
G01X1592263Y152464D02*
X1590569D01*
G01X1593353Y153554D02*
X1592263Y152464D01*
G01X1602097Y153554D02*
X1593353D01*
G01X1602153Y153498D02*
X1602097Y153554D01*
G01X1603281Y153498D02*
X1602153D01*
G01X1603337Y153554D02*
X1603281Y153498D01*
G01X1604024Y153554D02*
X1603337D01*
G01X1605867Y151711D02*
X1604024Y153554D01*
G01X1604325Y143804D02*
X1605867Y142262D01*
G01X1598796Y143804D02*
X1604325D01*
G01X1596248Y146352D02*
X1598796Y143804D01*
G01X1592553Y146352D02*
X1596248D01*
G01X1589305Y149600D02*
X1592553Y146352D01*
G01X1609016Y154861D02*
X1607441Y156436D01*
G01X1604369Y112418D02*
X1605867Y113916D01*
G01X1597265Y112418D02*
X1604369D01*
G01X1596224Y111377D02*
X1597265Y112418D01*
G01X1594452Y111377D02*
X1596224D01*
G01X1646812Y117066D02*
X1648387Y115491D01*
G01X1624764Y113836D02*
X1626300Y112300D01*
G01X1624764Y113916D02*
Y113836D01*
G01X1620026Y153300D02*
X1618465Y154861D01*
G01X1620100Y153300D02*
X1620026D01*
G01X1600182Y148562D02*
X1602717D01*
G01X1598913Y106100D02*
X1597867Y105054D01*
G01X1603269Y106100D02*
X1598913D01*
G01X1604349Y107180D02*
X1603269Y106100D01*
G01X1604349Y108168D02*
Y107180D01*
G01X1605261Y109080D02*
X1604349Y108168D01*
G01X1605347Y109080D02*
X1605261D01*
G01X1605362Y109095D02*
X1605347Y109080D01*
G01X1607345Y109095D02*
X1605362D01*
G01X1609016Y110766D02*
X1607345Y109095D01*
G01X1640512Y106565D02*
Y107617D01*
G01X1639149Y105202D02*
X1640512Y106565D01*
G01X1639149Y104271D02*
Y105202D01*
G01X1639148Y104270D02*
X1639149Y104271D01*
G01X1639148Y102201D02*
Y104270D01*
G01X1635960Y99013D02*
X1639148Y102201D01*
G01X1635960Y94481D02*
Y99013D01*
G01X1613741Y146987D02*
X1615316Y145412D01*
G01X1643662Y117066D02*
X1645237Y115491D01*
G01X1605867Y148562D02*
X1604292Y150137D01*
G01X1591439Y123613D02*
X1592617Y122435D01*
G01X1604504Y122002D02*
X1605867Y123365D01*
G01X1602153Y122002D02*
X1604504D01*
G01X1601255Y122900D02*
X1602153Y122002D01*
G01X1593082Y122900D02*
X1601255D01*
G01X1592617Y122435D02*
X1593082Y122900D01*
G01X1636000Y105830D02*
X1634213Y107617D01*
G01X1636000Y102967D02*
Y105830D01*
G01X1634977Y101944D02*
X1636000Y102967D01*
G01X1634977Y96860D02*
Y101944D01*
G01X1612166Y99666D02*
Y104467D01*
G01X1608750Y96250D02*
X1612166Y99666D01*
G01Y135963D02*
X1610591Y137538D01*
G01X1649961Y102083D02*
Y104467D01*
G01X1656519Y95525D02*
X1649961Y102083D01*
G01X1645088Y99141D02*
X1647588Y96641D01*
G01X1645088Y106191D02*
Y99141D01*
G01X1643662Y107617D02*
X1645088Y106191D01*
G01X1592850Y102720D02*
X1591460Y104110D01*
G01X1592850Y97393D02*
Y102720D01*
G01X1591478Y96021D02*
X1592850Y97393D01*
G01X1604916Y110766D02*
X1605867D01*
G01X1603230Y109080D02*
X1604916Y110766D01*
G01X1598779Y109080D02*
X1603230D01*
G01X1595339Y105640D02*
X1598779Y109080D01*
G01X1592080Y105640D02*
X1595339D01*
G01X1591460Y105020D02*
X1592080Y105640D01*
G01X1591460Y104110D02*
Y105020D01*
G01X1651599Y105979D02*
X1649961Y107617D01*
G01X1605867Y135963D02*
X1604292Y134388D01*
G01X1618465Y117066D02*
X1616848Y115449D01*
G01X1634213Y110766D02*
X1632638Y112341D01*
G01X1634213Y113916D02*
X1632638Y115491D01*
G01X1634213Y103071D02*
Y104467D01*
G01X1633874Y102732D02*
X1634213Y103071D01*
G01X1615316Y113916D02*
X1613741Y112341D01*
G01X1643662Y99353D02*
X1644824Y98191D01*
G01X1643662Y104467D02*
Y99353D01*
G01X1612166Y117066D02*
X1610591Y115491D01*
G01X1612167Y151711D02*
X1613741Y150137D01*
G01X1612166Y151711D02*
X1612167D01*
G01X1640512Y117066D02*
X1642084Y115494D01*
G01X1612166Y123365D02*
X1610591Y121790D01*
G01X1646113Y100116D02*
X1650931Y95298D01*
G01X1646113Y103768D02*
Y100116D01*
G01X1646812Y104467D02*
X1646113Y103768D01*
G01X1621615Y154685D02*
X1623200Y153100D01*
G01X1621615Y154861D02*
Y154685D01*
G01X1615316Y110766D02*
X1613741Y109191D01*
G01X1612166Y113916D02*
X1610591Y112341D01*
G01X1648000Y100597D02*
X1652051Y96546D01*
G01X1613690Y124990D02*
X1612166Y126514D01*
G01Y154861D02*
X1610591Y153286D01*
G01X1649961Y113916D02*
X1651536Y112341D01*
G01X1646812Y110766D02*
X1648387Y109191D01*
G01X1589700Y150700D02*
X1588859D01*
G01X1593192Y147208D02*
X1589700Y150700D01*
G01X1597474Y147208D02*
X1593192D01*
G01X1599270Y145412D02*
X1597474Y147208D01*
G01X1602717Y145412D02*
X1599270D01*
G01X1605867Y101618D02*
Y104467D01*
G01X1601067Y96818D02*
X1605867Y101618D01*
G01X1601067Y94620D02*
Y96818D01*
G01X1646812Y113916D02*
X1648387Y112341D01*
G01X1602717Y110766D02*
X1600490D01*
G01X1627914Y107617D02*
X1629400Y106131D01*
G01X1609016Y113916D02*
X1607441Y112341D01*
G01X1613741Y156436D02*
X1615316Y154861D01*
G01X1601655Y134901D02*
X1602717Y135963D01*
G01X1600799Y134901D02*
X1601655D01*
G01X1595150Y140550D02*
X1600799Y134901D01*
G01X1592816Y140550D02*
X1595150D01*
G01X1627914Y113916D02*
X1629489Y112341D01*
G01X1612166Y132814D02*
X1610591Y134389D01*
G01X1618465Y129663D02*
X1616891Y128089D01*
G01X1618465Y129664D02*
Y129663D01*
G01X1609016Y107617D02*
X1607441Y106042D01*
G01X1615316Y135963D02*
X1613741Y137538D01*
G01X1607958Y97000D02*
X1607075D01*
G01X1610750Y99792D02*
X1607958Y97000D01*
G01X1610750Y106201D02*
Y99792D01*
G01X1612166Y107617D02*
X1610750Y106201D01*
G01X1643662Y113916D02*
X1645237Y112341D01*
G01X1609016Y117066D02*
X1607441Y115491D01*
G01X1643662Y110766D02*
X1645237Y109191D01*
G01X1609016Y145412D02*
X1610645Y143783D01*
G01X1627914Y100954D02*
Y104467D01*
G01X1627040Y100080D02*
X1627914Y100954D01*
G01X1627040Y94458D02*
Y100080D01*
G01X1609016Y132814D02*
X1607441Y134389D01*
G01X1609016Y129664D02*
X1610591Y128089D01*
G01X1600374Y133876D02*
X1594725Y139525D01*
G01X1601655Y133876D02*
X1600374D01*
G01X1602717Y132814D02*
X1601655Y133876D01*
G01X1615316Y129664D02*
X1613741Y128089D01*
G01X1632574Y106107D02*
X1631064Y107617D01*
G01X1615316Y132814D02*
X1613741Y134389D01*
G01X1631064Y100896D02*
Y104467D01*
G01X1630405Y100237D02*
X1631064Y100896D01*
G01X1630405Y96101D02*
Y100237D01*
G01X1615316Y148562D02*
X1616891Y150137D01*
G01X1609016Y135963D02*
X1607441Y137538D01*
G01X1648175Y106254D02*
X1646812Y107617D01*
G01X1648175Y102702D02*
Y106254D01*
G01X1654406Y96471D02*
X1648175Y102702D01*
G01X1604504Y128301D02*
X1605867Y129664D01*
G01X1600199Y128301D02*
X1604504D01*
G01X1597837Y130663D02*
X1600199Y128301D01*
G01X1598150Y131800D02*
X1593420D01*
G01X1600286Y129664D02*
X1598150Y131800D01*
G01X1602717Y129664D02*
X1600286D01*
G01X1595339Y154861D02*
X1602717D01*
G01X1591950Y158250D02*
X1595339Y154861D01*
G01X1605715D02*
X1604169Y156407D01*
G01X1605867Y154861D02*
X1605715D01*
G01X1612166Y120215D02*
X1610591Y118640D01*
G01X1615316Y120215D02*
X1613741Y118640D01*
G01Y153286D02*
X1615316Y151711D01*
G01X1640512Y158010D02*
X1642087Y159585D01*
G01X1621615Y164311D02*
X1620041Y165885D01*
G01X1621615Y164310D02*
Y164311D01*
G01X1640512Y164310D02*
X1638938Y165884D01*
G01X1634350Y206988D02*
X1635621Y208259D01*
G01X1634350Y204800D02*
Y206988D01*
G01X1636500Y205074D02*
X1639378D01*
G01X1636226Y204800D02*
X1636500Y205074D01*
G01X1634350Y204800D02*
X1636226D01*
G01X1600490Y167459D02*
X1602717D01*
G01X1631063Y164310D02*
X1629489Y165884D01*
G01X1631064Y164310D02*
X1631063D01*
G01X1620040Y159585D02*
X1621615Y158010D01*
G01X1592122Y169038D02*
X1592450Y168710D01*
G01X1594966Y164310D02*
X1602717D01*
G01X1593218Y166058D02*
X1594966Y164310D01*
G01X1593218Y167942D02*
Y166058D01*
G01X1592450Y168710D02*
X1593218Y167942D01*
G01X1624764Y164310D02*
X1623276Y165798D01*
G01X1589274Y217033D02*
X1590525D01*
G01X1603987Y217000D02*
X1610819Y223832D01*
G01X1599200Y217000D02*
X1603987D01*
G01X1603115Y214600D02*
X1612202Y223687D01*
G01X1599650Y214600D02*
X1603115D01*
G01X1599200Y214150D02*
X1599650Y214600D01*
G01X1599200Y212000D02*
Y214150D01*
G01X1631996Y211448D02*
X1630154D01*
G01X1634882Y214334D02*
X1631996Y211448D01*
G01X1634882Y217000D02*
Y214334D01*
G01X1630154Y211448D02*
Y208148D01*
G01X1609934Y188068D02*
Y188291D01*
G01X1613053Y184949D02*
X1609934Y188068D01*
G01X1634069Y198482D02*
Y197454D01*
G01X1632500Y200051D02*
X1634069Y198482D01*
G01X1632500Y208199D02*
Y200051D01*
G01X1637441Y213140D02*
X1632500Y208199D01*
G01X1637441Y224000D02*
Y213140D01*
G01X1613650Y172275D02*
X1615316Y170609D01*
G01X1613650Y173750D02*
Y172275D01*
G01X1646812Y158010D02*
X1648387Y159585D01*
G01X1637363Y158010D02*
X1638938Y159585D01*
G01X1640512Y161160D02*
X1642101Y162749D01*
G01X1641090Y168037D02*
X1640512Y167459D01*
G01X1641090Y169260D02*
Y168037D01*
G01X1641875Y170045D02*
X1641090Y169260D01*
G01X1641875Y171173D02*
Y170045D01*
G01X1641336Y171712D02*
X1641875Y171173D01*
G01X1641336Y174964D02*
Y171712D01*
G01X1646530Y180158D02*
X1641336Y174964D01*
G01X1646530Y183277D02*
Y180158D01*
G01X1647130Y183877D02*
X1646530Y183277D01*
G01X1647130Y186688D02*
Y183877D01*
G01X1645220Y188598D02*
X1647130Y186688D01*
G01X1645220Y193223D02*
Y188598D01*
G01X1645136Y193307D02*
X1645220Y193223D01*
G01X1645136Y194649D02*
Y193307D01*
G01X1644290Y195495D02*
X1645136Y194649D01*
G01X1644290Y196383D02*
Y195495D01*
G01X1631064Y158010D02*
X1629489Y159585D01*
G01X1609016Y161160D02*
X1607441Y162735D01*
G01X1616970Y168954D02*
X1618465Y167459D01*
G01X1616970Y171730D02*
Y168954D01*
G01X1615900Y172800D02*
X1616970Y171730D01*
G01X1634213Y161160D02*
X1635788Y162735D01*
G01X1612166Y161160D02*
X1610591Y159585D01*
G01X1649961Y158010D02*
X1651536Y159585D01*
G01X1616750Y212000D02*
X1620800D01*
G01X1614250Y209500D02*
X1616750Y212000D01*
G01X1614250Y197000D02*
Y209500D01*
G01X1649509Y199500D02*
X1652927Y202918D01*
G01X1644330Y199500D02*
X1649509D01*
G01X1642318Y197488D02*
X1644330Y199500D01*
G01X1642318Y194958D02*
Y197488D01*
G01X1644395Y192881D02*
X1642318Y194958D01*
G01X1644395Y188110D02*
Y192881D01*
G01X1646236Y186269D02*
X1644395Y188110D01*
G01X1646236Y184938D02*
Y186269D01*
G01X1645599Y184301D02*
X1646236Y184938D01*
G01X1645599Y180582D02*
Y184301D01*
G01X1640512Y175495D02*
X1645599Y180582D01*
G01X1640512Y170609D02*
Y175495D01*
G01X1604843Y167459D02*
X1605867D01*
G01X1603188Y169114D02*
X1604843Y167459D01*
G01X1600712Y169114D02*
X1603188D01*
G01X1597642Y172184D02*
X1600712Y169114D01*
G01X1649961Y161160D02*
X1651536Y162735D01*
G01X1624701Y161160D02*
X1623250Y162611D01*
G01X1624764Y161160D02*
X1624701D01*
G01X1612165Y158010D02*
X1610591Y156436D01*
G01X1612166Y158010D02*
X1612165D01*
G01X1609016Y158011D02*
X1607442Y159585D01*
G01X1609016Y158010D02*
Y158011D01*
G01X1615316Y161160D02*
X1613741Y162735D01*
G01X1603934Y187317D02*
Y188541D01*
G01X1606390Y184861D02*
X1603934Y187317D01*
G01X1606390Y183604D02*
Y184861D01*
G01X1606879Y183115D02*
X1606390Y183604D01*
G01X1606879Y176331D02*
Y183115D01*
G01X1607552Y175658D02*
X1606879Y176331D01*
G01X1607552Y172459D02*
Y175658D01*
G01X1609016Y170995D02*
X1607552Y172459D01*
G01X1609016Y170609D02*
Y170995D01*
G01X1603504Y188541D02*
X1603934D01*
G01X1601565Y190480D02*
X1603504Y188541D01*
G01X1594350Y190480D02*
X1601565D01*
G01X1593960Y190090D02*
X1594350Y190480D01*
G01X1591361Y190090D02*
X1593960D01*
G01X1596000Y184350D02*
X1599000D01*
G01Y181963D02*
Y184350D01*
G01X1598950Y181913D02*
X1599000Y181963D01*
G01X1598950Y180300D02*
Y181913D01*
G01X1589325Y167375D02*
X1591800Y164900D01*
G01X1631347Y216141D02*
X1630154Y214948D01*
G01X1631347Y224691D02*
Y216141D01*
G01X1634213Y158010D02*
X1635788Y159585D01*
G01X1646812Y173712D02*
X1651000Y177900D01*
G01X1646812Y173320D02*
Y173712D01*
G01X1646808Y173316D02*
X1646812Y173320D01*
G01X1646808Y172064D02*
Y173316D01*
G01X1646812Y172060D02*
X1646808Y172064D01*
G01X1646812Y170609D02*
Y172060D01*
G01X1591500Y185690D02*
Y181000D01*
G01X1593160Y187350D02*
X1591500Y185690D01*
G01X1595500Y187350D02*
X1593160D01*
G01X1596000Y187850D02*
X1595500Y187350D01*
G01X1591500Y181000D02*
Y180255D01*
G01X1631064Y161160D02*
X1629489Y162735D01*
G01X1646812Y161160D02*
X1648326Y162674D01*
G01X1637363Y161160D02*
X1638938Y162735D01*
G01X1643662Y158010D02*
X1645237Y159585D01*
G01X1622265Y171259D02*
X1621615Y170609D01*
G01X1622265Y172914D02*
Y171259D01*
G01X1621942Y173237D02*
X1622265Y172914D01*
G01X1610320Y171374D02*
X1612166Y170609D01*
G01X1609222Y172472D02*
X1610320Y171374D01*
G01X1609222Y173389D02*
Y172472D01*
G01X1624966Y170811D02*
X1624764Y170609D01*
G01X1624966Y172936D02*
Y170811D01*
G01X1648320Y172250D02*
X1649961Y170609D01*
G01X1648320Y172690D02*
Y172250D01*
G01X1612934Y187550D02*
Y188291D01*
G01X1615487Y184997D02*
X1612934Y187550D01*
G01X1615487Y184908D02*
Y184997D01*
G01X1615553Y184908D02*
X1615487D01*
G01X1632724Y166604D02*
Y174600D01*
G01X1634213Y165115D02*
X1632724Y166604D01*
G01X1634213Y164310D02*
Y165115D01*
G01X1623600Y195791D02*
Y197580D01*
G01X1624972Y194419D02*
X1623600Y195791D01*
G01X1624972Y192756D02*
Y194419D01*
G01X1626072Y192756D02*
X1624972D01*
G01X1626801Y192027D02*
X1626072Y192756D01*
G01X1626801Y186950D02*
Y192027D01*
G01X1628789Y184962D02*
X1626801Y186950D01*
G01X1629473Y184962D02*
X1628789D01*
G01X1608869Y186562D02*
X1610554Y184877D01*
G01X1608033Y186562D02*
X1608869D01*
G01X1606934Y187661D02*
X1608033Y186562D01*
G01X1606934Y188291D02*
Y187661D01*
G01X1627326Y185055D02*
Y182759D01*
G01X1625871Y186510D02*
X1627326Y185055D01*
G01X1625871Y188357D02*
Y186510D01*
G01X1624972Y189256D02*
X1625871Y188357D01*
G01X1643145Y186948D02*
X1642457D01*
G01X1643570Y187373D02*
X1643145Y186948D01*
G01X1643570Y192539D02*
Y187373D01*
G01X1640824Y195285D02*
X1643570Y192539D01*
G01X1640824Y198681D02*
Y195285D01*
G01X1639583Y199922D02*
X1640824Y198681D01*
G01X1639583Y200339D02*
Y199922D01*
G01X1639378Y200544D02*
X1639583Y200339D01*
G01X1639378Y202515D02*
Y200544D01*
G01X1605500Y181506D02*
X1604766Y182240D01*
G01X1605500Y174782D02*
Y181506D01*
G01X1606550Y173732D02*
X1605500Y174782D01*
G01X1606550Y172003D02*
Y173732D01*
G01X1607330Y171223D02*
X1606550Y172003D01*
G01X1607330Y170226D02*
Y171223D01*
G01X1609016Y168540D02*
X1607330Y170226D01*
G01X1609016Y167459D02*
Y168540D01*
G01X1599941Y187850D02*
X1599000D01*
G01X1601110Y186681D02*
X1599941Y187850D01*
G01X1601110Y184290D02*
Y186681D01*
G01X1603160Y182240D02*
X1601110Y184290D01*
G01X1604766Y182240D02*
X1603160D01*
G01X1643662Y161160D02*
X1645151Y162649D01*
G01X1607381Y165945D02*
X1609016Y164310D01*
G01X1607381Y168192D02*
Y165945D01*
G01X1606584Y168989D02*
X1607381Y168192D01*
G01X1605215Y168989D02*
X1606584D01*
G01X1604277Y169927D02*
X1605215Y168989D01*
G01X1604277Y172724D02*
Y169927D01*
G01X1600001Y177000D02*
X1604277Y172724D01*
G01X1597822Y177000D02*
X1600001D01*
G01X1595800Y179022D02*
X1597822Y177000D01*
G01X1595800Y180300D02*
Y179022D01*
G01X1627914Y161160D02*
X1626339Y162735D01*
G01X1646812Y167459D02*
X1645237Y165884D01*
G01X1635788Y165885D02*
X1637363Y164310D01*
G01X1643662D02*
X1642088Y165885D01*
G01X1591736Y161160D02*
X1602717D01*
G01X1604480Y162547D02*
X1605867Y161160D01*
G01X1589686Y162547D02*
X1604480D01*
G01X1645449Y169246D02*
X1643662Y167459D01*
G01X1645449Y171173D02*
Y169246D01*
G01X1645988Y171712D02*
X1645449Y171173D01*
G01X1645988Y171718D02*
Y171712D01*
G01X1645984Y171722D02*
X1645988Y171718D01*
G01X1645984Y173658D02*
Y171722D01*
G01X1645988Y173662D02*
X1645984Y173658D01*
G01X1645988Y175184D02*
Y173662D01*
G01X1648143Y177339D02*
X1645988Y175184D01*
G01X1648739Y177935D02*
X1648143Y177339D01*
G01X1648739Y179736D02*
Y177935D01*
G01X1649980Y180977D02*
X1648739Y179736D01*
G01X1649980Y181707D02*
Y180977D01*
G01X1649983Y181710D02*
X1649980Y181707D01*
G01X1649983Y184060D02*
Y181710D01*
G01X1648739Y185304D02*
X1649983Y184060D01*
G01X1648739Y187484D02*
Y185304D01*
G01X1647852Y188371D02*
X1648739Y187484D01*
G01X1647852Y189229D02*
Y188371D01*
G01X1650852Y189229D02*
X1647852D01*
G01X1627914Y158010D02*
X1626339Y159585D01*
G01X1649814Y211203D02*
X1651319Y212708D01*
G01X1648795Y211203D02*
X1649814D01*
G01X1646378Y208786D02*
X1648795Y211203D01*
G01X1646378Y207633D02*
Y208786D01*
G01Y207633D02*
Y205074D01*
G01X1624764Y158010D02*
X1623189Y159585D01*
G01X1649961Y164310D02*
X1648386Y165885D01*
G01X1590991Y198840D02*
Y202378D01*
G01X1592074Y197757D02*
X1590991Y198840D01*
G01X1595629Y197757D02*
X1592074D01*
G01X1596386Y197000D02*
X1595629Y197757D01*
G01X1598750Y197000D02*
X1596386D01*
G01X1592514Y207000D02*
X1599200D01*
G01X1590991Y205477D02*
X1592514Y207000D01*
G01X1590991Y202378D02*
Y205477D01*
G01X1647852Y192729D02*
Y197374D01*
G01X1627913Y164310D02*
X1626339Y165884D01*
G01X1627914Y164310D02*
X1627913D01*
G01X1604123Y159754D02*
X1605867Y158010D01*
G01X1598206Y159754D02*
X1604123D01*
G01X1596427Y157975D02*
X1598206Y159754D01*
G01X1602185Y176266D02*
Y180709D01*
G01X1605719Y172732D02*
X1602185Y176266D01*
G01X1605719Y170757D02*
Y172732D01*
G01X1605867Y170609D02*
X1605719Y170757D01*
G01X1600490Y158010D02*
X1602717D01*
G01X1593020Y211720D02*
Y215129D01*
G01X1618465Y174336D02*
X1616286Y176515D01*
G01X1618465Y170609D02*
Y174336D01*
G01X1601142Y172184D02*
X1602717Y170609D01*
G01X1601142Y172185D02*
Y172184D01*
G01X1602150Y259413D02*
Y255500D01*
G01X1602473Y259736D02*
X1602150Y259413D01*
G01X1602473Y268710D02*
Y259736D01*
G01X1603741Y269978D02*
X1602473Y268710D01*
G01X1603741Y272842D02*
Y269978D01*
G01X1593513Y283070D02*
X1603741Y272842D01*
G01X1600557Y249642D02*
X1599201D01*
G01X1600699Y249500D02*
X1600557Y249642D01*
G01X1602150Y249500D02*
X1600699D01*
G01X1602150Y252500D02*
Y249500D01*
G01Y255500D02*
Y252500D01*
G01X1614336Y224732D02*
X1615064Y225460D01*
G01X1611719Y224732D02*
X1614336D01*
G01X1610820Y223833D02*
X1611719Y224732D01*
G01X1610820Y223832D02*
Y223833D01*
G01X1610819Y223832D02*
X1610820D01*
G01X1611658Y250118D02*
X1615512D01*
G01X1608910Y247370D02*
X1611658Y250118D01*
G01X1606520Y247370D02*
X1608910D01*
G01X1605650Y246500D02*
X1606520Y247370D01*
G01X1613837Y223687D02*
X1615064Y222460D01*
G01X1612202Y223687D02*
X1613837D01*
G01X1644850Y230820D02*
Y231500D01*
G01X1641530Y227500D02*
X1644850Y230820D01*
G01X1638000Y227500D02*
X1641530D01*
G01X1637441Y226941D02*
X1638000Y227500D01*
G01X1637441Y224000D02*
Y226941D01*
G01X1648500Y237300D02*
X1669064Y216736D01*
G01X1645827Y237300D02*
X1648500D01*
G01X1643519Y234992D02*
X1645827Y237300D01*
G01X1643519Y234326D02*
Y234992D01*
G01X1643106Y233913D02*
X1643519Y234326D01*
G01X1596725Y249895D02*
X1596300Y250320D01*
G01X1596725Y248735D02*
Y249895D01*
G01X1597441Y248019D02*
X1596725Y248735D01*
G01X1597887Y248019D02*
X1597441D01*
G01X1597927Y247979D02*
X1597887Y248019D01*
G01X1600560Y247979D02*
X1597927D01*
G01X1602039Y246500D02*
X1600560Y247979D01*
G01X1602150Y246500D02*
X1602039D01*
G01X1650250Y223200D02*
Y225150D01*
G01X1653313Y220137D02*
X1650250Y223200D01*
G01X1607100Y255500D02*
X1605650D01*
G01X1607500Y255900D02*
X1607100Y255500D01*
G01X1610100Y255900D02*
X1607500D01*
G01X1611945Y254055D02*
X1610100Y255900D01*
G01X1615512Y254055D02*
X1611945D01*
G01X1599701Y242600D02*
X1600900D01*
G01X1596600Y245701D02*
X1599701Y242600D01*
G01X1596600Y246350D02*
Y245701D01*
G01X1649450Y238750D02*
X1669990Y218210D01*
G01X1642841Y238750D02*
X1649450D01*
G01X1638773Y242818D02*
X1642841Y238750D01*
G01X1638773Y245464D02*
Y242818D01*
G01X1638216Y246021D02*
X1638773Y245464D01*
G01X1606993Y277500D02*
X1589463Y295030D01*
G01X1624881Y277500D02*
X1606993D01*
G01X1630522Y283141D02*
X1624881Y277500D01*
G01X1604610Y242600D02*
X1604400D01*
G01X1606847Y244837D02*
X1604610Y242600D01*
G01X1606924Y244837D02*
X1606847D01*
G01X1607927Y245840D02*
X1606924Y244837D01*
G01X1610480Y245840D02*
X1607927D01*
G01X1610821Y246181D02*
X1610480Y245840D01*
G01X1615512Y246181D02*
X1610821D01*
G01X1604400Y239200D02*
Y242600D01*
G01X1602418Y237218D02*
X1604400Y239200D01*
G01X1611352Y261929D02*
X1615512D01*
G01X1608752Y259329D02*
X1611352Y261929D01*
G01X1605819Y259329D02*
X1608752D01*
G01X1632128Y225472D02*
X1631347Y224691D01*
G01X1607600Y273072D02*
X1594607Y286065D01*
G01X1607600Y271742D02*
Y273072D01*
G01X1608025Y271317D02*
X1607600Y271742D01*
G01X1608407Y271317D02*
X1608025D01*
G01X1608832Y270892D02*
X1608407Y271317D01*
G01X1608832Y270042D02*
Y270892D01*
G01X1608407Y269617D02*
X1608832Y270042D01*
G01X1608025Y269617D02*
X1608407D01*
G01X1607600Y269192D02*
X1608025Y269617D01*
G01X1607600Y264610D02*
Y269192D01*
G01X1605819Y262829D02*
X1607600Y264610D01*
G01X1630303Y275303D02*
X1606856D01*
G01X1634815Y279815D02*
X1630303Y275303D01*
G01X1599201Y255597D02*
Y253142D01*
G01X1598376Y256422D02*
X1599201Y255597D01*
G01X1598028Y256422D02*
X1598376D01*
G01X1644650Y228350D02*
X1645400D01*
G01X1643450Y227150D02*
X1644650Y228350D01*
G01X1643450Y225050D02*
Y227150D01*
G01X1642400Y224000D02*
X1643450Y225050D01*
G01X1640000Y224000D02*
X1642400D01*
G01X1648600Y229400D02*
Y233800D01*
G01X1647550Y228350D02*
X1648600Y229400D01*
G01X1645400Y228350D02*
X1647550D01*
G01X1650000Y233800D02*
X1651575Y232225D01*
G01X1648600Y233800D02*
X1650000D01*
G01X1641750Y244750D02*
Y252500D01*
G01X1643700Y242800D02*
X1641750Y244750D01*
G01X1638887Y252087D02*
X1632112D01*
G01X1639300Y252500D02*
X1638887Y252087D01*
G01X1641750Y252500D02*
X1639300D01*
G01X1610892Y257992D02*
X1615512D01*
G01X1610436Y257536D02*
X1610892Y257992D01*
G01X1604604Y257536D02*
X1610436D01*
G01X1603898Y258242D02*
X1604604Y257536D01*
G01X1603898Y263845D02*
Y258242D01*
G01X1604790Y264737D02*
X1603898Y263845D01*
G01X1605189Y264737D02*
X1604790D01*
G01X1606163Y265711D02*
X1605189Y264737D01*
G01X1606163Y272452D02*
Y265711D01*
G01X1594084Y284531D02*
X1606163Y272452D01*
G01X1629720Y276128D02*
X1635070Y281478D01*
G01X1607198Y276128D02*
X1629720D01*
G01X1650400Y244005D02*
X1678815Y215590D01*
G01X1650400Y246500D02*
Y244005D01*
G01X1640000Y255500D02*
X1641750D01*
G01X1639200Y256300D02*
X1640000Y255500D01*
G01X1636000Y256300D02*
X1639200D01*
G01X1635724Y256024D02*
X1636000Y256300D01*
G01X1632112Y256024D02*
X1635724D01*
G01X1641750Y257000D02*
Y255500D01*
G01X1642550Y257800D02*
X1641750Y257000D01*
G01X1647105Y257800D02*
X1642550D01*
G01X1650400Y254505D02*
X1647105Y257800D01*
G01X1650400Y246500D02*
Y254505D01*
G01X1646548Y255500D02*
X1645250D01*
G01X1647900Y254148D02*
X1646548Y255500D01*
G01X1647900Y243200D02*
Y254148D01*
G01X1649666Y241434D02*
X1647900Y243200D01*
G01X1676750Y214350D02*
X1649666Y241434D01*
G01X1621164Y228550D02*
Y225910D01*
G01X1620739Y228975D02*
X1621164Y228550D01*
G01X1612713Y228975D02*
X1620739D01*
G01X1610200Y231488D02*
X1612713Y228975D01*
G01X1610200Y240799D02*
Y231488D01*
G01X1611645Y242244D02*
X1610200Y240799D01*
G01X1615512Y242244D02*
X1611645D01*
G01X1620714Y225460D02*
X1618564D01*
G01X1621164Y225910D02*
X1620714Y225460D01*
G01X1645250Y250510D02*
Y252500D01*
G01X1643775Y249035D02*
X1645250Y250510D01*
G01X1643775Y246137D02*
Y249035D01*
G01X1620232Y222460D02*
X1621164Y223392D01*
G01X1618564Y222460D02*
X1620232D01*
G01X1628568Y248150D02*
X1632112D01*
G01X1626122Y245704D02*
X1628568Y248150D01*
G01X1624504Y245704D02*
X1626122D01*
G01X1618800Y240000D02*
X1624504Y245704D01*
G01X1611650Y240000D02*
X1618800D01*
G01X1611225Y239575D02*
X1611650Y240000D01*
G01X1611225Y231773D02*
Y239575D01*
G01X1612998Y230000D02*
X1611225Y231773D01*
G01X1621500Y230000D02*
X1612998D01*
G01X1622900Y228600D02*
X1621500Y230000D01*
G01X1622900Y225128D02*
Y228600D01*
G01X1621164Y223392D02*
X1622900Y225128D01*
G01X1636655Y287811D02*
X1636800Y287956D01*
G01X1631691Y287811D02*
X1636655D01*
G01X1627180Y283300D02*
X1631691Y287811D01*
G01X1604963Y283300D02*
X1627180D01*
G01X1591950Y296313D02*
X1604963Y283300D01*
G01X1591950Y308648D02*
Y296313D01*
G01X1595726Y312424D02*
X1591950Y308648D01*
G01X1595726Y316312D02*
Y312424D01*
G01X1598131Y318717D02*
X1595726Y316312D01*
G01X1598131Y340689D02*
Y318717D01*
G01X1590913Y347907D02*
X1598131Y340689D01*
G01X1636440Y334060D02*
Y336594D01*
G01X1637450Y333050D02*
X1636440Y334060D01*
G01X1637450Y331300D02*
Y333050D01*
G01Y327117D02*
Y331300D01*
G01X1638063Y326504D02*
X1637450Y327117D01*
G01X1628046Y292446D02*
X1636822D01*
G01X1621968Y286368D02*
X1628046Y292446D01*
G01X1606733Y286368D02*
X1621968D01*
G01X1596225Y296876D02*
X1606733Y286368D01*
G01X1596225Y307850D02*
Y296876D01*
G01X1599512Y311137D02*
X1596225Y307850D01*
G01X1599512Y315412D02*
Y311137D01*
G01X1604439Y320339D02*
X1599512Y315412D01*
G01X1604439Y324600D02*
Y320339D01*
G01Y331993D02*
Y324600D01*
G01X1602300Y334132D02*
X1604439Y331993D01*
G01X1602300Y344968D02*
Y334132D01*
G01X1633656Y297444D02*
X1636925D01*
G01X1630700Y300400D02*
X1633656Y297444D01*
G01X1630700Y309800D02*
Y300400D01*
G01X1620000Y320500D02*
X1630700Y309800D01*
G01X1618500Y320500D02*
X1620000D01*
G01X1610500Y328500D02*
X1618500Y320500D01*
G01X1610500Y330000D02*
Y328500D01*
G01X1605150Y335350D02*
X1610500Y330000D01*
G01X1605150Y347589D02*
Y335350D01*
G01X1595656Y339663D02*
X1589887Y345432D01*
G01X1595656Y319743D02*
Y339663D01*
G01X1592971Y317058D02*
X1595656Y319743D01*
G01X1592971Y313846D02*
Y317058D01*
G01X1589463Y310338D02*
X1592971Y313846D01*
G01X1589463Y295030D02*
Y310338D01*
G01X1636684Y283141D02*
X1630522D01*
G01X1649500Y329059D02*
X1652991D01*
G01X1649542Y308763D02*
X1650735Y307570D01*
G01X1643385Y308763D02*
X1649542D01*
G01X1639413Y312735D02*
X1643385Y308763D01*
G01X1635437Y316711D02*
X1639413Y312735D01*
G01X1635437Y321794D02*
Y316711D01*
G01X1632537Y324694D02*
X1635437Y321794D01*
G01X1632537Y324702D02*
Y324694D01*
G01X1630840Y326399D02*
X1632537Y324702D01*
G01X1630194Y326399D02*
X1630840D01*
G01X1626252Y330341D02*
X1630194Y326399D01*
G01X1619470Y330341D02*
X1626252D01*
G01X1618496Y331315D02*
X1619470Y330341D01*
G01X1618496Y334735D02*
Y331315D01*
G01X1619897Y336136D02*
X1618496Y334735D01*
G01X1649500Y317236D02*
X1653500Y313236D01*
G01X1649500Y318559D02*
Y317236D01*
G01X1630534Y330718D02*
Y336594D01*
G01X1631015Y330237D02*
X1630534Y330718D01*
G01X1631015Y328350D02*
Y330237D01*
G01X1632503Y334346D02*
Y336594D01*
G01X1634200Y332649D02*
X1632503Y334346D01*
G01X1634200Y325383D02*
Y332649D01*
G01X1635355Y324228D02*
X1634200Y325383D01*
G01X1591622Y288448D02*
Y289050D01*
G01X1591071Y287897D02*
X1591622Y288448D01*
G01X1590369Y287897D02*
X1591071D01*
G01X1594607Y286065D02*
X1589795D01*
G01X1640399Y306600D02*
X1647900D01*
G01X1636711Y310288D02*
X1640399Y306600D01*
G01X1636711Y312053D02*
Y310288D01*
G01X1622765Y325999D02*
X1636711Y312053D01*
G01X1621173Y325999D02*
X1622765D01*
G01X1616074Y331098D02*
X1621173Y325999D01*
G01X1616074Y357926D02*
Y331098D01*
G01X1657852Y306600D02*
X1647900D01*
G01X1606575Y335924D02*
Y347473D01*
G01X1611500Y330999D02*
X1606575Y335924D01*
G01X1611500Y329000D02*
Y330999D01*
G01X1619000Y321500D02*
X1611500Y329000D01*
G01X1620894Y321500D02*
X1619000D01*
G01X1632125Y310269D02*
X1620894Y321500D01*
G01X1632125Y301275D02*
Y310269D01*
G01X1634248Y299152D02*
X1632125Y301275D01*
G01X1658604Y299152D02*
X1634248D01*
G01X1590667Y317088D02*
X1589523D01*
G01X1594006Y320427D02*
X1590667Y317088D01*
G01X1594006Y333267D02*
Y320427D01*
G01X1636684Y279815D02*
X1634815D01*
G01X1647276Y311103D02*
X1651966D01*
G01X1642697Y315682D02*
X1647276Y311103D01*
G01X1642697Y319628D02*
Y315682D01*
G01X1637408Y324917D02*
X1642697Y319628D01*
G01X1637018Y324917D02*
X1637408D01*
G01X1636044Y325891D02*
X1637018Y324917D01*
G01X1635791Y325891D02*
X1636044D01*
G01X1635200Y326482D02*
X1635791Y325891D01*
G01X1635200Y332816D02*
Y326482D01*
G01X1634472Y333544D02*
X1635200Y332816D01*
G01X1634472Y336594D02*
Y333544D01*
G01X1641772Y315978D02*
X1638086Y319664D01*
G01X1641772Y315298D02*
Y315978D01*
G01X1646892Y310178D02*
X1641772Y315298D01*
G01X1651115Y310178D02*
X1646892D01*
G01X1649500Y326500D02*
X1653091D01*
G01X1645500Y325000D02*
X1644500D01*
G01X1647000Y326500D02*
X1645500Y325000D01*
G01X1649500Y326500D02*
X1647000D01*
G01X1644500Y328500D02*
Y325000D01*
G01X1625607Y340193D02*
X1621700Y344100D01*
G01X1625951Y340193D02*
X1625607D01*
G01X1645788Y281478D02*
X1643320D01*
G01X1655198Y290888D02*
X1645788Y281478D01*
G01X1635070D02*
X1643320D01*
G01X1592146Y314720D02*
X1589517Y312091D01*
G01X1592146Y317400D02*
Y314720D01*
G01X1594831Y320085D02*
X1592146Y317400D01*
G01X1594831Y339321D02*
Y320085D01*
G01X1589545Y344607D02*
X1594831Y339321D01*
G01X1638530Y285629D02*
X1641594Y288693D01*
G01X1632222Y285629D02*
X1638530D01*
G01X1632221Y285630D02*
X1632222Y285629D01*
G01X1631539Y285630D02*
X1632221D01*
G01X1631538Y285629D02*
X1631539Y285630D01*
G01X1631360Y285629D02*
X1631538D01*
G01X1631359Y285630D02*
X1631360Y285629D01*
G01X1630677Y285630D02*
X1631359D01*
G01X1627360Y282313D02*
X1630677Y285630D01*
G01X1604783Y282313D02*
X1627360D01*
G01X1591125Y295971D02*
X1604783Y282313D01*
G01X1591125Y309156D02*
Y295971D01*
G01X1594621Y312652D02*
X1591125Y309156D01*
G01X1594621Y316374D02*
Y312652D01*
G01X1597306Y319059D02*
X1594621Y316374D01*
G01X1597306Y340347D02*
Y319059D01*
G01X1590571Y347082D02*
X1597306Y340347D01*
G01X1648205Y295304D02*
X1641594Y288693D01*
G01X1658525Y295304D02*
X1648205D01*
G01X1629944Y325475D02*
Y324236D01*
G01X1625903Y329516D02*
X1629944Y325475D01*
G01X1619128Y329516D02*
X1625903D01*
G01X1616899Y331745D02*
X1619128Y329516D01*
G01X1616899Y364901D02*
Y331745D01*
G01X1637671Y311977D02*
X1639413Y310235D01*
G01X1637671Y312629D02*
Y311977D01*
G01X1629944Y320356D02*
X1637671Y312629D01*
G01X1629944Y324236D02*
Y320356D01*
G01X1603725Y335275D02*
Y346127D01*
G01X1609500Y329500D02*
X1603725Y335275D01*
G01X1609500Y328000D02*
Y329500D01*
G01X1618000Y319500D02*
X1609500Y328000D01*
G01X1619500Y319500D02*
X1618000D01*
G01X1629150Y309850D02*
X1619500Y319500D01*
G01X1629150Y299450D02*
Y309850D01*
G01X1633654Y294946D02*
X1629150Y299450D01*
G01X1636822Y294946D02*
X1633654D01*
G01X1596481Y340005D02*
X1590229Y346257D01*
G01X1596481Y319401D02*
Y340005D01*
G01X1593796Y316716D02*
X1596481Y319401D01*
G01X1593796Y313236D02*
Y316716D01*
G01X1590300Y309740D02*
X1593796Y313236D01*
G01X1590300Y295629D02*
Y309740D01*
G01X1604441Y281488D02*
X1590300Y295629D01*
G01X1627702Y281488D02*
X1604441D01*
G01X1631018Y284804D02*
X1627702Y281488D01*
G01X1645994Y284804D02*
X1631018D01*
G01X1649692Y288502D02*
X1645994Y284804D01*
G01X1655669Y294479D02*
X1649692Y288502D01*
G01X1614424Y330414D02*
Y350343D01*
G01X1620489Y324349D02*
X1614424Y330414D01*
G01X1622081Y324349D02*
X1620489D01*
G01X1635061Y311369D02*
X1622081Y324349D01*
G01X1635061Y306891D02*
Y311369D01*
G01X1636861Y305091D02*
X1635061Y306891D01*
G01X1647050Y302400D02*
X1654900D01*
G01X1643675Y305775D02*
X1647050Y302400D01*
G01X1640025Y305775D02*
X1643675D01*
G01X1635886Y309914D02*
X1640025Y305775D01*
G01X1635886Y311711D02*
Y309914D01*
G01X1622423Y325174D02*
X1635886Y311711D01*
G01X1620831Y325174D02*
X1622423D01*
G01X1615249Y330756D02*
X1620831Y325174D01*
G01X1615249Y350685D02*
Y330756D01*
G01X1599056Y318333D02*
Y341780D01*
G01X1596871Y316148D02*
X1599056Y318333D01*
G01X1596871Y312229D02*
Y316148D01*
G01X1593375Y308733D02*
X1596871Y312229D01*
G01X1593375Y296346D02*
Y308733D01*
G01X1605496Y284225D02*
X1593375Y296346D01*
G01X1626650Y284225D02*
X1605496D01*
G01X1632079Y289654D02*
X1626650Y284225D01*
G01X1639293Y289654D02*
X1632079D01*
G01X1645868Y296229D02*
X1639293Y289654D01*
G01X1658141Y296229D02*
X1645868D01*
G01X1612500Y329500D02*
Y349084D01*
G01X1619500Y322500D02*
X1612500Y329500D01*
G01X1621454Y322500D02*
X1619500D01*
G01X1633311Y310643D02*
X1621454Y322500D01*
G01X1633311Y301528D02*
Y310643D01*
G01X1634762Y300077D02*
X1633311Y301528D01*
G01X1658988Y300077D02*
X1634762D01*
G01X1625406Y336594D02*
X1628566D01*
G01X1622950Y339050D02*
X1625406Y336594D01*
G01X1622950Y341150D02*
Y339050D01*
G01X1620000Y344100D02*
X1622950Y341150D01*
G01X1628566Y333216D02*
Y336594D01*
G01X1628100Y332750D02*
X1628566Y333216D01*
G01X1620905Y332750D02*
X1628100D01*
G01X1620159Y332004D02*
X1620905Y332750D01*
G01X1645484Y297154D02*
X1657757D01*
G01X1639004Y290674D02*
X1645484Y297154D01*
G01X1627583Y290674D02*
X1639004D01*
G01X1622352Y285443D02*
X1627583Y290674D01*
G01X1605972Y285443D02*
X1622352D01*
G01X1594800Y296615D02*
X1605972Y285443D01*
G01X1594800Y308141D02*
Y296615D01*
G01X1598296Y311637D02*
X1594800Y308141D01*
G01X1598296Y316096D02*
Y311637D01*
G01X1600188Y317988D02*
X1598296Y316096D01*
G01X1600188Y344148D02*
Y317988D01*
G01X1613599Y330072D02*
Y350001D01*
G01X1620147Y323524D02*
X1613599Y330072D01*
G01X1621739Y323524D02*
X1620147D01*
G01X1634236Y311027D02*
X1621739Y323524D01*
G01X1634236Y305274D02*
Y311027D01*
G01X1636922Y302588D02*
X1634236Y305274D01*
G01X1590581Y403058D02*
X1589586Y402063D01*
G01X1654325Y398700D02*
X1647100D01*
G01D02*
X1638500D01*
G01X1627525Y397925D02*
X1620700Y391100D01*
G01X1627525Y398275D02*
Y397925D01*
G01X1630550Y401300D02*
X1627525Y398275D01*
G01X1594201Y387566D02*
X1589134D01*
G01X1602404Y388133D02*
X1599227D01*
G01X1602859Y387678D02*
X1602404Y388133D01*
G01X1602859Y385806D02*
Y387678D01*
G01X1602359Y385306D02*
X1602859Y385806D01*
G01X1596234Y385306D02*
X1602359D01*
G01X1595843Y385697D02*
X1596234Y385306D01*
G01X1595843Y386367D02*
Y385697D01*
G01X1594644Y387566D02*
X1595843Y386367D01*
G01X1594201Y387566D02*
X1594644D01*
G01X1604563Y401437D02*
X1611500D01*
G01X1601800Y404200D02*
X1604563Y401437D01*
G01X1592808Y403018D02*
X1593990Y404200D01*
G01X1615033Y401437D02*
X1611500D01*
G01X1616890Y399580D02*
X1615033Y401437D01*
G01X1648881Y354555D02*
X1649005D01*
G01X1647886Y355550D02*
X1648881Y354555D01*
G01X1638293Y355550D02*
X1647886D01*
G01X1635813Y358030D02*
X1638293Y355550D01*
G01X1635813Y358640D02*
Y358030D01*
G01X1635803Y358650D02*
X1635813Y358640D01*
G01X1635803Y362942D02*
Y358650D01*
G01X1635813Y362952D02*
X1635803Y362942D01*
G01X1635813Y386387D02*
Y362952D01*
G01X1630400Y391800D02*
X1635813Y386387D01*
G01X1650523Y351411D02*
X1651497Y350437D01*
G01X1649005Y354555D02*
X1650523Y353037D01*
G01X1594014Y394591D02*
X1594451Y395028D01*
G01X1595612D02*
X1594451D01*
G01X1596151Y395567D02*
X1595612Y395028D01*
G01X1596151Y396647D02*
Y395567D01*
G01X1596826Y397322D02*
X1596151Y396647D01*
G01X1604514Y397322D02*
X1596826D01*
G01X1607403Y394433D02*
X1604514Y397322D01*
G01X1607495Y394433D02*
X1607403D01*
G01X1643555Y344879D02*
X1642443D01*
G01X1643926Y345250D02*
X1643555Y344879D01*
G01X1645650Y345250D02*
X1643926D01*
G01X1641223Y346099D02*
X1639055D01*
G01X1642443Y344879D02*
X1641223Y346099D01*
G01X1617200Y393000D02*
Y391100D01*
G01X1616890Y393310D02*
X1617200Y393000D01*
G01X1616890Y396080D02*
Y393310D01*
G01X1617200Y390846D02*
X1613452Y387098D01*
G01X1617200Y391100D02*
Y390846D01*
G01X1628566Y358766D02*
Y349698D01*
G01X1629764Y359964D02*
X1628566Y358766D01*
G01X1630337Y359964D02*
X1629764D01*
G01X1630476Y360103D02*
X1630337Y359964D01*
G01X1636946Y349698D02*
X1636440D01*
G01X1638991Y351743D02*
X1636946Y349698D01*
G01X1638991Y352037D02*
Y351743D01*
G01X1590531Y356737D02*
X1602300Y344968D01*
G01X1627901Y365099D02*
X1625500Y367500D01*
G01X1630240Y365099D02*
X1627901D01*
G01X1649700Y348750D02*
X1651950Y346500D01*
G01X1648650Y348750D02*
X1649700D01*
G01X1648650D02*
X1645650D01*
G01X1632503Y356197D02*
Y349698D01*
G01X1631097Y357603D02*
X1632503Y356197D01*
G01X1630408Y357603D02*
X1631097D01*
G01X1613930Y360070D02*
X1616074Y357926D01*
G01X1609160Y360070D02*
X1613930D01*
G01X1607610Y358520D02*
X1609160Y360070D01*
G01X1603061Y358520D02*
X1607610D01*
G01X1592519Y369062D02*
X1603061Y358520D01*
G01X1592519Y369680D02*
Y369062D01*
G01X1592500Y369699D02*
X1592519Y369680D01*
G01X1592500Y378599D02*
Y369699D01*
G01X1590563Y399233D02*
X1589502D01*
G01X1593330Y402000D02*
X1590563Y399233D01*
G01X1594750Y402000D02*
X1593330D01*
G01X1622550Y369572D02*
X1625681Y372703D01*
G01X1622550Y358200D02*
Y369572D01*
G01X1625681Y381781D02*
Y372703D01*
G01X1629300Y385400D02*
X1625681Y381781D01*
G01X1636198Y355442D02*
X1635342D01*
G01X1637040Y354600D02*
X1636198Y355442D01*
G01X1645900Y354600D02*
X1637040D01*
G01X1651550Y348950D02*
X1645900Y354600D01*
G01X1634472Y354572D02*
X1635342Y355442D01*
G01X1634472Y349698D02*
Y354572D01*
G01X1630534Y349698D02*
Y354900D01*
G01X1633400Y373100D02*
X1630900Y375600D01*
G01X1633400Y372900D02*
Y373100D01*
G01X1624500Y354700D02*
X1622550D01*
G01X1625400Y355600D02*
X1624500Y354700D01*
G01X1625400Y361700D02*
Y355600D01*
G01X1625535Y361835D02*
X1625400Y361700D01*
G01X1621700Y353850D02*
X1622550Y354700D01*
G01X1621700Y344100D02*
Y353850D01*
G01X1631730Y367730D02*
X1630200D01*
G01X1633400Y369400D02*
X1631730Y367730D01*
G01X1593344Y369404D02*
Y378956D01*
G01X1600430Y362318D02*
X1593344Y369404D01*
G01X1605316Y362318D02*
X1600430D01*
G01X1606381Y363383D02*
X1605316Y362318D01*
G01X1607761Y363383D02*
X1606381D01*
G01X1609785Y365407D02*
X1607761Y363383D01*
G01X1612146Y365407D02*
X1609785D01*
G01X1614139Y367400D02*
X1612146Y365407D01*
G01X1614400Y367400D02*
X1614139D01*
G01X1614400D02*
X1616899Y364901D01*
G01X1603725Y346127D02*
X1589789Y360063D01*
G01X1590815Y368432D02*
Y377785D01*
G01X1606965Y352282D02*
X1590815Y368432D01*
G01X1612485Y352282D02*
X1606965D01*
G01X1614424Y350343D02*
X1612485Y352282D01*
G01X1612506Y353428D02*
X1615249Y350685D01*
G01X1606986Y353428D02*
X1612506D01*
G01X1591640Y368774D02*
X1606986Y353428D01*
G01X1591640Y378259D02*
Y368774D01*
G01X1599056Y341780D02*
X1591504Y349332D01*
G01X1611552Y350032D02*
X1606032D01*
G01X1612500Y349084D02*
X1611552Y350032D01*
G01X1630337Y362600D02*
X1633337D01*
G01X1620000Y345750D02*
Y344100D01*
G01X1630400Y398700D02*
X1635000D01*
G01X1591482Y352854D02*
X1600188Y344148D01*
G01X1589990Y368090D02*
Y377210D01*
G01X1606623Y351457D02*
X1589990Y368090D01*
G01X1612143Y351457D02*
X1606623D01*
G01X1613599Y350001D02*
X1612143Y351457D01*
G01X1613104Y415500D02*
X1615250D01*
G01X1612604Y416000D02*
X1613104Y415500D01*
G01X1609750Y416000D02*
X1612604D01*
G01X1615250Y415163D02*
Y415500D01*
G01X1617244Y413169D02*
X1615250Y415163D01*
G01X1629613Y413169D02*
X1617244D01*
G01X1630386Y413942D02*
X1629613Y413169D01*
G01X1609750Y417250D02*
Y416000D01*
G01X1609139Y417861D02*
X1609750Y417250D01*
G01X1593361Y417861D02*
X1609139D01*
G01X1590819Y415319D02*
X1593361Y417861D01*
G01X1645362Y421575D02*
X1652037Y428250D01*
G01X1621109Y421575D02*
X1645362D01*
G01X1620847Y421837D02*
X1621109Y421575D01*
G01X1590581Y404170D02*
Y403058D01*
G01X1605727Y432523D02*
X1605750Y432500D01*
G01X1603050Y432523D02*
X1605727D01*
G01X1600641D02*
X1603050D01*
G01X1595729Y427611D02*
X1600641Y432523D01*
G01X1591140Y427611D02*
X1595729D01*
G01X1590571Y428180D02*
X1591140Y427611D01*
G01X1589292Y428180D02*
X1590571D01*
G01X1639300Y435500D02*
X1639500Y435700D01*
G01X1636750Y435500D02*
X1639300D01*
G01X1633250D02*
X1627250D01*
G01X1639375Y433075D02*
X1639500Y433200D01*
G01X1638772Y433075D02*
X1639375D01*
G01X1638147Y433700D02*
X1638772Y433075D01*
G01X1633800Y433700D02*
X1638147D01*
G01X1633250Y434250D02*
X1633800Y433700D01*
G01X1633250Y435500D02*
Y434250D01*
G01X1642810Y442010D02*
X1652505Y432315D01*
G01X1639411Y442010D02*
X1642810D01*
G01X1636401Y439000D02*
X1639411Y442010D01*
G01X1627800Y439000D02*
X1636401D01*
G01X1627300Y439500D02*
X1627800Y439000D01*
G01X1610816Y444286D02*
X1608760Y442230D01*
G01X1619614Y444286D02*
X1610816D01*
G01X1621686Y442214D02*
X1619614Y444286D01*
G01X1621709Y442214D02*
X1621686D01*
G01X1622598Y441325D02*
X1621709Y442214D01*
G01X1626675Y441325D02*
X1622598D01*
G01X1627300Y440700D02*
X1626675Y441325D01*
G01X1627300Y439500D02*
Y440700D01*
G01X1602601Y444286D02*
X1602600Y444287D01*
G01X1607314Y444286D02*
X1602601D01*
G01X1608760Y442840D02*
X1607314Y444286D01*
G01X1608760Y442230D02*
Y442840D01*
G01X1636700Y446600D02*
Y445800D01*
G01X1635800Y447500D02*
X1636700Y446600D01*
G01X1634600Y447500D02*
X1635800D01*
G01X1633250Y448850D02*
X1634600Y447500D01*
G01X1633250Y449500D02*
Y448850D01*
G01X1632900Y449500D02*
X1633250D01*
G01X1630300Y452100D02*
X1632900Y449500D01*
G01X1610630Y451000D02*
X1609250D01*
G01X1611530Y451900D02*
X1610630Y451000D01*
G01X1613801Y451900D02*
X1611530D01*
G01X1619076Y457175D02*
X1613801Y451900D01*
G01X1630200Y457175D02*
X1619076D01*
G01X1633250Y454000D02*
Y452500D01*
G01X1633750Y454500D02*
X1633250Y454000D01*
G01X1637687Y454500D02*
X1633750D01*
G01X1639133Y453054D02*
X1637687Y454500D01*
G01X1639736Y453054D02*
X1639133D01*
G01X1639822Y453140D02*
X1639736Y453054D01*
G01X1602329Y451481D02*
X1602450Y451360D01*
G01X1595187Y451481D02*
X1602329D01*
G01X1591528Y447822D02*
X1595187Y451481D01*
G01X1602810Y451000D02*
X1605750D01*
G01X1602450Y451360D02*
X1602810Y451000D01*
G01X1624444Y417174D02*
X1624602Y417332D01*
G01X1618709Y417174D02*
X1624444D01*
G01X1617347Y418536D02*
X1618709Y417174D01*
G01X1617347Y418837D02*
Y418536D01*
G01X1615537Y418837D02*
X1617347D01*
G01X1614900Y418200D02*
X1615537Y418837D01*
G01X1611800Y418200D02*
X1614900D01*
G01X1610400Y419600D02*
X1611800Y418200D01*
G01X1593186Y419600D02*
X1610400D01*
G01X1589909Y416323D02*
X1593186Y419600D01*
G01X1612250Y435500D02*
X1614750D01*
G01X1596000Y430500D02*
X1589386D01*
G01X1601337Y435837D02*
X1596000Y430500D01*
G01X1601337Y436189D02*
Y435837D01*
G01X1602368Y437220D02*
X1601337Y436189D01*
G01X1610530Y437220D02*
X1602368D01*
G01X1612250Y435500D02*
X1610530Y437220D01*
G01X1593990Y404200D02*
X1601800D01*
G01X1637601Y441900D02*
X1635700D01*
G01X1639750Y444049D02*
X1637601Y441900D01*
G01X1639750Y445477D02*
Y444049D01*
G01X1623200Y449800D02*
X1621000Y452000D01*
G01X1623800Y449800D02*
X1623200D01*
G01X1642000Y449400D02*
X1643300Y448100D01*
G01X1636850Y449400D02*
X1642000D01*
G01X1636750Y449500D02*
X1636850Y449400D01*
G01X1643810Y447590D02*
X1646525D01*
G01X1643300Y448100D02*
X1643810Y447590D01*
G01X1589106Y455500D02*
X1590500D01*
G01X1633250Y430763D02*
X1630150Y427663D01*
G01X1633250Y432000D02*
Y430763D01*
G01X1627250Y430563D02*
Y432000D01*
G01X1630150Y427663D02*
X1627250Y430563D01*
G01X1598130Y436120D02*
Y435920D01*
G01X1600160Y438150D02*
X1598130Y436120D01*
G01X1611661Y438150D02*
X1600160D01*
G01X1612251Y437560D02*
X1611661Y438150D01*
G01X1643210Y437560D02*
X1612251D01*
G01X1643430Y437780D02*
X1643210Y437560D01*
G01X1597930Y435920D02*
X1598130D01*
G01X1596238Y434228D02*
X1597930Y435920D01*
G01X1628700Y459700D02*
X1642783Y473783D01*
G01X1618899Y459700D02*
X1628700D01*
G01X1616200Y457001D02*
X1618899Y459700D01*
G01X1606277Y457001D02*
X1616200D01*
G01X1605669Y456393D02*
X1606277Y457001D01*
G01X1605669Y454809D02*
Y456393D01*
G01X1598229Y454809D02*
X1605669D01*
G01X1597245Y453825D02*
X1598229Y454809D01*
G01X1613300Y420500D02*
X1613400D01*
G01X1612952Y420848D02*
X1613300Y420500D01*
G01X1592642Y420848D02*
X1612952D01*
G01X1589142Y417348D02*
X1592642Y420848D01*
G01X1616010Y420500D02*
X1617347Y421837D01*
G01X1613400Y420500D02*
X1616010D01*
G01X1604300Y425800D02*
X1602520D01*
G01X1604500Y426000D02*
X1604300Y425800D01*
G01X1605750Y426000D02*
X1604500D01*
G01X1592200Y423700D02*
X1590698Y422198D01*
G01X1598901Y423700D02*
X1592200D01*
G01X1601001Y425800D02*
X1598901Y423700D01*
G01X1602520Y425800D02*
X1601001D01*
G01X1605306Y459843D02*
X1606791D01*
G01X1602741Y457278D02*
X1605306Y459843D01*
G01X1592707Y457278D02*
X1602741D01*
G01X1591828Y458157D02*
X1592707Y457278D01*
G01X1611057Y459843D02*
X1611800Y459100D01*
G01X1606791Y459843D02*
X1611057D01*
G01X1613882Y426868D02*
X1614750Y426000D01*
G01X1610118Y426868D02*
X1613882D01*
G01X1609250Y426000D02*
X1610118Y426868D01*
G01X1622800Y424800D02*
X1628655D01*
G01X1621500Y423500D02*
X1622800Y424800D01*
G01X1615500Y423500D02*
X1621500D01*
G01X1614750Y424250D02*
X1615500Y423500D01*
G01X1614750Y426000D02*
Y424250D01*
G01X1645271Y423500D02*
X1651636Y429865D01*
G01X1631873Y423500D02*
X1645271D01*
G01X1630573Y424800D02*
X1631873Y423500D01*
G01X1628655Y424800D02*
X1630573D01*
G01X1597800Y412000D02*
X1592800Y407000D01*
G01X1612651Y408750D02*
X1609500D01*
G01X1612875Y408974D02*
X1612651Y408750D01*
G01X1612825Y408974D02*
X1612875D01*
G01X1627300Y449800D02*
Y453663D01*
G01X1628275Y454675D02*
X1630200D01*
G01X1627300Y453700D02*
X1628275Y454675D01*
G01X1627300Y453663D02*
Y453700D01*
G01X1620700Y407100D02*
X1617900Y409900D01*
G01X1620700Y406900D02*
Y407100D01*
G01X1621550Y448700D02*
X1619984D01*
G01X1623750Y446500D02*
X1621550Y448700D01*
G01X1617900Y450000D02*
X1616300D01*
G01X1619200Y448700D02*
X1617900Y450000D01*
G01X1619984Y448700D02*
X1619200D01*
G01X1620652Y445600D02*
X1621226Y445026D01*
G01X1615100Y445600D02*
X1620652D01*
G01X1612937Y447763D02*
X1615100Y445600D01*
G01X1599711Y447763D02*
X1612937D01*
G01X1598498Y446550D02*
X1599711Y447763D01*
G01X1596560Y446550D02*
X1598498D01*
G01X1593570Y443560D02*
X1596560Y446550D01*
G01X1622752Y443500D02*
X1621226Y445026D01*
G01X1623750Y443500D02*
X1622752D01*
G01X1638150Y451100D02*
X1636750Y452500D01*
G01X1645459Y451100D02*
X1638150D01*
G01X1646469Y450090D02*
X1645459Y451100D01*
G01X1602472Y422971D02*
X1603000D01*
G01X1602001Y422500D02*
X1602472Y422971D01*
G01X1592810Y422500D02*
X1602001D01*
G01X1591841Y421531D02*
X1592810Y422500D01*
G01X1603000Y422971D02*
X1605449D01*
G01X1614750Y432330D02*
Y432500D01*
G01X1611935Y429515D02*
X1614750Y432330D01*
G01X1600259Y430685D02*
X1599194Y429620D01*
G01X1610765Y430685D02*
X1600259D01*
G01X1611935Y429515D02*
X1610765Y430685D01*
G01X1596360Y426786D02*
X1599194Y429620D01*
G01X1590665Y426786D02*
X1596360D01*
G01X1590208Y427243D02*
X1590665Y426786D01*
G01X1625600Y461900D02*
X1622700D01*
G01X1627800Y464100D02*
X1625600Y461900D01*
G01X1622000Y461200D02*
X1622700Y461900D01*
G01X1617400Y461200D02*
X1622000D01*
G01X1615300Y459100D02*
X1617400Y461200D01*
G01X1633385Y411885D02*
X1634400Y412900D01*
G01X1617031Y411885D02*
X1633385D01*
G01X1615116Y413800D02*
X1617031Y411885D01*
G01X1610950Y413800D02*
X1615116D01*
G01X1610600Y413450D02*
X1610950Y413800D01*
G01X1610600Y412850D02*
Y413450D01*
G01X1609750Y412000D02*
X1610600Y412850D01*
G01X1608963Y412787D02*
X1609750Y412000D01*
G01X1608963Y413088D02*
Y412787D01*
G01X1608165Y413886D02*
X1608963Y413088D01*
G01X1604419Y413886D02*
X1608165D01*
G01X1604339Y413806D02*
X1604419Y413886D01*
G01X1602961Y413806D02*
X1604339D01*
G01X1602881Y413886D02*
X1602961Y413806D01*
G01X1596446Y413886D02*
X1602881D01*
G01X1595929Y414403D02*
X1596446Y413886D01*
G01X1594551Y414403D02*
X1595929D01*
G01X1591262Y411114D02*
X1594551Y414403D01*
G01X1590817Y411114D02*
X1591262D01*
G01X1598437Y444287D02*
X1592162Y438012D01*
G01X1600083Y444287D02*
X1598437D01*
G01X1602140Y442230D02*
X1600083Y444287D01*
G01X1605260Y442230D02*
X1602140D01*
G01X1639200Y427100D02*
X1636700D01*
G01X1640332Y428232D02*
X1639200Y427100D01*
G01X1640332Y429167D02*
Y428232D01*
G01X1640625Y429460D02*
X1640332Y429167D01*
G01X1636750Y427150D02*
X1636700Y427100D01*
G01X1636750Y432000D02*
Y427150D01*
G01X1620700Y403400D02*
X1616900D01*
G01X1604300D02*
X1616900D01*
G01X1601800Y405900D02*
X1604300Y403400D01*
G01X1595800Y405900D02*
X1601800D01*
G01X1623500Y407000D02*
X1624200D01*
G01X1622400Y405900D02*
X1623500Y407000D01*
G01X1622400Y404200D02*
Y405900D01*
G01X1621600Y403400D02*
X1622400Y404200D01*
G01X1620700Y403400D02*
X1621600D01*
G01X1640764Y455100D02*
X1643300D01*
G01X1640751Y455087D02*
X1640764Y455100D01*
G01X1639249Y455087D02*
X1640751D01*
G01X1639236Y455100D02*
X1639249Y455087D01*
G01X1639100Y455100D02*
X1639236D01*
G01X1634784Y459416D02*
X1639100Y455100D01*
G01X1629583Y459416D02*
X1634784D01*
G01X1628867Y458700D02*
X1629583Y459416D01*
G01X1619400Y458700D02*
X1628867D01*
G01X1613796Y453096D02*
X1619400Y458700D01*
G01X1604445Y453096D02*
X1613796D01*
G01X1604018Y453523D02*
X1604445Y453096D01*
G01X1599023Y453523D02*
X1604018D01*
G01X1598000Y452500D02*
X1599023Y453523D01*
G01X1594528Y452500D02*
X1598000D01*
G01X1590933Y448905D02*
X1594528Y452500D01*
G01X1643941Y455100D02*
X1646451Y452590D01*
G01X1643300Y455100D02*
X1643941D01*
G01X1646741Y452300D02*
X1646451Y452590D01*
G01X1649800Y452300D02*
X1646741D01*
G01X1613577Y427827D02*
X1614750Y429000D01*
G01X1610423Y427827D02*
X1613577D01*
G01X1609250Y429000D02*
X1610423Y427827D01*
G01X1632399Y424800D02*
X1642515D01*
G01X1631199Y426000D02*
X1632399Y424800D01*
G01X1625724Y426000D02*
X1631199D01*
G01X1621437Y430287D02*
X1625724Y426000D01*
G01X1621430Y430287D02*
X1621437D01*
G01X1620982Y430735D02*
X1621430Y430287D01*
G01X1615235Y430735D02*
X1620982D01*
G01X1614750Y430250D02*
X1615235Y430735D01*
G01X1614750Y429000D02*
Y430250D01*
G01X1644701Y424800D02*
X1650791Y430890D01*
G01X1642515Y424800D02*
X1644701D01*
G01X1645720Y428970D02*
X1647200Y430450D01*
G01X1644040Y428970D02*
X1645720D01*
G01X1643430Y429580D02*
X1644040Y428970D01*
G01X1643430Y434280D02*
Y429580D01*
G01X1590764Y407833D02*
X1590752Y407845D01*
G01X1592096Y407833D02*
X1590764D01*
G01X1595200Y410937D02*
X1592096Y407833D01*
G01X1595200Y412700D02*
Y410937D01*
G01X1613700Y411800D02*
X1612500D01*
G01X1616237Y409263D02*
X1613700Y411800D01*
G01X1616237Y409211D02*
Y409263D01*
G01X1616900Y408548D02*
X1616237Y409211D01*
G01X1616900Y406900D02*
Y408548D01*
G01X1599800Y441900D02*
X1599320D01*
G01X1601760Y439940D02*
X1599800Y441900D01*
G01X1609500Y439940D02*
X1601760D01*
G01X1612183Y442623D02*
X1609500Y439940D01*
G01X1612306Y442500D02*
X1614750D01*
G01X1612183Y442623D02*
X1612306Y442500D01*
G01X1598112Y441900D02*
X1592780Y436568D01*
G01X1599320Y441900D02*
X1598112D01*
G01X1606500Y405250D02*
X1609500D01*
G01X1612637D02*
X1612825Y405438D01*
G01X1609500Y405250D02*
X1612637D01*
G01X1602600Y408400D02*
X1601300D01*
G01X1605750Y405250D02*
X1602600Y408400D01*
G01X1606500Y405250D02*
X1605750D01*
G01X1611640Y440088D02*
X1612256D01*
G01X1610552Y439000D02*
X1611640Y440088D01*
G01X1597346Y439000D02*
X1610552D01*
G01X1593484Y435138D02*
X1597346Y439000D01*
G01X1612844Y439500D02*
X1614750D01*
G01X1612256Y440088D02*
X1612844Y439500D01*
G01X1594000Y455500D02*
X1596500D01*
G01X1603000Y435500D02*
X1605750D01*
G01X1602262D02*
X1603000D01*
G01X1602262Y435453D02*
Y435500D01*
G01X1595845Y429036D02*
X1602262Y435453D01*
G01X1601550Y449318D02*
X1597885D01*
G01X1601671Y449197D02*
X1601550Y449318D01*
G01X1611997Y449197D02*
X1601671D01*
G01X1612800Y450000D02*
X1611997Y449197D01*
G01X1597147Y448580D02*
X1597885Y449318D01*
G01X1594580Y448580D02*
X1597147D01*
G01X1599925Y445625D02*
X1600400Y446100D01*
G01X1597575Y445625D02*
X1599925D01*
G01X1594108Y442158D02*
X1597575Y445625D01*
G01X1605650Y446100D02*
X1605750Y446000D01*
G01X1600400Y446100D02*
X1605650D01*
G01X1591400Y424761D02*
X1597400D01*
G01X1589184Y422545D02*
X1591400Y424761D01*
G01X1602800Y429000D02*
X1605750D01*
G01X1598561Y424761D02*
X1602800Y429000D01*
G01X1597400Y424761D02*
X1598561D01*
G01X1645787Y420550D02*
X1652462Y427225D01*
G01X1622560Y420550D02*
X1645787D01*
G01X1620847Y418837D02*
X1622560Y420550D01*
G01X1595600Y408400D02*
X1593200Y406000D01*
G01X1597800Y408400D02*
X1595600D01*
G01X1640743Y487760D02*
X1640781D01*
G01X1640743Y487838D02*
Y487760D01*
G01X1640072Y487167D02*
X1640743Y487838D01*
G01X1634611Y487167D02*
X1640072D01*
G01X1625704Y525907D02*
X1624443Y527168D01*
G01X1625704Y524099D02*
Y525907D01*
G01X1626571Y523232D02*
X1625704Y524099D01*
G01X1627535Y523232D02*
X1626571D01*
G01X1630159Y520608D02*
X1627535Y523232D01*
G01X1640136Y492000D02*
X1639271Y491135D01*
G01X1644293Y492000D02*
X1640136D01*
G01X1645180Y491113D02*
X1644293Y492000D01*
G01X1645180Y482441D02*
Y491113D01*
G01X1642783Y480044D02*
X1645180Y482441D01*
G01X1642783Y473783D02*
Y480044D01*
G01X1644874Y517143D02*
X1650649D01*
G01X1642670Y514939D02*
X1644874Y517143D01*
G01X1627622Y524928D02*
Y526473D01*
G01X1649788Y479642D02*
X1652783Y476647D01*
G01X1649788Y481699D02*
Y479642D01*
G01X1648123Y483364D02*
X1649788Y481699D01*
G01X1648123Y495415D02*
Y483364D01*
G01X1640623Y502915D02*
X1648123Y495415D01*
G01X1634611Y502915D02*
X1640623D01*
G01X1629062Y518663D02*
X1627407Y520318D01*
G01X1634611Y518663D02*
X1629062D01*
G01X1625807Y521918D02*
X1623361D01*
G01X1627407Y520318D02*
X1625807Y521918D01*
G01X1630500Y491104D02*
X1634611D01*
G01X1630104Y491500D02*
X1630500Y491104D01*
G01X1629500Y491500D02*
X1630104D01*
G01X1590100Y492799D02*
Y491500D01*
G01X1589399Y493500D02*
X1590100Y492799D01*
G01X1648463Y479093D02*
X1651457Y476099D01*
G01X1648463Y481149D02*
Y479093D01*
G01X1646798Y482814D02*
X1648463Y481149D01*
G01X1646798Y494866D02*
Y482814D01*
G01X1642686Y498978D02*
X1646798Y494866D01*
G01X1634611Y498978D02*
X1642686D01*
G01X1630825D02*
X1634611D01*
G01X1629778Y500025D02*
X1630825Y498978D01*
G01X1629778Y507294D02*
Y500025D01*
G01X1632242Y514726D02*
X1634611D01*
G01X1629668Y517300D02*
X1632242Y514726D01*
G01X1627301Y517300D02*
X1629668D01*
G01X1625683Y518918D02*
X1627301Y517300D01*
G01X1623361Y518918D02*
X1625683D01*
G01X1637730Y514726D02*
X1639391Y513065D01*
G01X1634611Y514726D02*
X1637730D01*
G01X1624538Y529263D02*
Y530500D01*
G01X1625747Y528054D02*
X1624538Y529263D01*
G01X1626493Y528054D02*
X1625747D01*
G01X1626518Y528029D02*
X1626493Y528054D01*
G01X1599104Y579266D02*
Y580396D01*
G01X1603660Y574710D02*
X1599104Y579266D01*
G01X1607760Y574710D02*
X1603660D01*
G01X1609620Y576570D02*
X1607760Y574710D01*
G01X1609620Y584620D02*
Y576570D01*
G01X1608070Y586170D02*
X1609620Y584620D01*
G01X1608070Y607450D02*
Y586170D01*
G01X1621295Y528506D02*
Y530312D01*
G01X1622633Y527168D02*
X1621295Y528506D01*
G01X1624443Y527168D02*
X1622633D01*
G01X1628038Y528962D02*
Y530500D01*
G01X1628221Y528779D02*
X1628038Y528962D01*
G01X1628221Y527072D02*
Y528779D01*
G01X1627622Y526473D02*
X1628221Y527072D01*
G01X1595604Y584396D02*
Y580396D01*
G01Y588396D02*
Y584396D01*
G01X1593910Y580396D02*
X1595604D01*
G01X1591910Y582396D02*
X1593910Y580396D01*
G01X1589578Y582396D02*
X1591910D01*
G01X1631538Y528137D02*
Y530500D01*
G01X1631975Y527700D02*
X1631538Y528137D01*
G01X1602330Y613190D02*
X1608070Y607450D01*
G01X1595790Y613190D02*
X1602330D01*
G01X1594110Y611510D02*
X1595790Y613190D01*
G01X1592934Y592396D02*
X1595604D01*
G01X1591630Y593700D02*
X1592934Y592396D01*
G01X1589578Y593700D02*
X1591630D01*
G01X1593752Y623973D02*
X1777027D01*
G01X1591468Y621689D02*
X1593752Y623973D01*
G01X1591468Y619375D02*
Y621689D01*
G01X1590881Y618788D02*
X1591468Y619375D01*
G01X1594177Y622948D02*
X1775452D01*
G01X1592493Y621264D02*
X1594177Y622948D01*
G01X1592493Y619762D02*
Y621264D01*
G01X1593519Y618736D02*
X1592493Y619762D01*
G01X1708003Y-9500D02*
X1713503Y-15000D01*
G01X1700800Y-9500D02*
X1708003D01*
G01X1691000Y300D02*
X1700800Y-9500D01*
G01X1691000Y3000D02*
Y300D01*
G01X1711300Y68900D02*
X1713500D01*
G01X1650800Y73800D02*
X1650700D01*
G01X1673800Y74922D02*
Y75200D01*
G01X1675739Y72983D02*
X1673800Y74922D01*
G01X1677117Y72983D02*
X1675739D01*
G01X1678237Y74103D02*
X1677117Y72983D01*
G01X1678237Y75189D02*
Y74103D01*
G01X1679211Y76163D02*
X1678237Y75189D01*
G01X1683688Y76163D02*
X1679211D01*
G01X1687280Y72571D02*
X1683688Y76163D01*
G01X1687280Y68600D02*
Y72571D01*
G01X1713200Y65400D02*
X1711300D01*
G01X1668600Y86000D02*
X1669800Y84800D01*
G01X1666648Y86000D02*
X1668600D01*
G01X1664848Y87800D02*
X1666648Y86000D01*
G01X1663700Y87800D02*
X1664848D01*
G01X1669800Y84800D02*
X1673000Y81600D01*
G01X1663700Y92919D02*
Y87800D01*
G01X1659731Y96888D02*
X1663700Y92919D01*
G01X1672098Y85002D02*
X1675500Y81600D01*
G01X1672098Y94440D02*
Y85002D01*
G01X1670055Y96483D02*
X1672098Y94440D01*
G01X1667547Y92000D02*
X1665909Y93638D01*
G01X1669000Y92000D02*
X1667547D01*
G01X1665909Y93638D02*
X1662013Y97534D01*
G01X1712140Y93380D02*
G02X1710359Y97680I4300J4300D01*
G01X1712432Y93088D02*
X1712140Y93380D01*
G01X1706800Y83289D02*
X1712845Y77244D01*
G01X1706800Y86614D02*
Y83289D01*
G01X1705203Y88211D02*
X1706800Y86614D01*
G01X1703819Y88211D02*
X1705203D01*
G01X1700103Y91927D02*
X1703819Y88211D01*
G01X1697166Y91927D02*
X1700103D01*
G01X1695300Y93793D02*
X1697166Y91927D01*
G01X1695300Y94712D02*
Y93793D01*
G01X1671237Y78363D02*
X1674400D01*
G01X1668000Y81600D02*
X1671237Y78363D01*
G01X1692400Y72248D02*
Y68600D01*
G01X1692207Y72441D02*
X1692400Y72248D01*
G01X1692207Y75425D02*
Y72441D01*
G01X1691782Y75850D02*
X1692207Y75425D01*
G01X1688872Y75850D02*
X1691782D01*
G01X1686359Y78363D02*
X1688872Y75850D01*
G01X1674400Y78363D02*
X1686359D01*
G01X1705381Y90049D02*
X1704824D01*
G01X1708480Y86950D02*
X1705381Y90049D01*
G01X1709578Y86950D02*
X1708480D01*
G01X1710563Y85965D02*
X1709578Y86950D01*
G01X1710563Y82996D02*
Y85965D01*
G01X1711869Y81690D02*
X1710563Y82996D01*
G01X1705000Y59500D02*
X1708000D01*
G01X1694960Y65189D02*
Y68600D01*
G01X1700649Y59500D02*
X1694960Y65189D01*
G01X1705000Y59500D02*
X1700649D01*
G01X1656519Y94041D02*
Y95525D01*
G01X1660813Y89747D02*
X1656519Y94041D01*
G01X1660813Y84961D02*
Y89747D01*
G01X1659809Y83957D02*
X1660813Y84961D01*
G01X1659809Y77869D02*
Y83957D01*
G01X1656600Y74660D02*
X1659809Y77869D01*
G01X1656600Y73614D02*
Y74660D01*
G01X1674749Y87364D02*
Y87050D01*
G01X1673399Y88714D02*
X1674749Y87364D01*
G01X1673399Y96127D02*
Y88714D01*
G01X1657425Y94443D02*
Y95786D01*
G01X1658370Y93498D02*
X1657425Y94443D01*
G01X1658371Y93498D02*
X1658370D01*
G01X1661738Y90131D02*
X1658371Y93498D01*
G01X1661738Y84577D02*
Y90131D01*
G01X1660900Y83739D02*
X1661738Y84577D01*
G01X1660900Y75414D02*
Y83739D01*
G01X1659100Y73614D02*
X1660900Y75414D01*
G01X1700080Y65219D02*
Y68600D01*
G01X1702099Y63200D02*
X1700080Y65219D01*
G01X1704900Y63200D02*
X1702099D01*
G01X1704900D02*
Y66268D01*
G01X1651000Y76900D02*
X1654100Y73800D01*
G01X1655857Y77856D02*
X1656737D01*
G01X1654100Y76099D02*
X1655857Y77856D01*
G01X1654100Y73800D02*
Y76099D01*
G01X1697520Y64680D02*
Y68600D01*
G01X1700800Y61400D02*
X1697520Y64680D01*
G01X1711100Y61400D02*
X1700800D01*
G01X1711700Y62000D02*
X1711100Y61400D01*
G01X1711700Y62000D02*
X1714700D01*
G01X1692400Y50100D02*
Y46400D01*
G01X1691244Y51256D02*
X1692400Y50100D01*
G01X1679314Y51256D02*
X1691244D01*
G01X1676050Y54520D02*
X1679314Y51256D01*
G01X1676050Y56770D02*
Y54520D01*
G01X1673400Y59420D02*
X1676050Y56770D01*
G01X1672450Y60370D02*
X1673400Y59420D01*
G01X1668850Y60370D02*
X1672450D01*
G01X1667916Y59436D02*
X1668850Y60370D01*
G01X1667916Y58116D02*
Y59436D01*
G01X1679707Y89064D02*
Y94697D01*
G01X1677573Y86930D02*
X1679707Y89064D01*
G01X1650931Y88768D02*
Y90182D01*
G01X1653000Y86699D02*
X1650931Y88768D01*
G01X1653000Y85250D02*
Y86699D01*
G01X1650931Y95298D02*
Y90182D01*
G01X1706596Y95656D02*
X1712688Y89564D01*
G01X1655948Y86000D02*
X1656500D01*
G01X1653763Y88185D02*
X1655948Y86000D01*
G01X1653763Y90867D02*
Y88185D01*
G01X1652051Y92579D02*
X1653763Y90867D01*
G01X1652051Y96546D02*
Y92579D01*
G01X1679900Y74218D02*
Y74500D01*
G01X1681482Y72636D02*
X1679900Y74218D01*
G01X1684369Y72636D02*
X1681482D01*
G01X1684720Y72285D02*
X1684369Y72636D01*
G01X1684720Y68600D02*
Y72285D01*
G01X1670708Y92672D02*
X1665993Y97387D01*
G01X1670708Y91209D02*
Y92672D01*
G01X1667499Y88000D02*
X1670708Y91209D01*
G01X1667000Y88000D02*
X1667499D01*
G01X1702500Y84668D02*
Y87083D01*
G01X1699941Y79642D02*
Y77668D01*
G01X1694900Y84683D02*
X1699941Y79642D01*
G01X1694900Y88924D02*
Y84683D01*
G01X1693824Y90000D02*
X1694900Y88924D01*
G01X1692500Y90000D02*
X1693824D01*
G01X1689840Y72101D02*
Y68600D01*
G01X1684953Y76988D02*
X1689840Y72101D01*
G01X1678770Y76988D02*
X1684953D01*
G01X1676428Y74646D02*
X1678770Y76988D01*
G01X1698347Y50862D02*
X1716570D01*
G01X1694264Y54945D02*
X1698347Y50862D01*
G01X1686049Y54945D02*
X1694264D01*
G01X1684248Y56746D02*
X1686049Y54945D01*
G01X1711788Y85112D02*
X1717150Y79750D01*
G01X1711788Y88642D02*
Y85112D01*
G01X1704677Y95753D02*
X1711788Y88642D01*
G01X1654406Y93094D02*
Y94104D01*
G01X1656500Y91000D02*
X1654406Y93094D01*
G01X1656500Y89500D02*
Y91000D01*
G01X1654406Y94104D02*
Y96471D01*
G01X1697520Y50282D02*
Y46400D01*
G01X1693782Y54020D02*
X1697520Y50282D01*
G01X1683404Y54020D02*
X1693782D01*
G01X1672444Y64980D02*
X1683404Y54020D01*
G01X1668968Y64980D02*
X1672444D01*
G01X1666746Y67202D02*
X1668968Y64980D01*
G01X1666746Y70066D02*
Y67202D01*
G01X1664350Y72462D02*
X1666746Y70066D01*
G01X1662500Y70612D02*
X1664350Y72462D01*
G01X1662500Y69662D02*
Y70612D01*
G01X1660966Y68128D02*
X1662500Y69662D01*
G01X1656272Y68128D02*
X1660966D01*
G01X1654100Y70300D02*
X1656272Y68128D01*
G01X1675062Y91219D02*
Y95630D01*
G01X1653000Y77600D02*
Y81750D01*
G01X1653897Y67203D02*
X1650800Y70300D01*
G01X1661591Y67203D02*
X1653897D01*
G01X1664350Y69962D02*
X1661591Y67203D01*
G01X1694960Y51243D02*
Y46400D01*
G01X1693522Y52681D02*
X1694960Y51243D01*
G01X1683218Y52681D02*
X1693522D01*
G01X1671844Y64055D02*
X1683218Y52681D01*
G01X1668584Y64055D02*
X1671844D01*
G01X1665821Y66818D02*
X1668584Y64055D01*
G01X1665821Y68491D02*
Y66818D01*
G01X1664350Y69962D02*
X1665821Y68491D01*
G01X1694500Y82500D02*
X1692500D01*
G01X1696655Y80345D02*
X1694500Y82500D01*
G01X1696655Y77991D02*
Y80345D01*
G01X1689000Y82500D02*
X1692500D01*
G01X1687437Y84063D02*
X1689000Y82500D01*
G01X1687437Y86751D02*
Y84063D01*
G01X1689000Y88314D02*
X1687437Y86751D01*
G01X1689000Y90000D02*
Y88314D01*
G01X1686033Y89967D02*
X1686000Y90000D01*
G01X1688967Y89967D02*
X1686033D01*
G01X1689000Y90000D02*
X1688967Y89967D01*
G01X1698927Y153638D02*
Y153139D01*
G01X1698502Y154063D02*
X1698927Y153638D01*
G01X1691577Y154063D02*
X1698502D01*
G01X1690613Y155027D02*
G03X1691577Y154063I964J0D01*
G01X1690613Y155248D02*
Y155027D01*
G01X1688688Y155248D02*
G02X1690613I962J0D01*
G01X1688688Y155027D02*
Y155248D01*
G01X1687726Y154065D02*
G03X1688688Y155027I0J962D01*
G01X1684735Y154065D02*
X1687726D01*
G01X1684735Y152138D02*
G02Y154065I0J964D01*
G01X1696707Y152138D02*
X1684735D01*
G01X1696707Y150213D02*
G03Y152138I0J962D01*
G01X1682566Y150213D02*
X1696707D01*
G01X1682120Y150197D02*
G02X1682566Y150213I453J-6390D01*
G01X1678325Y148625D02*
G02X1682120Y150197I3795J-3795D01*
G01X1676515Y146815D02*
X1678325Y148625D01*
G01X1673128Y145412D02*
G03X1676515Y146815I0J4790D01*
G01X1668859Y145412D02*
X1673128D01*
G01X1662560Y117066D02*
X1664135Y115491D01*
G01X1693225Y111254D02*
X1695119D01*
G01X1691458Y111986D02*
G03X1693225Y111254I1768J1768D01*
G01X1685853Y117586D02*
X1691458Y111986D01*
G01X1684493Y117586D02*
G02X1685853I680J-680D01*
G01X1684250Y117343D02*
X1684493Y117586D01*
G01X1682890Y117343D02*
G03X1684250I680J680D01*
G01X1682888Y117345D02*
X1682890Y117343D01*
G01X1682888Y118705D02*
G03Y117345I680J-680D01*
G01X1683131Y118948D02*
X1682888Y118705D01*
G01X1683131Y120308D02*
G02Y118948I-680J-680D01*
G01X1683129Y120310D02*
X1683131Y120308D01*
G01X1681769Y120310D02*
G02X1683129I680J-680D01*
G01X1681526Y120067D02*
X1681769Y120310D01*
G01X1680166Y120067D02*
G03X1681526I680J680D01*
G01X1680164Y120069D02*
X1680166Y120067D01*
G01X1680164Y121429D02*
G03Y120069I680J-680D01*
G01X1680407Y121672D02*
X1680164Y121429D01*
G01X1680407Y123032D02*
G02Y121672I-680J-680D01*
G01X1679013Y124426D02*
X1680407Y123032D01*
G01X1675003Y126087D02*
G02X1679013Y124426I0J-5671D01*
G01X1672530Y126087D02*
X1675003D01*
G01X1672122Y125918D02*
G02X1672530Y126087I408J-408D01*
G01X1671480Y125276D02*
X1672122Y125918D01*
G01X1670664Y124938D02*
G03X1671480Y125276I0J1154D01*
G01X1667462Y124938D02*
X1670664D01*
G01X1666501Y125336D02*
G03X1667462Y124938I961J961D01*
G01X1665982Y125855D02*
X1666501Y125336D01*
G01X1665709Y126514D02*
G03X1665982Y125855I933J0D01*
G01X1708773Y111254D02*
X1695119D01*
G01X1712363Y107664D02*
G03X1708773Y111254I-3590J0D01*
G01X1684578Y144438D02*
X1691776D01*
G01X1680156Y142606D02*
G02X1684578Y144438I4422J-4421D01*
G01X1680119Y142569D02*
X1680156Y142606D01*
G01X1679250Y141838D02*
G03X1680119Y142569I-3793J5391D01*
G01X1675458Y140638D02*
G03X1679250Y141838I0J6591D01*
G01X1668586Y140638D02*
X1675458D01*
G01X1667561Y140214D02*
G02X1668586Y140638I1025J-1027D01*
G01X1667386Y140038D02*
X1667561Y140214D01*
G01X1666886Y139538D02*
X1667386Y140038D01*
G01X1665860Y139113D02*
G03X1666886Y139538I0J1451D01*
G01X1665709Y139113D02*
X1665860D01*
G01X1697270Y142438D02*
X1693586D01*
G01X1698233Y141475D02*
G03X1697270Y142438I-963J0D01*
G01X1698233Y139549D02*
Y141475D01*
G01X1699196Y138586D02*
G02X1698233Y139549I0J963D01*
G01X1702603Y138586D02*
X1699196D01*
G01X1702603Y140512D02*
G02Y138586I0J-963D01*
G01X1701122Y140512D02*
X1702603D01*
G01X1701122Y142438D02*
G03Y140512I0J-963D01*
G01X1702655Y142438D02*
X1701122D01*
G01X1702655Y144438D02*
G02Y142438I0J-1000D01*
G01X1691776Y144438D02*
X1702655D01*
G01X1657708Y96888D02*
X1659731D01*
G01X1654818Y99778D02*
X1657708Y96888D01*
G01X1654818Y105910D02*
Y99778D01*
G01X1653111Y107617D02*
X1654818Y105910D01*
G01X1661097Y105930D02*
X1659410Y107617D01*
G01X1661097Y103861D02*
Y105930D01*
G01X1664075Y100883D02*
X1661097Y103861D01*
G01X1664897Y100883D02*
X1664075D01*
G01X1668797Y96983D02*
X1664897Y100883D01*
G01X1669555Y96983D02*
X1668797D01*
G01X1670055Y96483D02*
X1669555Y96983D01*
G01X1659410Y117066D02*
X1660985Y115491D01*
G01X1657671Y106206D02*
X1656260Y107617D01*
G01X1657671Y104109D02*
Y106206D01*
G01X1662013Y99767D02*
X1657671Y104109D01*
G01X1662013Y97534D02*
Y99767D01*
G01X1666440Y119484D02*
X1665709Y120215D01*
G01X1668934Y118450D02*
G02X1666440Y119484I0J3525D01*
G01X1671843Y118450D02*
X1668934D01*
G01X1672968Y117984D02*
G03X1671843Y118450I-1125J-1125D01*
G01X1674194Y116758D02*
X1672968Y117984D01*
G01X1677217Y115507D02*
G02X1674194Y116758I-1J4276D01*
G01X1679972Y115507D02*
X1677217D01*
G01X1681801Y114750D02*
G03X1679972Y115507I-1828J-1829D01*
G01X1681820Y114730D02*
X1681801Y114750D01*
G01X1682615Y113935D02*
X1681820Y114730D01*
G01X1686474Y110076D02*
X1682615Y113935D01*
G01X1688685Y109160D02*
G02X1686474Y110076I0J3126D01*
G01X1707373Y109160D02*
X1688685D01*
G01X1710359Y106174D02*
G03X1707373Y109160I-2986J0D01*
G01X1710359Y97680D02*
Y106174D01*
G01X1665709Y113916D02*
X1667238Y112387D01*
G01X1653111Y110766D02*
X1654686Y109191D01*
G01X1713237Y121230D02*
X1707500D01*
G01X1705725D02*
X1707500D01*
G01X1705300Y121655D02*
X1705725Y121230D01*
G01X1705300Y122700D02*
Y121655D01*
G01X1706100Y123500D02*
X1705300Y122700D01*
G01X1706100Y124950D02*
Y123500D01*
G01X1665709Y117066D02*
X1667284Y115491D01*
G01X1662560Y113916D02*
X1664135Y112341D01*
G01X1653111Y113915D02*
X1654685Y112341D01*
G01X1653111Y113916D02*
Y113915D01*
G01X1660046Y133451D02*
X1659410Y132814D01*
G01X1662186Y134338D02*
G03X1660046Y133451I0J-3025D01*
G01X1670704Y134338D02*
X1662186D01*
G01X1672121Y134925D02*
G02X1670704Y134338I-1417J1417D01*
G01X1672342Y135146D02*
X1672121Y134925D01*
G01X1673950Y135812D02*
G03X1672342Y135146I0J-2274D01*
G01X1675092Y135812D02*
X1673950D01*
G01X1678226Y134514D02*
G03X1675092Y135812I-3134J-3134D01*
G01X1678577Y134163D02*
X1678226Y134514D01*
G01X1679092Y132920D02*
G03X1678577Y134163I-1758J0D01*
G01X1679353Y132290D02*
G02X1679092Y132920I630J630D01*
G01X1692271Y119372D02*
X1679353Y132290D01*
G01X1692272Y119372D02*
X1692271D01*
G01X1712071Y116476D02*
G03X1713034Y115513I963J0D01*
G01X1712071Y118462D02*
Y116476D01*
G01X1710145Y118462D02*
G02X1712071I963J0D01*
G01X1710145Y116476D02*
Y118462D01*
G01X1708219Y116476D02*
G03X1710145I963J0D01*
G01X1708219Y118530D02*
Y116476D01*
G01X1706293Y118530D02*
G02X1708219I963J0D01*
G01X1706293Y116476D02*
Y118530D01*
G01X1704367Y116476D02*
G03X1706293I963J0D01*
G01X1704367Y118531D02*
Y116476D01*
G01X1702441Y118531D02*
G02X1704367I963J0D01*
G01X1702441Y116476D02*
Y118531D01*
G01X1700515Y116476D02*
G03X1702441I963J0D01*
G01X1700515Y118530D02*
Y116476D01*
G01X1698589Y118530D02*
G02X1700515I963J0D01*
G01X1698589Y116476D02*
Y118530D01*
G01X1697626Y115513D02*
G03X1698589Y116476I0J963D01*
G01X1696679Y115513D02*
X1697626D01*
G01X1695742Y115901D02*
G03X1696679Y115513I937J937D01*
G01X1692272Y119371D02*
X1695742Y115901D01*
G01X1692272Y119372D02*
Y119371D01*
G01X1656260Y102340D02*
Y104467D01*
G01X1658100Y100500D02*
X1656260Y102340D01*
G01X1658100Y99400D02*
Y100500D01*
G01X1658154Y99400D02*
X1658100D01*
G01X1670845Y98681D02*
X1673399Y96127D01*
G01X1668265Y98681D02*
X1670845D01*
G01X1665131Y101815D02*
X1668265Y98681D01*
G01X1664502Y101815D02*
X1665131D01*
G01X1662560Y103757D02*
X1664502Y101815D01*
G01X1662560Y104467D02*
Y103757D01*
G01X1653111Y117066D02*
X1654673Y118628D01*
G01X1651599Y102868D02*
Y105979D01*
G01X1651598Y102867D02*
X1651599Y102868D01*
G01X1651598Y101613D02*
Y102867D01*
G01X1657425Y95786D02*
X1651598Y101613D01*
G01X1672653Y151711D02*
X1668859D01*
G01X1674390Y152430D02*
G02X1672653Y151711I-1737J1739D01*
G01X1679250Y157286D02*
X1674390Y152430D01*
G01X1656260Y117066D02*
X1657835Y115491D01*
G01X1679707Y94697D02*
X1679980Y94970D01*
G01X1665709Y106536D02*
Y107617D01*
G01X1667396Y104849D02*
X1665709Y106536D01*
G01X1667396Y103311D02*
Y104849D01*
G01X1669229Y101478D02*
X1667396Y103311D01*
G01X1673472Y101478D02*
X1669229D01*
G01X1679980Y94970D02*
X1673472Y101478D01*
G01X1656260Y113916D02*
X1657835Y112341D01*
G01X1670286Y148562D02*
X1668859D01*
G01X1675508Y150725D02*
G02X1670286Y148562I-5222J5222D01*
G01X1686930Y162147D02*
X1675508Y150725D01*
G01X1697653Y156951D02*
G02X1695727I-963J0D01*
G01X1696650Y99334D02*
X1696907Y99077D01*
G01X1696650Y102000D02*
Y99334D01*
G01X1706596Y103254D02*
Y95656D01*
G01X1702650Y107200D02*
X1706596Y103254D01*
G01X1684739Y107200D02*
X1702650D01*
G01X1678023Y113916D02*
X1684739Y107200D01*
G01X1668859Y113916D02*
X1678023D01*
G01X1711413Y142959D02*
G02X1713339I963J0D01*
G01X1711413Y134670D02*
Y142959D01*
G01X1709487Y134670D02*
G03X1711413I963J0D01*
G01X1709487Y143230D02*
Y134670D01*
G01X1707561Y143230D02*
G02X1709487I963J0D01*
G01X1707561Y134761D02*
Y143230D01*
G01X1705635Y134761D02*
G03X1707561I963J0D01*
G01X1705635Y144336D02*
Y134761D01*
G01X1704928Y146043D02*
G02X1705635Y144336I-1707J-1707D01*
G01X1704155Y146363D02*
G02X1704928Y146043I0J-1093D01*
G01X1702140Y146363D02*
X1704155D01*
G01X1673440Y142262D02*
X1668859D01*
G01X1678943Y144145D02*
G02X1673440Y142262I-5503J7100D01*
G01X1678944Y144146D02*
X1678943Y144145D01*
G01X1679250Y144435D02*
G03X1678944Y144146I5043J-5646D01*
G01X1684297Y146363D02*
G03X1679250Y144435I0J-7570D01*
G01X1702140Y146363D02*
X1684297D01*
G01X1653111Y102240D02*
Y104467D01*
G01X1665709Y103832D02*
Y104467D01*
G01X1668995Y100546D02*
X1665709Y103832D01*
G01X1671854Y100546D02*
X1668995D01*
G01X1659410Y103894D02*
Y104467D01*
G01X1659467Y103837D02*
X1659410Y103894D01*
G01X1659468Y103837D02*
X1659467D01*
G01X1661337Y101968D02*
X1659468Y103837D01*
G01X1661337Y101967D02*
Y101968D01*
G01X1662887Y100417D02*
X1661337Y101967D01*
G01X1662887Y98332D02*
Y100417D01*
G01X1663832Y97387D02*
X1662887Y98332D01*
G01X1665993Y97387D02*
X1663832D01*
G01X1664246Y109080D02*
X1662560Y110766D01*
G01X1666592Y109080D02*
X1664246D01*
G01X1667238Y108434D02*
X1666592Y109080D01*
G01X1667238Y106921D02*
Y108434D01*
G01X1668005Y106154D02*
X1667238Y106921D01*
G01X1669234Y106154D02*
X1668005D01*
G01X1669458Y105930D02*
X1669234Y106154D01*
G01X1669465Y105930D02*
X1669458D01*
G01X1670322Y105073D02*
X1669465Y105930D01*
G01X1670322Y105066D02*
Y105073D01*
G01X1670350Y105038D02*
X1670322Y105066D01*
G01X1675969Y105038D02*
X1670350D01*
G01X1676640Y104367D02*
X1675969Y105038D01*
G01X1676640Y101752D02*
Y104367D01*
G01X1677506Y100886D02*
X1676640Y101752D01*
G01X1680890Y100886D02*
X1679250D01*
G01X1685578Y96198D02*
X1680890Y100886D01*
G01X1685578Y94887D02*
Y96198D01*
G01X1685976Y98962D02*
X1686876D01*
G01X1678288Y106650D02*
X1685976Y98962D01*
G01X1670489Y106650D02*
X1678288D01*
G01X1669522Y107617D02*
X1670489Y106650D01*
G01X1668859Y107617D02*
X1669522D01*
G01X1710100Y149564D02*
X1717014Y142650D01*
G01X1710100Y153550D02*
Y149564D01*
G01X1712026Y153550D02*
G03X1710100I-963J0D01*
G01X1712026Y151150D02*
Y153550D01*
G01X1713952Y151150D02*
G02X1712026I-963J0D01*
G01X1709380Y113250D02*
X1701890D01*
G01X1714389Y108241D02*
G03X1709380Y113250I-5009J0D01*
G01X1695865D02*
X1701890D01*
G01X1695003Y113607D02*
G03X1695865Y113250I862J862D01*
G01X1683329Y125281D02*
X1695003Y113607D01*
G01X1680625Y126401D02*
G02X1683329Y125281I0J-3824D01*
G01X1679441Y126658D02*
G03X1680625Y126401I1184J2599D01*
G01X1679250Y126745D02*
X1679441Y126658D01*
G01X1678791Y126954D02*
X1679250Y126745D01*
G01X1678486Y127165D02*
G03X1678791Y126954I731J731D01*
G01X1677233Y127684D02*
G02X1678486Y127165I0J-1772D01*
G01X1671682Y127684D02*
X1677233D01*
G01X1668860Y126515D02*
G02X1671682Y127684I2822J-2822D01*
G01X1668859Y126514D02*
X1668860Y126515D01*
G01X1656260Y120215D02*
X1657835Y118640D01*
G01X1666700Y146403D02*
X1665709Y145412D01*
G01X1668113Y146988D02*
G03X1666700Y146403I0J-1999D01*
G01X1671675Y146988D02*
X1668113D01*
G01X1676559Y149011D02*
G02X1671675Y146988I-4884J4884D01*
G01X1684722Y157174D02*
X1676559Y149011D01*
G01X1659410Y110766D02*
X1660985Y109191D01*
G01X1656260Y110766D02*
X1657835Y109191D01*
G01X1662561Y142262D02*
X1662560D01*
G01X1663677Y143378D02*
X1662561Y142262D01*
G01X1664786Y143838D02*
G03X1663677Y143378I0J-1567D01*
G01X1672900Y143838D02*
X1664786D01*
G01X1676492Y144696D02*
G02X1672900Y143838I-3593J7095D01*
G01X1677462Y145399D02*
G02X1676492Y144696I-2686J2685D01*
G01X1678534Y146471D02*
X1677462Y145399D01*
G01X1682921Y148288D02*
G03X1678534Y146471I0J-6205D01*
G01X1706879Y148288D02*
X1682921D01*
G01X1708175Y149584D02*
G02X1706879Y148288I-1296J0D01*
G01X1708175Y155783D02*
Y149584D01*
G01X1706976Y156982D02*
G02X1708175Y155783I0J-1199D01*
G01X1703744Y155056D02*
G02Y156982I0J963D01*
G01X1705238Y155056D02*
X1703744D01*
G01X1705238Y153101D02*
G03Y155056I0J978D01*
G01X1701473Y153101D02*
X1705238D01*
G01X1701455Y153083D02*
X1701473Y153101D01*
G01X1672932Y153780D02*
X1683692Y164541D01*
G01X1671745Y153288D02*
G03X1672932Y153780I0J1678D01*
G01X1666596Y153288D02*
X1671745D01*
G01X1665997Y153040D02*
G02X1666596Y153288I599J-599D01*
G01X1665994Y153037D02*
X1665997Y153040D01*
G01X1665709Y152349D02*
G02X1665994Y153037I973J0D01*
G01X1665709Y151711D02*
Y152349D01*
G01X1704677Y102773D02*
Y95753D01*
G01X1701950Y105500D02*
X1704677Y102773D01*
G01X1700000Y105500D02*
X1701950D01*
G01X1696650D02*
X1700000D01*
G01X1688800Y104300D02*
X1690870D01*
G01X1687600Y105500D02*
X1688800Y104300D01*
G01X1682899Y105500D02*
X1687600D01*
G01X1679011Y109388D02*
X1682899Y105500D01*
G01X1672111Y109388D02*
X1679011D01*
G01X1670733Y110766D02*
X1672111Y109388D01*
G01X1668859Y110766D02*
X1670733D01*
G01X1694000Y105500D02*
X1696650D01*
G01X1692800Y104300D02*
X1694000Y105500D01*
G01X1690870Y104300D02*
X1692800D01*
G01X1670886Y154861D02*
X1668859D01*
G01X1671488Y155111D02*
G02X1670886Y154861I-603J602D01*
G01X1679250Y162871D02*
X1671488Y155111D01*
G01X1666573Y110766D02*
X1665709D01*
G01X1668036Y109303D02*
X1666573Y110766D01*
G01X1669586Y109303D02*
X1668036D01*
G01X1670851Y108038D02*
X1669586Y109303D01*
G01X1678814Y108038D02*
X1670851D01*
G01X1683783Y103069D02*
X1678814Y108038D01*
G01X1685622Y103069D02*
X1683783D01*
G01X1689348Y98750D02*
X1689368D01*
G01X1689348Y100102D02*
Y98750D01*
G01X1686381Y103069D02*
X1689348Y100102D01*
G01X1685622Y103069D02*
X1686381D01*
G01X1662560Y120215D02*
X1664135Y118640D01*
G01X1659410Y113916D02*
X1660985Y112341D01*
G01X1682096Y140928D02*
X1681586Y141438D01*
G01X1683433Y140928D02*
X1682096D01*
G01X1684020Y141515D02*
X1683433Y140928D01*
G01X1684020Y142025D02*
Y141515D01*
G01X1662560Y106923D02*
Y107617D01*
G01X1664246Y105237D02*
X1662560Y106923D01*
G01X1664246Y103861D02*
Y105237D01*
G01X1665103Y103004D02*
X1664246Y103861D01*
G01X1665108Y103004D02*
X1665103D01*
G01X1668607Y99505D02*
X1665108Y103004D01*
G01X1670503Y99505D02*
X1668607D01*
G01X1670504Y99506D02*
X1670503Y99505D01*
G01X1671186Y99506D02*
X1670504D01*
G01X1671187Y99505D02*
X1671186Y99506D01*
G01X1671200Y99505D02*
X1671187D01*
G01X1673693Y97012D02*
X1671200Y99505D01*
G01X1673693Y96999D02*
Y97012D01*
G01X1675062Y95630D02*
X1673693Y96999D01*
G01X1668859Y117066D02*
X1670434Y115491D01*
G01X1659410Y120215D02*
X1660985Y118640D01*
G01X1658500Y178515D02*
Y179742D01*
G01X1656535Y176550D02*
X1658500Y178515D01*
G01X1656535Y170884D02*
Y176550D01*
G01X1656260Y170609D02*
X1656535Y170884D01*
G01X1659949Y186814D02*
Y189288D01*
G01X1660200Y186563D02*
X1659949Y186814D01*
G01X1660200Y183601D02*
Y186563D01*
G01X1658500Y181901D02*
X1660200Y183601D01*
G01X1658500Y179742D02*
Y181901D01*
G01X1689421Y192179D02*
X1692312D01*
G01X1687600Y194000D02*
X1689421Y192179D01*
G01X1684600Y194000D02*
X1687600D01*
G01X1692312Y195886D02*
Y192179D01*
G01X1693242Y196816D02*
X1692312Y195886D01*
G01X1693242Y198749D02*
Y196816D01*
G01X1691439Y174595D02*
Y174354D01*
G01X1692556Y175712D02*
X1691439Y174595D01*
G01X1692556Y176594D02*
Y175712D01*
G01X1693343Y177381D02*
X1692556Y176594D01*
G01X1693344Y177380D02*
X1693343Y177381D01*
G01X1696368Y177380D02*
X1693344D01*
G01X1657534Y198059D02*
X1656235Y199358D01*
G01X1661353Y198059D02*
X1657534D01*
G01X1662269Y198975D02*
X1661353Y198059D01*
G01X1662269Y201716D02*
Y198975D01*
G01X1660040Y203945D02*
X1662269Y201716D01*
G01X1659471Y203945D02*
X1660040D01*
G01X1657996Y205420D02*
X1659471Y203945D01*
G01X1657996Y210329D02*
Y205420D01*
G01X1658458Y210791D02*
X1657996Y210329D01*
G01X1667697Y210791D02*
X1658458D01*
G01X1669064Y212158D02*
X1667697Y210791D01*
G01X1669064Y216736D02*
Y212158D01*
G01X1684392Y170746D02*
X1679062Y165416D01*
G01X1692845Y170746D02*
X1684392D01*
G01X1654015Y217239D02*
X1653313Y217941D01*
G01X1668377Y185245D02*
X1668519Y185387D01*
G01X1666944Y185245D02*
X1668377D01*
G01X1665500Y183801D02*
X1666944Y185245D01*
G01X1665500Y181100D02*
Y183801D01*
G01X1666300Y180300D02*
X1665500Y181100D01*
G01X1666300Y178546D02*
Y180300D01*
G01X1660963Y173209D02*
X1666300Y178546D01*
G01X1660963Y169012D02*
Y173209D01*
G01X1659410Y167459D02*
X1660963Y169012D01*
G01X1667349Y188684D02*
Y189288D01*
G01X1668519Y187514D02*
X1667349Y188684D01*
G01X1668519Y185387D02*
Y187514D01*
G01X1666545Y207858D02*
X1659985D01*
G01X1669990Y211303D02*
X1666545Y207858D01*
G01X1669990Y218210D02*
Y211303D01*
G01X1658311Y202918D02*
X1660440Y200789D01*
G01X1652927Y202918D02*
X1658311D01*
G01X1698611Y180389D02*
Y183518D01*
G01X1699868Y179132D02*
X1698611Y180389D01*
G01X1699868Y177380D02*
Y179132D01*
G01X1667299Y165900D02*
X1665709Y164310D01*
G01X1669400Y165900D02*
X1667299D01*
G01X1670400Y166900D02*
X1669400Y165900D01*
G01X1670400Y168601D02*
Y166900D01*
G01X1671189Y169390D02*
X1670400Y168601D01*
G01X1671189Y176965D02*
Y169390D01*
G01X1676624Y182400D02*
X1671189Y176965D01*
G01X1676624Y185521D02*
Y182400D01*
G01X1676849Y185746D02*
Y189288D01*
G01X1676624Y185521D02*
X1676849Y185746D01*
G01X1699900Y174350D02*
X1703350D01*
G01X1707100Y176600D02*
Y188300D01*
G01X1704850Y174350D02*
X1707100Y176600D01*
G01X1703350Y174350D02*
X1704850D01*
G01X1653111Y161161D02*
X1654685Y162735D01*
G01X1653111Y161160D02*
Y161161D01*
G01X1685570Y163601D02*
X1679250Y157286D01*
G01X1686656Y164365D02*
G03X1685570Y163601I1658J-3511D01*
G01X1688871Y164863D02*
G03X1686656Y164365I0J-5176D01*
G01X1689942Y164863D02*
X1688871D01*
G01X1690992Y165298D02*
G02X1689942Y164863I-1050J1050D01*
G01X1692187Y166493D02*
X1690992Y165298D01*
G01X1692762Y166731D02*
G03X1692187Y166493I0J-814D01*
G01X1701866Y166731D02*
X1692762D01*
G01X1701866Y164676D02*
G03Y166731I0J1028D01*
G01X1695734Y164676D02*
X1701866D01*
G01X1689843Y176244D02*
Y177381D01*
G01X1688046Y174447D02*
X1689843Y176244D01*
G01X1694431Y174350D02*
X1696400D01*
G01X1694431Y174342D02*
Y174350D01*
G01X1692260Y172171D02*
X1694431Y174342D01*
G01X1682655Y172171D02*
X1692260D01*
G01X1680901Y170417D02*
X1682655Y172171D01*
G01X1679100Y168616D02*
X1680901Y170417D01*
G01X1679100Y168100D02*
Y168616D01*
G01X1670585Y159585D02*
X1679100Y168100D01*
G01X1668507Y159585D02*
X1670585D01*
G01X1666932Y158010D02*
X1668507Y159585D01*
G01X1665709Y158010D02*
X1666932D01*
G01X1668859Y168359D02*
Y167459D01*
G01X1670344Y169844D02*
X1668859Y168359D01*
G01X1670344Y177399D02*
Y169844D01*
G01X1674912Y181967D02*
X1670344Y177399D01*
G01X1674912Y183000D02*
Y181967D01*
G01X1651000Y177900D02*
Y178628D01*
G01X1684550Y186050D02*
Y187970D01*
G01X1685930Y184670D02*
X1684550Y186050D01*
G01X1685930Y181039D02*
Y184670D01*
G01X1685492Y180601D02*
X1685930Y181039D01*
G01X1683340Y180601D02*
X1685492D01*
G01X1667396Y162847D02*
X1665709Y161160D01*
G01X1669465Y162847D02*
X1667396D01*
G01X1672843Y166225D02*
X1669465Y162847D01*
G01X1672843Y173353D02*
Y166225D01*
G01X1673769Y174279D02*
X1672843Y173353D01*
G01X1676832Y174279D02*
X1673769D01*
G01X1680776Y178223D02*
X1676832Y174279D01*
G01X1680776Y179325D02*
Y178223D01*
G01X1682052Y180601D02*
X1680776Y179325D01*
G01X1683340Y180601D02*
X1682052D01*
G01X1679849Y193806D02*
X1676924Y196731D01*
G01X1679849Y192788D02*
Y193806D01*
G01X1688805Y162923D02*
G03X1686930Y162147I-1J-2652D01*
G01X1690807Y162923D02*
X1688805D01*
G01X1691875Y161855D02*
G03X1690807Y162923I-1068J0D01*
G01X1691875Y157498D02*
Y161855D01*
G01X1693801Y157498D02*
G02X1691875I-963J0D01*
G01X1693801Y161855D02*
Y157498D01*
G01X1695727Y161855D02*
G03X1693801I-963J0D01*
G01X1695727Y156951D02*
Y161855D01*
G01X1698425Y157723D02*
G03X1697653Y156951I0J-772D01*
G01X1699676Y157723D02*
X1698425D01*
G01X1699676Y159648D02*
G02Y157723I0J-962D01*
G01X1698615Y159648D02*
X1699676D01*
G01X1697653Y160610D02*
G03X1698615Y159648I962J0D01*
G01X1697653Y161855D02*
Y160610D01*
G01X1698400Y162602D02*
G03X1697653Y161855I0J-747D01*
G01X1700346Y162602D02*
X1698400D01*
G01X1700836Y162112D02*
G03X1700346Y162602I-490J0D01*
G01X1700836Y161268D02*
Y162112D01*
G01X1664023Y168922D02*
X1662560Y167459D01*
G01X1664023Y171215D02*
Y168922D01*
G01X1663384Y171854D02*
X1664023Y171215D01*
G01X1663384Y173074D02*
Y171854D01*
G01X1668752Y178442D02*
X1663384Y173074D01*
G01X1668752Y182632D02*
Y178442D01*
G01X1670632Y184512D02*
X1668752Y182632D01*
G01X1670632Y187806D02*
Y184512D01*
G01X1669957Y188481D02*
X1670632Y187806D01*
G01X1669957Y193067D02*
Y188481D01*
G01X1669849Y193067D02*
X1669957D01*
G01X1673530Y204693D02*
X1669405Y200568D01*
G01X1673530Y209974D02*
Y204693D01*
G01X1657966Y169165D02*
X1656260Y167459D01*
G01X1657966Y176467D02*
Y169165D01*
G01X1662500Y181001D02*
X1657966Y176467D01*
G01X1662500Y182536D02*
Y181001D01*
G01X1661211Y183825D02*
X1662500Y182536D01*
G01X1661211Y186404D02*
Y183825D01*
G01X1661937Y187130D02*
X1661211Y186404D01*
G01X1661937Y197075D02*
Y187130D01*
G01X1662362Y197500D02*
X1661937Y197075D01*
G01X1666337Y197500D02*
X1662362D01*
G01X1669405Y200568D02*
X1666337Y197500D01*
G01X1662560Y164310D02*
X1660985Y165885D01*
G01X1711814Y157833D02*
X1713952Y155695D01*
G01X1711814Y163406D02*
Y157833D01*
G01X1714189Y165781D02*
X1711814Y163406D01*
G01X1685730Y157174D02*
G03X1684722I-504J-504D01*
G01X1686738D02*
G02X1685730I-504J504D01*
G01X1687092Y157528D02*
X1686738Y157174D01*
G01X1687092Y158536D02*
G02Y157528I-504J-504D01*
G01Y159544D02*
G03Y158536I504J-504D01*
G01X1687871Y160323D02*
X1687092Y159544D01*
G01X1689199Y160873D02*
G03X1687871Y160323I0J-1878D01*
G01X1689201Y160875D02*
X1689199Y160873D01*
G01X1689480Y160875D02*
X1689201D01*
G01X1689785Y161180D02*
X1689480Y160875D01*
G01X1683340Y175340D02*
Y177101D01*
G01X1681386Y173386D02*
X1683340Y175340D01*
G01X1678286Y173386D02*
X1681386D01*
G01X1677600Y172700D02*
X1678286Y173386D01*
G01X1710586Y202900D02*
X1716191Y197295D01*
G01X1693923Y202900D02*
X1710586D01*
G01X1687781Y196758D02*
X1693923Y202900D01*
G01X1683642Y196758D02*
X1687781D01*
G01X1678815Y199986D02*
X1683642Y196758D01*
G01X1678815Y215590D02*
Y199986D01*
G01X1710120Y171380D02*
Y172616D01*
G01X1710650Y170850D02*
X1710120Y171380D01*
G01X1710650Y169700D02*
Y170850D01*
G01X1710120Y173280D02*
X1708350Y175050D01*
G01X1710120Y172616D02*
Y173280D01*
G01X1651319Y213437D02*
Y212708D01*
G01X1652695Y214813D02*
X1651319Y213437D01*
G01X1654153Y214813D02*
X1652695D01*
G01X1655316Y215976D02*
X1654153Y214813D01*
G01X1660599Y215976D02*
X1655316D01*
G01X1663566Y213009D02*
X1660599Y215976D01*
G01X1673800Y200579D02*
Y201070D01*
G01X1672120Y198899D02*
X1673800Y200579D01*
G01X1672120Y190000D02*
Y198899D01*
G01X1667172Y168922D02*
X1665709Y167459D01*
G01X1667172Y171511D02*
Y168922D01*
G01X1666701Y171982D02*
X1667172Y171511D01*
G01X1666701Y175118D02*
Y171982D01*
G01X1673300Y181717D02*
X1666701Y175118D01*
G01X1673300Y187400D02*
Y181717D01*
G01X1672120Y188580D02*
X1673300Y187400D01*
G01X1672120Y190000D02*
Y188580D01*
G01X1653300Y188639D02*
X1653949Y189288D01*
G01X1653300Y186869D02*
Y188639D01*
G01X1652218Y185787D02*
X1653300Y186869D01*
G01X1652218Y182351D02*
Y185787D01*
G01X1651748Y168822D02*
X1653111Y167459D01*
G01X1651748Y175823D02*
Y168822D01*
G01X1652765Y176840D02*
X1651748Y175823D01*
G01X1652765Y181804D02*
Y176840D01*
G01X1652218Y182351D02*
X1652765Y181804D01*
G01X1656949Y189288D02*
Y186868D01*
G01X1658000Y183400D02*
Y185337D01*
G01X1657600Y183000D02*
X1658000Y183400D01*
G01X1657600Y179273D02*
Y183000D01*
G01X1654897Y176570D02*
X1657600Y179273D01*
G01X1654897Y166096D02*
Y176570D01*
G01X1653111Y164310D02*
X1654897Y166096D01*
G01X1703744Y156982D02*
X1706976D01*
G01X1703183Y161214D02*
X1703610D01*
G01X1702758Y160789D02*
G02X1703183Y161214I425J0D01*
G01X1702758Y159652D02*
Y160789D01*
G01X1703398Y159012D02*
G02X1702758Y159652I0J640D01*
G01X1705826Y159012D02*
X1703398D01*
G01X1706286Y159472D02*
G02X1705826Y159012I-460J0D01*
G01X1707248Y160434D02*
G03X1706286Y159472I0J-962D01*
G01X1708873Y160434D02*
X1707248D01*
G01X1708873Y162359D02*
G02Y160434I0J-962D01*
G01X1707248Y162359D02*
X1708873D01*
G01X1706286Y163321D02*
G03X1707248Y162359I962J0D01*
G01X1706286Y167171D02*
Y163321D01*
G01X1705836Y168257D02*
G02X1706286Y167171I-1086J-1086D01*
G01X1704752Y168706D02*
G02X1705836Y168257I0J-1533D01*
G01X1703682Y168706D02*
X1704752D01*
G01X1702720Y169668D02*
G03X1703682Y168706I962J0D01*
G01X1702720Y169745D02*
Y169668D01*
G01X1700795Y169745D02*
G02X1702720I962J0D01*
G01X1700795Y169664D02*
Y169745D01*
G01X1698870Y169664D02*
G03X1700795I962J0D01*
G01X1698870Y169745D02*
Y169664D01*
G01X1696945Y169745D02*
G02X1698870I962J0D01*
G01X1696945Y169668D02*
Y169745D01*
G01X1695983Y168706D02*
G03X1696945Y169668I0J962D01*
G01X1692428Y168706D02*
X1695983D01*
G01X1689714Y167582D02*
G02X1692428Y168706I2714J-2714D01*
G01X1689657Y167525D02*
X1689714Y167582D01*
G01X1687805Y166758D02*
G03X1689657Y167525I0J2619D01*
G01X1684219Y165015D02*
G02X1687805Y166758I4312J-4312D01*
G01X1683692Y164541D02*
G02X1684219Y165015I4687J-4681D01*
G01X1676750Y206050D02*
Y214350D01*
G01X1669010Y164310D02*
X1668859D01*
G01X1671300Y166600D02*
X1669010Y164310D01*
G01X1671300Y168300D02*
Y166600D01*
G01X1672019Y169019D02*
X1671300Y168300D01*
G01X1672019Y176566D02*
Y169019D01*
G01X1675053Y179600D02*
X1672019Y176566D01*
G01X1678400Y179600D02*
X1675053D01*
G01X1679849Y188359D02*
Y189288D01*
G01X1678740Y187250D02*
X1679849Y188359D01*
G01X1678740Y179940D02*
Y187250D01*
G01X1678400Y179600D02*
X1678740Y179940D01*
G01X1683955Y167575D02*
X1679250Y162871D01*
G01X1687329Y168972D02*
G03X1683955Y167575I-1J-4770D01*
G01X1688207Y168972D02*
X1687329D01*
G01X1662560Y173417D02*
Y170609D01*
G01X1667140Y177997D02*
X1662560Y173417D01*
G01X1667140Y182300D02*
Y177997D01*
G01X1663434Y181966D02*
Y185008D01*
G01X1665300Y180100D02*
X1663434Y181966D01*
G01X1665300Y178890D02*
Y180100D01*
G01X1659410Y173000D02*
X1665300Y178890D01*
G01X1659410Y170609D02*
Y173000D01*
G01X1664349Y185923D02*
Y189288D01*
G01X1663434Y185008D02*
X1664349Y185923D01*
G01X1653313Y217941D02*
Y220137D01*
G01X1689455Y262800D02*
X1834049D01*
G01X1689384Y262871D02*
X1689455Y262800D01*
G01X1685177Y262871D02*
X1689384D01*
G01X1677437Y270611D02*
X1685177Y262871D01*
G01X1677437Y289131D02*
Y270611D01*
G01X1675200Y266719D02*
Y286341D01*
G01X1681573Y260346D02*
X1675200Y266719D01*
G01X1684193Y260346D02*
X1681573D01*
G01X1684194Y260345D02*
X1684193Y260346D01*
G01X1832143Y260345D02*
X1684194D01*
G01X1672525Y264692D02*
Y285231D01*
G01X1679547Y257670D02*
X1672525Y264692D01*
G01X1829948Y257670D02*
X1679547D01*
G01X1658351Y221400D02*
X1658750D01*
G01X1651575Y228176D02*
X1658351Y221400D01*
G01X1651575Y232225D02*
Y228176D01*
G01X1668100Y262856D02*
Y282652D01*
G01X1677848Y253108D02*
X1668100Y262856D01*
G01X1729957Y253108D02*
X1677848D01*
G01X1669750Y263540D02*
Y284079D01*
G01X1678532Y254758D02*
X1669750Y263540D01*
G01X1805058Y254758D02*
X1678532D01*
G01X1668925Y263198D02*
Y283737D01*
G01X1678190Y253933D02*
X1668925Y263198D01*
G01X1762280Y253933D02*
X1678190D01*
G01X1676300Y267635D02*
Y286797D01*
G01X1682164Y261771D02*
X1676300Y267635D01*
G01X1688928Y261771D02*
X1682164D01*
G01X1689099Y261600D02*
X1688928Y261771D01*
G01X1832904Y261600D02*
X1689099D01*
G01X1674375Y265460D02*
Y285999D01*
G01X1680315Y259520D02*
X1674375Y265460D01*
G01X1831801Y259520D02*
X1680315D01*
G01X1670675Y263924D02*
Y284463D01*
G01X1678916Y255683D02*
X1670675Y263924D01*
G01X1822558Y255683D02*
X1678916D01*
G01X1673450Y265076D02*
Y285615D01*
G01X1679931Y258595D02*
X1673450Y265076D01*
G01X1831039Y258595D02*
X1679931D01*
G01X1679300Y256608D02*
X1823395D01*
G01X1671600Y264308D02*
X1679300Y256608D01*
G01X1671600Y284847D02*
Y264308D01*
G01X1677100Y296500D02*
X1679100Y294500D01*
G01X1677100Y306499D02*
Y296500D01*
G01X1679916Y309315D02*
X1677100Y306499D01*
G01X1679916Y431349D02*
Y309315D01*
G01X1666257Y300311D02*
X1677437Y289131D01*
G01X1666257Y309105D02*
Y300311D01*
G01X1665142Y310220D02*
X1666257Y309105D01*
G01X1663764Y310220D02*
X1665142D01*
G01X1661114Y307570D02*
X1663764Y310220D01*
G01X1650735Y307570D02*
X1661114D01*
G01X1659226Y316000D02*
X1656500D01*
G01X1662100Y318874D02*
X1659226Y316000D01*
G01X1662174Y318874D02*
X1662100D01*
G01X1663800Y320500D02*
X1662174Y318874D01*
G01X1663800Y323200D02*
Y320500D01*
G01X1663059Y323941D02*
X1663800Y323200D01*
G01X1656500Y323941D02*
X1663059D01*
G01X1656500Y325100D02*
Y323941D01*
G01X1657150Y325750D02*
X1656500Y325100D01*
G01X1661150Y325750D02*
X1657150D01*
G01X1662000Y326600D02*
X1661150Y325750D01*
G01X1662000Y328750D02*
Y326600D01*
G01X1666713Y319814D02*
Y343363D01*
G01X1658500Y311601D02*
X1666713Y319814D01*
G01X1653925Y311601D02*
X1658500D01*
G01X1653500Y312026D02*
X1653925Y311601D01*
G01X1653500Y313236D02*
Y312026D01*
G01X1659263Y305189D02*
X1657852Y306600D01*
G01X1659263Y302278D02*
Y305189D01*
G01X1675200Y286341D02*
X1659263Y302278D01*
G01X1672525Y285231D02*
X1658604Y299152D01*
G01X1667638Y318837D02*
Y343747D01*
G01X1659211Y310410D02*
X1667638Y318837D01*
G01X1652659Y310410D02*
X1659211D01*
G01X1651966Y311103D02*
X1652659Y310410D01*
G01X1652354Y308939D02*
X1651115Y310178D01*
G01X1659338Y308939D02*
X1652354D01*
G01X1669063Y318664D02*
X1659338Y308939D01*
G01X1669063Y344237D02*
Y318664D01*
G01X1659864Y290888D02*
X1655198D01*
G01X1668100Y282652D02*
X1659864Y290888D01*
G01X1669750Y284079D02*
X1658525Y295304D01*
G01X1658183Y294479D02*
X1655669D01*
G01X1668925Y283737D02*
X1658183Y294479D01*
G01X1664471Y308539D02*
X1664453Y308557D01*
G01X1664471Y298626D02*
Y308539D01*
G01X1676300Y286797D02*
X1664471Y298626D01*
G01X1657974Y302400D02*
X1654900D01*
G01X1674375Y285999D02*
X1657974Y302400D01*
G01X1658142Y296230D02*
X1658141Y296229D01*
G01X1658908Y296230D02*
X1658142D01*
G01X1670675Y284463D02*
X1658908Y296230D01*
G01X1676000Y295100D02*
X1679100Y292000D01*
G01X1676000Y306849D02*
Y295100D01*
G01X1678891Y309740D02*
X1676000Y306849D01*
G01X1678891Y431857D02*
Y309740D01*
G01X1673450Y285615D02*
X1658988Y300077D01*
G01X1659291Y297156D02*
X1671600Y284847D01*
G01X1658525Y297156D02*
X1659291D01*
G01X1658524Y297155D02*
X1658525Y297156D01*
G01X1657758Y297155D02*
X1658524D01*
G01X1657757Y297154D02*
X1657758Y297155D01*
G01X1654770Y399145D02*
X1654325Y398700D01*
G01X1672413Y366641D02*
Y433732D01*
G01X1656209Y350437D02*
X1672413Y366641D01*
G01X1651497Y350437D02*
X1656209D01*
G01X1650523Y353037D02*
Y351411D01*
G01X1663576Y346500D02*
X1655600D01*
G01X1666713Y343363D02*
X1663576Y346500D01*
G01X1651950D02*
X1655600D01*
G01X1662435Y348950D02*
X1651550D01*
G01X1667638Y343747D02*
X1662435Y348950D01*
G01X1673338Y365738D02*
Y433203D01*
G01X1660700Y353100D02*
X1673338Y365738D01*
G01X1660700Y351600D02*
Y353100D01*
G01X1661700Y351600D02*
X1669063Y344237D01*
G01X1660700Y351600D02*
X1661700D01*
G01X1657119Y401687D02*
Y401669D01*
G01X1655498Y403308D02*
X1657119Y401687D01*
G01X1654951Y456251D02*
X1654400Y455700D01*
G01X1661470Y456251D02*
X1654951D01*
G01X1656000Y452300D02*
Y451750D01*
G01X1654400Y453900D02*
X1656000Y452300D01*
G01X1654400Y455700D02*
Y453900D01*
G01X1667025Y427025D02*
X1667809Y427809D01*
G01X1665725Y427025D02*
X1667025D01*
G01X1664500Y428250D02*
X1665725Y427025D01*
G01X1652037Y428250D02*
X1664500D01*
G01X1664762Y435653D02*
Y438035D01*
G01X1661424Y432315D02*
X1664762Y435653D01*
G01X1652505Y432315D02*
X1661424D01*
G01X1659050Y408050D02*
Y410500D01*
G01X1657984Y406984D02*
X1659050Y408050D01*
G01X1657984Y403994D02*
Y406984D01*
G01X1681172Y459781D02*
Y470072D01*
G01X1678008Y456617D02*
X1681172Y459781D01*
G01X1678008Y446131D02*
Y456617D01*
G01X1675715Y443838D02*
X1678008Y446131D01*
G01X1675715Y441648D02*
Y443838D01*
G01X1676828Y440535D02*
X1675715Y441648D01*
G01X1676828Y438147D02*
Y440535D01*
G01X1672413Y433732D02*
X1676828Y438147D01*
G01X1683564Y434997D02*
X1679916Y431349D01*
G01X1723189Y434997D02*
X1683564D01*
G01X1666748Y431750D02*
X1667649Y430849D01*
G01X1665350Y431750D02*
X1666748D01*
G01X1663465Y429865D02*
X1665350Y431750D01*
G01X1651636Y429865D02*
X1663465D01*
G01X1682097Y459397D02*
Y469497D01*
G01X1678933Y456233D02*
X1682097Y459397D01*
G01X1678933Y445747D02*
Y456233D01*
G01X1676640Y443454D02*
X1678933Y445747D01*
G01X1676640Y442076D02*
Y443454D01*
G01X1676718Y441998D02*
X1676640Y442076D01*
G01X1676718Y441954D02*
Y441998D01*
G01X1677753Y440919D02*
X1676718Y441954D01*
G01X1677753Y437618D02*
Y440919D01*
G01X1673338Y433203D02*
X1677753Y437618D01*
G01X1655550Y408011D02*
X1653310Y405771D01*
G01X1655550Y410500D02*
Y408011D01*
G01X1666414Y432975D02*
X1667588Y434149D01*
G01X1665125Y432975D02*
X1666414D01*
G01X1663040Y430890D02*
X1665125Y432975D01*
G01X1650791Y430890D02*
X1663040D01*
G01X1652042Y403308D02*
X1655498D01*
G01X1651147Y404203D02*
X1652042Y403308D01*
G01X1651147Y407497D02*
Y404203D01*
G01X1652050Y408400D02*
X1651147Y407497D01*
G01X1652050Y410500D02*
Y408400D01*
G01X1683153Y436119D02*
X1678891Y431857D01*
G01X1718887Y436119D02*
X1683153D01*
G01X1667729Y425700D02*
Y424621D01*
G01X1667429Y426000D02*
X1667729Y425700D01*
G01X1665300Y426000D02*
X1667429D01*
G01X1664075Y427225D02*
X1665300Y426000D01*
G01X1652462Y427225D02*
X1664075D01*
G01X1666847Y446453D02*
X1666200Y447100D01*
G01X1669816Y446453D02*
X1666847D01*
G01X1670670Y490850D02*
X1671050D01*
G01X1662542Y498978D02*
X1670670Y490850D01*
G01X1656611Y498978D02*
X1662542D01*
G01X1674000Y491800D02*
X1675450D01*
G01X1673050Y490850D02*
X1674000Y491800D01*
G01X1671050Y490850D02*
X1673050D01*
G01X1689943Y478843D02*
Y487203D01*
G01X1681172Y470072D02*
X1689943Y478843D01*
G01X1674250Y504550D02*
X1675750D01*
G01X1669050Y509750D02*
X1674250Y504550D01*
G01X1669050Y513400D02*
Y509750D01*
G01X1667725Y514725D02*
X1669050Y513400D01*
G01X1666000Y514725D02*
X1667725D01*
G01X1666000Y514726D02*
Y514725D01*
G01X1656611Y514726D02*
X1666000D01*
G01X1653756D02*
X1656611D01*
G01X1653755Y514725D02*
X1653756Y514726D01*
G01X1653016Y515464D02*
X1653755Y514725D01*
G01X1652328Y515464D02*
X1653016D01*
G01X1650649Y517143D02*
X1652328Y515464D01*
G01X1686542Y495970D02*
Y497217D01*
G01X1684719Y494147D02*
X1686542Y495970D01*
G01X1684719Y475019D02*
Y494147D01*
G01X1679250Y469550D02*
X1684719Y475019D01*
G01X1664713Y469550D02*
X1679250D01*
G01X1661213Y466050D02*
X1664713Y469550D01*
G01X1661000Y466050D02*
X1661213D01*
G01X1661000Y467091D02*
Y466050D01*
G01X1659311Y468780D02*
X1661000Y467091D01*
G01X1658840Y468780D02*
X1659311D01*
G01X1652782Y474838D02*
X1658840Y468780D01*
G01X1652782Y475550D02*
Y474838D01*
G01X1652783Y475551D02*
X1652782Y475550D01*
G01X1652783Y476647D02*
Y475551D01*
G01X1689581Y503485D02*
X1690091Y503995D01*
G01X1689581Y500541D02*
Y503485D01*
G01X1686542Y497502D02*
X1689581Y500541D01*
G01X1686542Y497217D02*
Y497502D01*
G01X1672450Y488400D02*
X1671050Y487000D01*
G01X1675350Y488400D02*
X1672450D01*
G01X1663009Y495041D02*
X1656611D01*
G01X1671050Y487000D02*
X1663009Y495041D01*
G01X1652968Y479293D02*
X1656611D01*
G01X1651926Y480335D02*
X1652968Y479293D01*
G01X1651926Y482197D02*
Y480335D01*
G01X1675750Y516250D02*
Y514000D01*
G01X1676500Y517000D02*
X1675750Y516250D01*
G01X1683166Y517000D02*
X1676500D01*
G01X1687500Y512666D02*
X1683166Y517000D01*
G01X1687500Y505200D02*
Y512666D01*
G01X1674941Y513191D02*
X1675750Y514000D01*
G01X1672853Y513191D02*
X1674941D01*
G01X1664901Y521143D02*
X1672853Y513191D01*
G01X1661258Y521143D02*
X1664901D01*
G01X1660833Y521568D02*
X1661258Y521143D01*
G01X1660833Y522174D02*
Y521568D01*
G01X1660407Y522600D02*
X1660833Y522174D01*
G01X1656611Y522600D02*
X1660407D01*
G01X1687673Y518250D02*
X1690000D01*
G01X1686400Y519523D02*
X1687673Y518250D01*
G01X1686400Y531000D02*
Y519523D01*
G01X1693017Y518250D02*
X1693019Y518252D01*
G01X1690000Y518250D02*
X1693017D01*
G01X1711305Y521613D02*
X1712562Y520356D01*
G01X1706574Y521613D02*
X1711305D01*
G01X1704890Y523297D02*
X1706574Y521613D01*
G01X1696362Y523297D02*
X1704890D01*
G01X1693019Y519954D02*
X1696362Y523297D01*
G01X1693019Y518252D02*
Y519954D01*
G01X1683150Y506700D02*
X1684650Y505200D01*
G01X1676755Y506700D02*
X1683150D01*
G01X1675750Y507705D02*
X1676755Y506700D01*
G01X1675750Y511000D02*
Y507705D01*
G01X1674584Y512166D02*
X1675750Y511000D01*
G01X1672428Y512166D02*
X1674584D01*
G01X1664476Y520118D02*
X1672428Y512166D01*
G01X1661258Y520118D02*
X1664476D01*
G01X1660833Y519693D02*
X1661258Y520118D01*
G01X1660833Y519087D02*
Y519693D01*
G01X1660409Y518663D02*
X1660833Y519087D01*
G01X1656611Y518663D02*
X1660409D01*
G01X1692443Y479843D02*
Y487259D01*
G01X1682097Y469497D02*
X1692443Y479843D01*
G01X1687443Y491278D02*
X1687152Y491569D01*
G01X1687443Y487203D02*
Y491278D01*
G01X1672275Y500151D02*
X1672606Y499820D01*
G01X1672275Y503825D02*
Y500151D01*
G01X1665311Y510789D02*
X1672275Y503825D01*
G01X1656611Y510789D02*
X1665311D01*
G01X1674036Y501250D02*
X1675750D01*
G01X1672606Y499820D02*
X1674036Y501250D01*
G01X1657500Y468246D02*
Y466050D01*
G01X1651457Y474289D02*
X1657500Y468246D01*
G01X1651457Y476099D02*
Y474289D01*
G01X1672917Y494800D02*
X1672159Y494042D01*
G01X1675650Y494800D02*
X1672917D01*
G01X1666085Y502915D02*
X1656611D01*
G01X1669325Y499675D02*
X1666085Y502915D01*
G01X1669325Y496876D02*
Y499675D01*
G01X1672159Y494042D02*
X1669325Y496876D01*
G01X1673956Y497300D02*
X1672313D01*
G01X1674706Y498050D02*
X1673956Y497300D01*
G01X1675750Y498050D02*
X1674706D01*
G01X1666648Y506852D02*
X1656611D01*
G01X1670400Y503100D02*
X1666648Y506852D01*
G01X1670400Y499213D02*
Y503100D01*
G01X1672313Y497300D02*
X1670400Y499213D01*
G01X1653378Y483230D02*
X1656611D01*
G01X1651867Y484741D02*
X1653378Y483230D01*
G01X1684800Y532600D02*
X1686400Y531000D01*
G01X1682371Y532600D02*
X1684800D01*
G01X1680133Y534838D02*
X1682371Y532600D01*
G01X1680133Y535489D02*
Y534838D01*
G01X1711969Y579367D02*
X1710389Y577787D01*
G01X1711969Y604152D02*
Y579367D01*
G01X1701291Y609823D02*
Y602268D01*
G01X1699106Y612008D02*
X1701291Y609823D01*
G01X1699106Y618018D02*
Y612008D01*
G01X1714573Y606756D02*
X1711969Y604152D01*
G01X1743500Y2750D02*
X1745250Y4500D01*
G01X1743500Y-5000D02*
Y2750D01*
G01X1743503Y-5000D02*
X1743500D01*
G01X1745250Y6300D02*
Y4500D01*
G01X1748127Y9177D02*
X1745250Y6300D01*
G01X1749085Y9177D02*
X1748127D01*
G01X1756250Y8326D02*
X1755500Y9076D01*
G01X1756250Y4500D02*
Y8326D01*
G01Y1951D02*
Y4500D01*
G01X1754999Y700D02*
X1756250Y1951D01*
G01X1751200Y700D02*
X1754999D01*
G01X1748400Y-2100D02*
X1751200Y700D01*
G01X1748400Y-10100D02*
Y-2100D01*
G01X1743500Y-15000D02*
X1748400Y-10100D01*
G01X1743503Y-15000D02*
X1743500D01*
G01X1743233Y10767D02*
X1744900Y9100D01*
G01X1740596Y10767D02*
X1743233D01*
G01X1734779Y4950D02*
X1740596Y10767D01*
G01X1716588Y4950D02*
X1734779D01*
G01X1716163Y4525D02*
X1716588Y4950D01*
G01X1716163Y3233D02*
Y4525D01*
G01Y1097D02*
Y3233D01*
G01X1713500Y-1566D02*
X1716163Y1097D01*
G01X1713500Y-5000D02*
Y-1566D01*
G01X1713503Y-5000D02*
X1713500D01*
G01X1730550Y58150D02*
X1732650D01*
G01X1729750Y58950D02*
X1730550Y58150D01*
G01X1729750Y60500D02*
Y58950D01*
G01X1713500Y68900D02*
X1715100Y70500D01*
G01X1716619Y93435D02*
G02X1713690Y94648I0J4143D01*
G01X1721358Y93435D02*
X1716619D01*
G01X1727648Y96040D02*
G02X1721358Y93435I-6290J6291D01*
G01X1749400Y47400D02*
X1750400D01*
G01X1748594Y48206D02*
X1749400Y47400D01*
G01X1748594Y49606D02*
Y48206D01*
G01X1718100Y66500D02*
X1719750D01*
G01X1717600Y67000D02*
X1718100Y66500D01*
G01X1716050Y67000D02*
X1717600D01*
G01X1714800D02*
X1713200Y65400D01*
G01X1716050Y67000D02*
X1714800D01*
G01X1716401Y91444D02*
G02X1712432Y93088I0J5613D01*
G01X1723079Y91444D02*
X1716401D01*
G01X1724100Y91021D02*
G03X1723079Y91444I-1021J-1021D01*
G01X1724609Y90900D02*
G02X1724100Y91021I0J1130D01*
G01X1725702Y90900D02*
X1724609D01*
G01X1729115Y92314D02*
G02X1725702Y90900I-3413J3412D01*
G01X1733942Y97142D02*
X1729115Y92314D01*
G01X1735500Y54500D02*
X1729500D01*
G01X1738100Y57100D02*
X1735500Y54500D01*
G01X1738100Y68200D02*
Y57100D01*
G01X1736100Y70200D02*
X1738100Y68200D01*
G01X1726992Y70200D02*
X1736100D01*
G01X1726279Y70913D02*
X1726992Y70200D01*
G01X1724785Y70913D02*
X1726279D01*
G01X1722171Y68299D02*
X1724785Y70913D01*
G01X1720002Y68299D02*
X1722171D01*
G01X1715801Y72500D02*
X1720002Y68299D01*
G01X1713691Y72500D02*
X1715801D01*
G01X1712845Y73346D02*
X1713691Y72500D01*
G01X1712845Y77244D02*
Y73346D01*
G01X1726500Y54500D02*
X1729500D01*
G01X1723500D02*
X1726500D01*
G01X1763118Y61500D02*
Y58000D01*
G01X1762500Y62118D02*
X1763118Y61500D01*
G01X1762500Y63000D02*
Y62118D01*
G01Y63000D02*
X1782500D01*
G01X1721940Y51000D02*
X1720500Y52440D01*
G01X1723500Y51000D02*
X1721940D01*
G01X1722950Y87849D02*
Y86600D01*
G01X1722199Y88600D02*
X1722950Y87849D01*
G01X1718650Y88600D02*
X1722199D01*
G01X1717686Y89564D02*
X1718650Y88600D01*
G01X1712688Y89564D02*
X1717686D01*
G01X1742141Y91300D02*
X1746491Y95650D01*
G01X1737000Y91300D02*
X1742141D01*
G01X1735213Y89513D02*
X1737000Y91300D01*
G01X1728800Y89513D02*
X1735213D01*
G01X1725887Y86600D02*
X1728800Y89513D01*
G01X1722950Y86600D02*
X1725887D01*
G01X1727400Y57500D02*
X1723250D01*
G01X1728500Y56400D02*
X1727400Y57500D01*
G01X1733400Y56400D02*
X1728500D01*
G01X1735150Y58150D02*
X1733400Y56400D01*
G01X1726250Y60500D02*
X1723250D01*
G01D02*
Y57500D01*
G01Y63500D02*
X1726250D01*
G01X1723250Y66500D02*
Y63500D01*
G01Y67250D02*
Y66500D01*
G01X1725250Y69250D02*
X1723250Y67250D01*
G01X1725474Y69250D02*
X1725250D01*
G01X1733600Y61600D02*
Y65000D01*
G01X1732650Y60650D02*
X1733600Y61600D01*
G01X1731250Y65000D02*
X1729750Y63500D01*
G01X1733600Y65000D02*
X1731250D01*
G01X1755400Y89300D02*
Y87700D01*
G01X1756274Y90174D02*
X1755400Y89300D01*
G01X1757772Y90174D02*
X1756274D01*
G01X1724300Y46100D02*
X1720100D01*
G01X1726500Y48300D02*
X1724300Y46100D01*
G01X1726500Y51000D02*
Y48300D01*
G01X1719750Y54042D02*
Y57500D01*
G01X1716570Y50862D02*
X1719750Y54042D01*
G01X1717150Y79750D02*
X1718500D01*
G01X1721150D02*
X1721400Y79500D01*
G01X1718500Y79750D02*
X1721150D01*
G01X1741594Y48106D02*
Y52606D01*
G01X1742594Y47106D02*
X1741594Y48106D01*
G01X1769742Y56842D02*
X1778958D01*
G01X1767400Y54500D02*
X1769742Y56842D01*
G01X1761920Y54500D02*
X1767400D01*
G01X1760559Y53139D02*
X1761920Y54500D01*
G01X1760559Y51000D02*
Y53139D01*
G01X1745094Y52606D02*
Y55606D01*
G01Y49606D02*
Y52606D01*
G01Y47106D02*
Y49606D01*
G01X1771600Y81600D02*
X1776400D01*
G01X1771000Y81000D02*
X1771600Y81600D01*
G01X1771000Y79800D02*
Y81000D01*
G01X1757650Y79750D02*
X1756200Y78300D01*
G01X1762000Y79750D02*
X1757650D01*
G01X1743366Y153250D02*
X1737488Y147372D01*
G01X1746189Y153250D02*
X1743366D01*
G01X1723727Y142821D02*
G03X1723314Y142650I0J-584D01*
G01X1726280Y142821D02*
X1723727D01*
G01X1726871Y142230D02*
G03X1726280Y142821I-591J0D01*
G01X1726871Y141498D02*
Y142230D01*
G01X1726446Y141073D02*
G03X1726871Y141498I0J425D01*
G01X1724890Y141073D02*
X1726446D01*
G01X1712363Y97798D02*
Y107664D01*
G01X1713652Y94686D02*
G02X1712363Y97798I3113J3112D01*
G01X1713690Y94648D02*
X1713652Y94686D01*
G01X1731574Y99966D02*
X1727648Y96040D01*
G01X1731964Y100128D02*
G03X1731574Y99966I1J-552D01*
G01X1737488Y100128D02*
X1731964D01*
G01X1727431Y152399D02*
Y157208D01*
G01X1729357Y152399D02*
G02X1727431I-963J0D01*
G01X1729357Y155208D02*
Y152399D01*
G01X1731283Y155208D02*
G03X1729357I-963J0D01*
G01X1731283Y150619D02*
Y155208D01*
G01X1726464Y145800D02*
X1731283Y150619D01*
G01X1724890Y144226D02*
X1726464Y145800D01*
G01X1724890Y144222D02*
Y144226D01*
G01X1721740Y122175D02*
X1723314Y120601D01*
G01X1727464Y132200D02*
X1726464Y133200D01*
G01X1728599Y132200D02*
X1727464D01*
G01X1730400Y134001D02*
X1728599Y132200D01*
G01X1730400Y137839D02*
Y134001D01*
G01X1729989Y138250D02*
X1730400Y137839D01*
G01X1729989Y141450D02*
Y138250D01*
G01X1734479Y145940D02*
X1729989Y141450D01*
G01X1734479Y163571D02*
Y145940D01*
G01X1724890Y131626D02*
X1726464Y133200D01*
G01X1724890Y131624D02*
Y131626D01*
G01X1772220Y127750D02*
X1777220D01*
G01X1735315Y131624D02*
X1737488D01*
G01X1733989Y132950D02*
X1735315Y131624D01*
G01X1733989Y136050D02*
Y132950D01*
G01X1731789Y138250D02*
X1733989Y136050D01*
G01X1731789Y139450D02*
Y138250D01*
G01X1748689Y130050D02*
X1760240D01*
G01X1748189Y130550D02*
X1748689Y130050D01*
G01X1748189Y132550D02*
Y130550D01*
G01X1747489Y133250D02*
X1748189Y132550D01*
G01X1739189Y133250D02*
X1747489D01*
G01X1737563Y131624D02*
X1739189Y133250D01*
G01X1737488Y131624D02*
X1737563D01*
G01X1772220Y129430D02*
Y127750D01*
G01X1771600Y130050D02*
X1772220Y129430D01*
G01X1760240Y130050D02*
X1771600D01*
G01X1737100Y98450D02*
G03X1733942Y97142I0J-4466D01*
G01X1737434Y98450D02*
X1737100D01*
G01X1739200Y100216D02*
G02X1737434Y98450I-1766J0D01*
G01X1739200Y102955D02*
Y100216D01*
G01X1740638Y106427D02*
G03X1739200Y102955I3472J-3472D01*
G01X1737487Y141073D02*
X1735914Y139500D01*
G01X1737488Y141073D02*
X1737487D01*
G01X1737488Y106424D02*
X1735914Y104850D01*
G01X1737488Y106427D02*
Y106424D01*
G01X1721736Y103278D02*
X1720164Y104850D01*
G01X1721740Y103278D02*
X1721736D01*
G01X1740638Y144224D02*
X1742214Y145800D01*
G01X1740638Y144222D02*
Y144224D01*
G01X1777220Y146250D02*
X1772220D01*
G01X1752889Y148550D02*
X1758228D01*
G01X1752289Y149150D02*
X1752889Y148550D01*
G01X1752289Y150550D02*
Y149150D01*
G01X1751389Y151450D02*
X1752289Y150550D01*
G01X1750289Y151450D02*
X1751389D01*
G01X1748089Y149250D02*
X1750289Y151450D01*
G01X1743189Y149250D02*
X1748089D01*
G01X1742214Y148275D02*
X1743189Y149250D01*
G01X1742214Y145800D02*
Y148275D01*
G01X1772220Y147719D02*
Y146250D01*
G01X1771389Y148550D02*
X1772220Y147719D01*
G01X1758228Y148550D02*
X1771389D01*
G01X1718591Y115876D02*
X1713237Y121230D01*
G01X1766409Y158650D02*
X1768886Y156173D01*
G01X1724890Y106426D02*
X1723314Y104850D01*
G01X1724890Y106427D02*
Y106426D01*
G01X1740640Y131624D02*
X1742214Y130050D01*
G01X1740638Y131624D02*
X1740640D01*
G01X1777220Y123250D02*
X1772220D01*
G01X1750539Y121000D02*
X1756589D01*
G01X1748289Y123250D02*
X1750539Y121000D01*
G01X1748289Y126850D02*
Y123250D01*
G01X1745089Y130050D02*
X1748289Y126850D01*
G01X1742214Y130050D02*
X1745089D01*
G01X1772220Y121981D02*
Y123250D01*
G01X1771239Y121000D02*
X1772220Y121981D01*
G01X1756589Y121000D02*
X1771239D01*
G01X1724027Y115013D02*
X1724890Y115876D01*
G01X1722185Y114250D02*
G03X1724027Y115013I0J2605D01*
G01X1718311Y114250D02*
X1722185D01*
G01X1716500Y115000D02*
G03X1718311Y114250I1811J1811D01*
G01X1715262Y115513D02*
G02X1716500Y115000I0J-1751D01*
G01X1713034Y115513D02*
X1715262D01*
G01X1721737Y141073D02*
X1720164Y139500D01*
G01X1721740Y141073D02*
X1721737D01*
G01X1740638Y141076D02*
X1739064Y142650D01*
G01X1740638Y141073D02*
Y141076D01*
G01X1725012Y137923D02*
X1726539Y139450D01*
G01X1724890Y137923D02*
X1725012D01*
G01X1737488Y122175D02*
X1739064Y123750D01*
G01X1740638Y119026D02*
X1739064Y120600D01*
G01X1721740Y131626D02*
X1723314Y133200D01*
G01X1721740Y131624D02*
Y131626D01*
G01X1725506Y151138D02*
X1721740Y147372D01*
G01X1725506Y156143D02*
Y151138D01*
G01X1723580Y156143D02*
G02X1725506I963J0D01*
G01X1723580Y151750D02*
Y156143D01*
G01X1721654Y151750D02*
G03X1723580I963J0D01*
G01X1721654Y157711D02*
Y151750D01*
G01X1721742Y147372D02*
X1723264Y145850D01*
G01X1721740Y147372D02*
X1721742D01*
G01X1735989Y145725D02*
Y149050D01*
G01X1737488Y144226D02*
X1735989Y145725D01*
G01X1737488Y144222D02*
Y144226D01*
G01Y125325D02*
X1735912Y123750D01*
G01X1737488Y109574D02*
X1735914Y108000D01*
G01X1737488Y109577D02*
Y109574D01*
G01X1720627Y135887D02*
X1721740Y134774D01*
G01X1719509Y136350D02*
G02X1720627Y135887I0J-1581D01*
G01X1714252Y136350D02*
X1719509D01*
G01X1713339Y137263D02*
G03X1714252Y136350I913J0D01*
G01X1713339Y142959D02*
Y137263D01*
G01X1721740Y134776D02*
Y134774D01*
G01X1723314Y136350D02*
X1721740Y134776D01*
G01X1725989Y136350D02*
X1723314D01*
G01X1728189Y138550D02*
X1725989Y136350D01*
G01X1728189Y144010D02*
Y138550D01*
G01X1733036Y148857D02*
X1728189Y144010D01*
G01X1733036Y156054D02*
Y148857D01*
G01X1729989Y159101D02*
X1733036Y156054D01*
G01X1734760Y137923D02*
X1737488D01*
G01X1734195Y138488D02*
X1734760Y137923D01*
G01X1734195Y141956D02*
Y138488D01*
G01X1734989Y142750D02*
X1734195Y141956D01*
G01X1726464Y120602D02*
Y120600D01*
G01X1724891Y122175D02*
X1726464Y120602D01*
G01X1724890Y122175D02*
X1724891D01*
G01X1772220Y132250D02*
X1777220D01*
G01X1740638Y134776D02*
Y134774D01*
G01X1739064Y136350D02*
X1740638Y134776D01*
G01X1751489Y134550D02*
X1763217D01*
G01X1750489Y133550D02*
X1751489Y134550D01*
G01X1749289Y133550D02*
X1750489D01*
G01X1748789Y134050D02*
X1749289Y133550D01*
G01X1748789Y135850D02*
Y134050D01*
G01X1748289Y136350D02*
X1748789Y135850D01*
G01X1741689Y136350D02*
X1748289D01*
G01X1741239Y135900D02*
X1741689Y136350D01*
G01X1741239Y135375D02*
Y135900D01*
G01X1740638Y134774D02*
X1741239Y135375D01*
G01X1772220Y133919D02*
Y132250D01*
G01X1771589Y134550D02*
X1772220Y133919D01*
G01X1763217Y134550D02*
X1771589D01*
G01X1740639Y122175D02*
X1742214Y120600D01*
G01X1740638Y122175D02*
X1740639D01*
G01X1718591Y141073D02*
X1717014Y142650D01*
G01X1713952Y155695D02*
Y151150D01*
G01X1714389Y97938D02*
Y108241D01*
G01X1716872Y95455D02*
G02X1714389Y97938I0J2483D01*
G01X1721860Y95455D02*
X1716872D01*
G01X1725412Y96926D02*
G02X1721860Y95455I-3552J3553D01*
G01X1732849Y104363D02*
X1725412Y96926D01*
G01X1733490Y105911D02*
G02X1732849Y104363I-2190J0D01*
G01X1733490Y109104D02*
Y105911D01*
G01X1735536Y111150D02*
G03X1733490Y109104I0J-2046D01*
G01X1738335Y111150D02*
X1735536D01*
G01X1739576Y111664D02*
G02X1738335Y111150I-1241J1241D01*
G01X1740638Y112726D02*
X1739576Y111664D01*
G01X1724890Y109576D02*
X1723314Y108000D01*
G01X1724890Y109577D02*
Y109576D01*
G01X1772220Y150750D02*
X1777220D01*
G01X1740636Y147372D02*
X1740638D01*
G01X1739064Y145800D02*
X1740636Y147372D01*
G01X1749889Y153550D02*
X1760339D01*
G01X1747189Y150850D02*
X1749889Y153550D01*
G01X1742789Y150850D02*
X1747189D01*
G01X1740689Y148750D02*
X1742789Y150850D01*
G01X1740689Y147423D02*
Y148750D01*
G01X1740638Y147372D02*
X1740689Y147423D01*
G01X1772220Y152819D02*
Y150750D01*
G01X1771489Y153550D02*
X1772220Y152819D01*
G01X1760339Y153550D02*
X1771489D01*
G01X1740638Y128474D02*
X1739064Y126900D01*
G01X1724890Y125324D02*
X1726464Y123750D01*
G01X1724890Y125325D02*
Y125324D01*
G01X1771789Y138950D02*
X1759589D01*
G01X1772220Y138519D02*
X1771789Y138950D01*
G01X1772220Y136750D02*
Y138519D01*
G01X1777220Y136750D02*
X1772220D01*
G01X1740638Y137926D02*
X1739064Y139500D01*
G01X1740638Y137923D02*
Y137926D01*
G01X1742265Y139550D02*
X1740638Y137923D01*
G01X1747089Y139550D02*
X1742265D01*
G01X1747489Y139950D02*
X1747089Y139550D01*
G01X1747489Y140650D02*
Y139950D01*
G01X1748289Y141450D02*
X1747489Y140650D01*
G01X1749389Y141450D02*
X1748289D01*
G01X1749889Y140950D02*
X1749389Y141450D01*
G01X1749889Y139550D02*
Y140950D01*
G01X1750489Y138950D02*
X1749889Y139550D01*
G01X1759589Y138950D02*
X1750489D01*
G01X1721740Y137926D02*
X1723314Y139500D01*
G01X1721740Y137923D02*
Y137926D01*
G01X1724890Y112724D02*
X1726464Y111150D01*
G01X1724890Y112726D02*
Y112724D01*
G01X1715877Y151789D02*
Y158094D01*
G01X1717803Y151789D02*
G02X1715877I-963J0D01*
G01X1717803Y156203D02*
Y151789D01*
G01X1719729Y149210D02*
Y156203D01*
G01X1720164Y148775D02*
X1719729Y149210D01*
G01X1720164Y145800D02*
Y148775D01*
G01X1721740Y144224D02*
X1720164Y145800D01*
G01X1721740Y144222D02*
Y144224D01*
G01X1737488Y134749D02*
X1735989Y133250D01*
G01X1737488Y134774D02*
Y134749D01*
G01X1727114Y134774D02*
X1724890D01*
G01X1727678Y134210D02*
X1727114Y134774D01*
G01X1728363Y134210D02*
X1727678D01*
G01X1728789Y134636D02*
X1728363Y134210D01*
G01X1728789Y136250D02*
Y134636D01*
G01X1743787Y141077D02*
Y141073D01*
G01X1742214Y142650D02*
X1743787Y141077D01*
G01X1772220Y141250D02*
X1777220D01*
G01X1771189Y143850D02*
X1761298D01*
G01X1772220Y142819D02*
X1771189Y143850D01*
G01X1772220Y141250D02*
Y142819D01*
G01X1746072Y141073D02*
X1743787D01*
G01X1747089Y142090D02*
X1746072Y141073D01*
G01X1747089Y146250D02*
Y142090D01*
G01X1747389Y146550D02*
X1747089Y146250D01*
G01X1748689Y146550D02*
X1747389D01*
G01X1749089Y146150D02*
X1748689Y146550D01*
G01X1749089Y144250D02*
Y146150D01*
G01X1749489Y143850D02*
X1749089Y144250D01*
G01X1761298Y143850D02*
X1749489D01*
G01X1737488Y128474D02*
X1739064Y130050D01*
G01X1721737Y106427D02*
X1720164Y108000D01*
G01X1721740Y106427D02*
X1721737D01*
G01X1719364Y186937D02*
X1721815D01*
G01X1718128Y188173D02*
X1719364Y186937D01*
G01X1718128Y189628D02*
Y188173D01*
G01X1719000Y190500D02*
X1718128Y189628D01*
G01X1725408Y163500D02*
X1727689Y165781D01*
G01X1725389Y163500D02*
X1725408D01*
G01X1725389Y159250D02*
Y163500D01*
G01X1727431Y157208D02*
X1725389Y159250D01*
G01X1727689Y165781D02*
Y169781D01*
G01X1736689Y165781D02*
X1734479Y163571D01*
G01X1736689Y165781D02*
Y169781D01*
G01X1764850Y158650D02*
X1766409D01*
G01X1720916Y158449D02*
X1721654Y157711D01*
G01X1720916Y163463D02*
Y158449D01*
G01X1721654Y164201D02*
X1720916Y163463D01*
G01X1721654Y164246D02*
Y164201D01*
G01X1723189Y165781D02*
X1721654Y164246D01*
G01X1723189Y169781D02*
Y165781D01*
G01X1729989Y163581D02*
Y159101D01*
G01X1732189Y165781D02*
X1729989Y163581D01*
G01X1732189Y165781D02*
Y169781D01*
G01X1714129Y167800D02*
Y169631D01*
G01X1714189Y167740D02*
X1714129Y167800D01*
G01X1714189Y165781D02*
Y167740D01*
G01X1713300Y185000D02*
X1713000D01*
G01X1716191Y187891D02*
X1713300Y185000D01*
G01X1716191Y197295D02*
Y187891D01*
G01X1717231Y165781D02*
X1718689D01*
G01X1716401Y164951D02*
X1717231Y165781D01*
G01X1716401Y158618D02*
Y164951D01*
G01X1715877Y158094D02*
X1716401Y158618D01*
G01X1719729Y156203D02*
G03X1717803I-963J0D01*
G01X1718689Y169731D02*
Y165781D01*
G01X1740748Y230903D02*
Y226756D01*
G01X1742398Y232553D02*
X1740748Y230903D01*
G01X1742398Y234681D02*
Y232553D01*
G01X1750276Y233769D02*
X1749462Y232955D01*
G01X1754036Y233769D02*
X1750276D01*
G01X1756495Y231310D02*
X1754036Y233769D01*
G01X1756495Y226757D02*
Y231310D01*
G01X1756496Y226756D02*
X1756495Y226757D01*
G01X1766877Y231881D02*
X1766077Y232681D01*
G01X1769606Y231881D02*
X1766877D01*
G01X1772068Y234343D02*
X1769606Y231881D01*
G01X1774243Y234343D02*
X1772068D01*
G01X1769095Y234039D02*
X1768700Y233644D01*
G01X1769095Y244105D02*
Y234039D01*
G01X1737599Y231086D02*
X1739847Y233334D01*
G01X1737599Y226756D02*
Y231086D01*
G01X1731620Y251445D02*
X1729957Y253108D01*
G01X1731620Y222580D02*
Y251445D01*
G01X1732957Y221243D02*
X1731620Y222580D01*
G01X1758766Y221243D02*
X1732957D01*
G01X1759646Y222123D02*
X1758766Y221243D01*
G01X1759646Y226756D02*
Y222123D01*
G01X1765945Y250268D02*
X1762280Y253933D01*
G01X1765945Y244105D02*
Y250268D01*
G01X1747047Y249657D02*
X1746900Y249804D01*
G01X1747047Y244105D02*
Y249657D01*
G01X1734449Y229956D02*
Y226756D01*
G01X1736847Y232354D02*
X1734449Y229956D01*
G01X1736847Y233334D02*
Y232354D01*
G01X1750197Y247997D02*
X1751900Y249700D01*
G01X1750197Y244105D02*
Y247997D01*
G01X1730996Y442804D02*
X1723189Y434997D01*
G01X1720327Y442957D02*
Y469858D01*
G01X1719317Y441947D02*
X1720327Y442957D01*
G01X1724369Y441601D02*
X1718887Y436119D01*
G01X1734649Y448349D02*
X1737150Y450850D01*
G01X1734649Y441754D02*
Y448349D01*
G01X1719485Y506800D02*
X1719486D01*
G01X1719485Y506801D02*
Y506800D01*
G01X1717436Y508850D02*
X1719485Y506801D01*
G01X1714530Y508850D02*
X1717436D01*
G01X1712562Y520356D02*
Y516950D01*
G01X1722365Y471811D02*
X1722347D01*
G01X1722365Y471896D02*
Y471811D01*
G01X1720327Y469858D02*
X1722365Y471896D01*
G01X1777390Y584310D02*
X1772300D01*
G01X1760092Y548192D02*
X1757478D01*
G01X1761200Y549300D02*
X1760092Y548192D01*
G01X1761200Y555000D02*
Y549300D01*
G01X1763700Y557500D02*
X1761200Y555000D01*
G01X1767800Y557500D02*
X1763700D01*
G01X1769195Y558895D02*
X1767800Y557500D01*
G01X1773471Y558895D02*
X1769195D01*
G01X1773471Y564015D02*
X1780015D01*
G01X1755260Y561455D02*
X1749971D01*
G01X1756500Y560215D02*
X1755260Y561455D01*
G01X1756500Y554500D02*
Y560215D01*
G01X1745350Y561455D02*
X1749971D01*
G01X1741783Y557888D02*
X1745350Y561455D01*
G01X1738697Y557888D02*
X1741783D01*
G01X1733096Y585496D02*
X1731124Y583524D01*
G01X1733096Y588640D02*
Y585496D01*
G01X1728218Y576682D02*
X1730814D01*
G01X1727400Y577500D02*
X1728218Y576682D01*
G01X1727400Y579800D02*
Y577500D01*
G01X1731124Y583524D02*
X1727400Y579800D01*
G01X1725694Y566806D02*
Y568814D01*
G01X1728000Y564500D02*
X1725694Y566806D01*
G01X1729700Y564500D02*
X1728000D01*
G01X1734864Y571564D02*
X1737814D01*
G01X1733700Y570400D02*
X1734864Y571564D01*
G01X1733700Y566200D02*
Y570400D01*
G01X1732000Y564500D02*
X1733700Y566200D01*
G01X1729700Y564500D02*
X1732000D01*
G01X1773471Y569135D02*
X1778917D01*
G01X1762500Y564800D02*
X1767500Y559800D01*
G01X1762500Y572375D02*
Y564800D01*
G01X1762925Y572800D02*
X1762500Y572375D01*
G01X1766200Y572800D02*
X1762925D01*
G01X1767200Y573800D02*
X1766200Y572800D01*
G01X1767200Y576100D02*
Y573800D01*
G01X1765500Y577800D02*
X1767200Y576100D01*
G01X1765500Y592500D02*
Y577800D01*
G01X1773471Y566575D02*
X1779075D01*
G01X1773471Y556335D02*
X1781865D01*
G01X1744912Y558895D02*
X1749971D01*
G01X1740272Y554255D02*
X1744912Y558895D01*
G01X1738498Y554255D02*
X1740272D01*
G01X1738243Y554000D02*
X1738498Y554255D01*
G01X1736000Y554000D02*
X1738243D01*
G01X1773471Y561455D02*
X1779943D01*
G01X1771193Y573490D02*
X1770719Y573964D01*
G01X1780756Y573490D02*
X1771193D01*
G01X1772300Y581750D02*
X1777250D01*
G01X1745425Y566575D02*
X1749971D01*
G01X1745000Y567000D02*
X1745425Y566575D01*
G01X1745000Y568000D02*
Y567000D01*
G01X1743000Y570000D02*
X1745000Y568000D01*
G01X1740575Y563000D02*
X1739000D01*
G01X1741400Y563825D02*
X1740575Y563000D01*
G01X1741400Y568400D02*
Y563825D01*
G01X1743000Y570000D02*
X1741400Y568400D01*
G01X1746364Y569135D02*
X1749971D01*
G01X1743799Y571700D02*
X1746364Y569135D01*
G01X1742201Y571700D02*
X1743799D01*
G01X1739000Y568499D02*
X1742201Y571700D01*
G01X1739000Y566000D02*
Y568499D01*
G01X1755635Y569135D02*
X1749971D01*
G01X1760800Y574300D02*
X1755635Y569135D01*
G01X1764900Y574300D02*
X1760800D01*
G01X1765300Y574700D02*
X1764900Y574300D01*
G01X1724723Y574123D02*
X1730814D01*
G01X1722500Y571900D02*
X1724723Y574123D01*
G01X1722500Y562000D02*
Y571900D01*
G01X1724768Y555100D02*
X1727600D01*
G01X1722500Y557368D02*
X1724768Y555100D01*
G01X1722500Y562000D02*
Y557368D01*
G01X1744041Y586870D02*
X1748800D01*
G01X1742381Y588530D02*
X1744041Y586870D01*
G01X1772300D02*
X1777630D01*
G01X1738434Y590379D02*
Y588986D01*
G01X1738008Y590805D02*
X1738434Y590379D01*
G01X1736245Y590805D02*
X1738008D01*
G01X1739364Y604617D02*
X1739714Y604967D01*
G01X1730728Y604617D02*
X1739364D01*
G01X1723983Y594684D02*
X1718037D01*
G01X1724041Y594742D02*
X1723983Y594684D01*
G01X1735607Y588640D02*
X1736003Y588244D01*
G01X1733096Y588640D02*
X1735607D01*
G01X1761680Y596320D02*
X1765500Y592500D01*
G01X1761680Y604490D02*
Y596320D01*
G01X1743486Y607088D02*
Y603249D01*
G01X1738916Y598679D02*
X1736245D01*
G01X1743486Y603249D02*
X1738916Y598679D01*
G01X1754300Y595250D02*
Y605268D01*
G01X1753600Y594550D02*
X1754300Y595250D01*
G01X1748800Y594550D02*
X1753600D01*
G01X1754300Y607299D02*
Y605268D01*
G01X1755617Y608616D02*
X1754300Y607299D01*
G01X1763294Y608616D02*
X1755617D01*
G01X1765180Y606730D02*
X1763294Y608616D01*
G01X1765180Y604490D02*
Y606730D01*
G01X1738476Y592773D02*
X1736245D01*
G01X1739179Y592070D02*
X1738476Y592773D01*
G01X1718568Y596653D02*
X1718037Y597184D01*
G01X1723983Y596653D02*
X1718568D01*
G01X1724041Y596711D02*
X1723983Y596653D01*
G01X1715461Y590827D02*
Y590723D01*
G01X1713546Y592742D02*
X1715461Y590827D01*
G01X1713546Y603385D02*
Y592742D01*
G01X1715714Y605553D02*
X1713546Y603385D01*
G01X1719043Y605553D02*
X1715714D01*
G01X1728341Y614851D02*
X1719043Y605553D01*
G01X1719305Y590805D02*
X1724041D01*
G01X1718631Y590131D02*
X1719305Y590805D01*
G01X1716909Y590131D02*
X1718631D01*
G01X1716317Y590723D02*
X1716909Y590131D01*
G01X1715461Y590723D02*
X1716317D01*
G01X1728341Y614851D02*
Y617959D01*
G01X1772300Y591990D02*
X1778405D01*
G01X1772300Y589430D02*
X1778070D01*
G01X1772300Y594550D02*
X1780350D01*
G01X1716993Y606756D02*
X1714573D01*
G01X1725133Y614896D02*
X1716993Y606756D01*
G01X1750351Y603249D02*
X1750399Y603201D01*
G01X1746986Y603249D02*
X1750351D01*
G01X1727228Y603116D02*
Y604617D01*
G01X1727112Y603000D02*
X1727228Y603116D01*
G01X1727112Y600844D02*
Y603000D01*
G01X1727228Y608629D02*
X1727666Y609067D01*
G01X1727228Y604617D02*
Y608629D01*
G01X1739947Y594742D02*
X1740270Y594419D01*
G01X1736245Y594742D02*
X1739947D01*
G01X1825507Y30668D02*
Y33693D01*
G01X1819000Y7504D02*
X1816723Y9781D01*
G01X1819000Y6000D02*
Y7504D01*
G01X1822357Y14656D02*
Y17268D01*
G01X1817482Y9781D02*
X1822357Y14656D01*
G01X1816723Y9781D02*
X1817482D01*
G01X1822357Y27201D02*
Y30668D01*
G01X1819837Y24681D02*
X1822357Y27201D01*
G01X1819837Y21700D02*
Y24681D01*
G01X1799504Y-2409D02*
Y-5000D01*
G01X1795696Y1399D02*
X1799504Y-2409D01*
G01X1795696Y6061D02*
Y1399D01*
G01X1831299Y4200D02*
X1833100D01*
G01X1830099Y5400D02*
X1831299Y4200D01*
G01X1827901Y5400D02*
X1830099D01*
G01X1826500Y3999D02*
X1827901Y5400D01*
G01X1826500Y2176D02*
Y3999D01*
G01X1825324Y1000D02*
X1826500Y2176D01*
G01X1824564Y4263D02*
Y3441D01*
G01X1828001Y7700D02*
X1824564Y4263D01*
G01X1833100Y7700D02*
X1828001D01*
G01X1828874Y-11100D02*
Y-13520D01*
G01X1827061Y-8540D02*
X1828874D01*
G01X1825756Y-9845D02*
X1827061Y-8540D01*
G01X1825756Y-12811D02*
Y-9845D01*
G01X1826945Y-14000D02*
X1825756Y-12811D01*
G01X1828394Y-14000D02*
X1826945D01*
G01X1828874Y-13520D02*
X1828394Y-14000D01*
G01X1808000Y8697D02*
X1808603Y9300D01*
G01X1808000Y6000D02*
Y8697D01*
G01X1819207Y13393D02*
Y17268D01*
G01X1817514Y11700D02*
X1819207Y13393D01*
G01X1815800Y11700D02*
X1817514D01*
G01X1814400Y10300D02*
X1815800Y11700D01*
G01X1809603Y10300D02*
X1814400D01*
G01X1808603Y9300D02*
X1809603Y10300D01*
G01X1825507Y21224D02*
X1825870Y21587D01*
G01X1825507Y17268D02*
Y21224D01*
G01X1819790Y37325D02*
X1817186Y39929D01*
G01X1821875Y37325D02*
X1819790D01*
G01X1825507Y33693D02*
X1821875Y37325D01*
G01X1833150Y90750D02*
X1833050Y90850D01*
G01X1838400Y90750D02*
X1833150D01*
G01X1833050Y94550D02*
Y90850D01*
G01X1824350Y94450D02*
Y91650D01*
G01X1826350D02*
X1824350D01*
G01X1827150Y90850D02*
X1826350Y91650D01*
G01X1829550Y90850D02*
X1827150D01*
G01X1822500Y94450D02*
X1821350Y95600D01*
G01X1824350Y94450D02*
X1822500D01*
G01X1782500Y63000D02*
X1784341Y64841D01*
G01X1833000Y83950D02*
X1829900D01*
G01X1834684Y87500D02*
X1836359Y89175D01*
G01X1833000Y87500D02*
X1834684D01*
G01X1833000Y83950D02*
Y87500D01*
G01X1828250Y80450D02*
X1829900D01*
G01X1827100Y81600D02*
X1828250Y80450D01*
G01X1798445Y82256D02*
X1798454D01*
G01X1798445Y82265D02*
Y82256D01*
G01X1795647Y85063D02*
X1798445Y82265D01*
G01X1793852Y85063D02*
X1795647D01*
G01X1833530Y76430D02*
X1836750Y79650D01*
G01X1832830Y76430D02*
X1833210D01*
G01X1785457Y63341D02*
X1786341D01*
G01X1778958Y56842D02*
X1785457Y63341D01*
G01X1803559Y106570D02*
X1804720D01*
G01X1801819Y104830D02*
X1803559Y106570D01*
G01X1798935Y104830D02*
X1801819D01*
G01X1798510Y105255D02*
X1798935Y104830D01*
G01X1798510Y108000D02*
Y105255D01*
G01X1807030Y106570D02*
X1804720D01*
G01X1807400Y106200D02*
X1807030Y106570D01*
G01X1810938Y106200D02*
X1807400D01*
G01X1812743Y104395D02*
X1810938Y106200D01*
G01X1801492Y136539D02*
X1802485D01*
G01X1798953Y134000D02*
X1801492Y136539D01*
G01X1796001Y134000D02*
X1798953D01*
G01X1795495Y134506D02*
X1796001Y134000D01*
G01X1795495Y136789D02*
Y134506D01*
G01X1802485Y131261D02*
Y136539D01*
G01X1803509Y130237D02*
X1802485Y131261D01*
G01X1803509Y128500D02*
Y130237D01*
G01X1790000Y135500D02*
X1787000D01*
G01X1791000Y136500D02*
X1790000Y135500D01*
G01X1791000Y139575D02*
Y136500D01*
G01X1791425Y140000D02*
X1791000Y139575D01*
G01X1797499Y140000D02*
X1791425D01*
G01X1798055Y139444D02*
X1797499Y140000D01*
G01X1798055Y136789D02*
Y139444D01*
G01X1793000Y146984D02*
Y149000D01*
G01X1792935Y146919D02*
X1793000Y146984D01*
G01X1792935Y143789D02*
Y146919D01*
G01Y141396D02*
Y143789D01*
G01X1793331Y141000D02*
X1792935Y141396D01*
G01X1795070Y141000D02*
X1793331D01*
G01X1795495Y141425D02*
X1795070Y141000D01*
G01X1795495Y143789D02*
Y141425D01*
G01X1795920Y149000D02*
X1797720Y150800D01*
G01X1793000Y149000D02*
X1795920D01*
G01X1819348Y149437D02*
X1815348D01*
G01X1811348Y154063D02*
X1812848Y155563D01*
G01X1811348Y149437D02*
Y154063D01*
G01X1809503Y146760D02*
X1806400Y143657D01*
G01X1809503Y148529D02*
Y146760D01*
G01X1810411Y149437D02*
X1809503Y148529D01*
G01X1811348Y149437D02*
X1810411D01*
G01X1815348D02*
X1811348D01*
G01X1821350Y95600D02*
Y98270D01*
G01X1803100Y108000D02*
X1801070D01*
G01X1803600Y108500D02*
X1803100Y108000D01*
G01X1809900Y108500D02*
X1803600D01*
G01X1801070Y110443D02*
Y108000D01*
G01X1800624Y110889D02*
X1801070Y110443D01*
G01X1794745Y110889D02*
X1800624D01*
G01X1794000Y110144D02*
X1794745Y110889D01*
G01X1794000Y109000D02*
Y110144D01*
G01X1793500Y108500D02*
X1794000Y109000D01*
G01X1791000Y108500D02*
X1793500D01*
G01X1808400Y123597D02*
Y120800D01*
G01X1807818Y124179D02*
X1808400Y123597D01*
G01X1813118Y124018D02*
Y127976D01*
G01X1811900Y122800D02*
X1813118Y124018D01*
G01X1811900Y121000D02*
Y122800D01*
G01X1819348Y142162D02*
Y145937D01*
G01X1820760Y140750D02*
X1819348Y142162D01*
G01X1826270Y140750D02*
X1820760D01*
G01X1827500Y141980D02*
X1826270Y140750D01*
G01X1827500Y144900D02*
Y141980D01*
G01X1802750Y118601D02*
Y120000D01*
G01X1802087Y117938D02*
X1802750Y118601D01*
G01X1799034Y117938D02*
X1802087D01*
G01X1798510Y117414D02*
X1799034Y117938D01*
G01X1798510Y115000D02*
Y117414D01*
G01Y112544D02*
Y115000D01*
G01X1798209Y112243D02*
X1798510Y112544D01*
G01X1796239Y112243D02*
X1798209D01*
G01X1795950Y112532D02*
X1796239Y112243D01*
G01X1795950Y115000D02*
Y112532D01*
G01X1802750Y122050D02*
Y120000D01*
G01X1807071Y126371D02*
X1802750Y122050D01*
G01X1809867Y126371D02*
X1807071D01*
G01X1791000Y118000D02*
Y115500D01*
G01X1790250Y118750D02*
X1791000Y118000D01*
G01X1790250Y120000D02*
Y118750D01*
G01X1785900Y115500D02*
X1784100Y117300D01*
G01X1791000Y115500D02*
X1785900D01*
G01X1787000Y146850D02*
Y143500D01*
G01X1787500Y147350D02*
X1787000Y146850D01*
G01X1787500Y149000D02*
Y147350D01*
G01X1791277Y127500D02*
X1800000D01*
G01X1790192Y126415D02*
X1791277Y127500D01*
G01X1790192Y124713D02*
Y126415D01*
G01X1787373Y121894D02*
X1790192Y124713D01*
G01X1787373Y120188D02*
Y121894D01*
G01X1789059Y130059D02*
X1788000Y129000D01*
G01X1793000Y130059D02*
X1789059D01*
G01X1788000Y126750D02*
X1788250Y126500D01*
G01X1788000Y129000D02*
Y126750D01*
G01X1783500Y155500D02*
X1786000Y158000D01*
G01X1783500Y146000D02*
Y155500D01*
G01X1781712Y144212D02*
X1783500Y146000D01*
G01X1780182Y144212D02*
X1781712D01*
G01X1777220Y141250D02*
X1780182Y144212D01*
G01X1812700Y133277D02*
X1815883D01*
G01X1786000Y163500D02*
X1785500Y164000D01*
G01X1786000Y161500D02*
Y163500D01*
G01X1831700Y250386D02*
Y252272D01*
G01X1832086Y250000D02*
X1831700Y250386D01*
G01X1832086Y244106D02*
Y250000D01*
G01X1832087Y244105D02*
X1832086Y244106D01*
G01X1783580Y233798D02*
X1784440Y232938D01*
G01X1780016Y233798D02*
X1783580D01*
G01X1778543Y232325D02*
X1780016Y233798D01*
G01X1778543Y226756D02*
Y232325D01*
G01X1816339Y232554D02*
Y226756D01*
G01X1817921Y234136D02*
X1816339Y232554D01*
G01X1824186Y234136D02*
X1817921D01*
G01X1824705Y234655D02*
X1824186Y234136D01*
G01X1824706Y234655D02*
X1824705D01*
G01X1826085Y236034D02*
X1824706Y234655D01*
G01X1775394Y233192D02*
X1774243Y234343D01*
G01X1775394Y226756D02*
Y233192D01*
G01X1834049Y262800D02*
X1841382Y255467D01*
G01X1838076Y254412D02*
X1832143Y260345D01*
G01X1834656Y226756D02*
X1836900Y229000D01*
G01X1832087Y226756D02*
X1834656D01*
G01X1834400Y253218D02*
X1829948Y257670D01*
G01X1834400Y239800D02*
Y253218D01*
G01X1832300Y237700D02*
X1834400Y239800D01*
G01X1830103Y237700D02*
X1832300D01*
G01X1826344Y233941D02*
X1830103Y237700D01*
G01X1825416Y233941D02*
X1826344D01*
G01X1823581Y232106D02*
X1825416Y233941D01*
G01X1822638Y232106D02*
X1823581D01*
G01X1822638D02*
Y226756D01*
G01X1797440Y231260D02*
X1793600Y235100D01*
G01X1797440Y226757D02*
Y231260D01*
G01X1797441Y226756D02*
X1797440Y226757D01*
G01X1806890Y252926D02*
X1805058Y254758D01*
G01X1806890Y244105D02*
Y252926D01*
G01X1803739Y249255D02*
X1804388Y249904D01*
G01X1803739Y244106D02*
Y249255D01*
G01X1803740Y244105D02*
X1803739Y244106D01*
G01X1813189Y231496D02*
Y226756D01*
G01X1817545Y235852D02*
X1813189Y231496D01*
G01X1822877Y235852D02*
X1817545D01*
G01X1839957Y254547D02*
X1832904Y261600D01*
G01X1834907Y234575D02*
X1835936Y235604D01*
G01X1830675Y234575D02*
X1834907D01*
G01X1828936Y232836D02*
X1830675Y234575D01*
G01X1828937Y232835D02*
X1828936Y232836D01*
G01X1828937Y226756D02*
Y232835D01*
G01X1837250Y254071D02*
X1831801Y259520D01*
G01X1824300Y250700D02*
Y251800D01*
G01X1822637Y249037D02*
X1824300Y250700D01*
G01X1822638Y249036D02*
X1822637Y249037D01*
G01X1822638Y244105D02*
Y249036D01*
G01X1824300Y253941D02*
X1822558Y255683D01*
G01X1824300Y251800D02*
Y253941D01*
G01X1835825Y253809D02*
X1831039Y258595D01*
G01X1832616Y236000D02*
X1835825Y239209D01*
G01X1830471Y236000D02*
X1832616D01*
G01X1826662Y232191D02*
X1830471Y236000D01*
G01X1825787Y231316D02*
X1826662Y232191D01*
G01X1825788Y231315D02*
X1825787Y231316D01*
G01X1825788Y226756D02*
Y231315D01*
G01X1794291Y231909D02*
X1793700Y232500D01*
G01X1794291Y226757D02*
Y231909D01*
G01X1794292Y226756D02*
X1794291Y226757D01*
G01X1826287Y253716D02*
Y250000D01*
G01X1823395Y256608D02*
X1826287Y253716D01*
G01X1825788Y249501D02*
X1826287Y250000D01*
G01X1825788Y244105D02*
Y249501D01*
G01X1811600Y526900D02*
X1810350Y525650D01*
G01D02*
X1806699Y529301D01*
G01X1825900Y525900D02*
Y523500D01*
G01X1828400Y528400D02*
X1825900Y525900D01*
G01X1831887Y493855D02*
X1836396Y489346D01*
G01X1831887Y498051D02*
Y493855D01*
G01X1832949Y499113D02*
X1831887Y498051D01*
G01X1834014Y499113D02*
X1832949D01*
G01X1835409Y500508D02*
X1834014Y499113D01*
G01X1835409Y513974D02*
Y500508D01*
G01X1831177Y518206D02*
X1835409Y513974D01*
G01X1831177Y518587D02*
Y518206D01*
G01X1828077Y521687D02*
X1831177Y518587D01*
G01X1825149Y521687D02*
X1828077D01*
G01X1825122Y521714D02*
X1825149Y521687D01*
G01X1812914Y521714D02*
X1825122D01*
G01X1810971Y519771D02*
X1812914Y521714D01*
G01X1798300Y519771D02*
X1810971D01*
G01X1797013Y521058D02*
X1798300Y519771D01*
G01X1797013Y526451D02*
Y521058D01*
G01X1794945Y528519D02*
X1797013Y526451D01*
G01X1832269Y480731D02*
X1837300Y475700D01*
G01X1832269Y486411D02*
Y480731D01*
G01X1818250Y500430D02*
X1832269Y486411D01*
G01X1818250Y510100D02*
Y500430D01*
G01X1815050Y513300D02*
X1818250Y510100D01*
G01X1810200Y513300D02*
X1815050D01*
G01X1831600Y520569D02*
Y529000D01*
G01X1832877Y519292D02*
X1831600Y520569D01*
G01X1832877Y518911D02*
Y519292D01*
G01X1837325Y514463D02*
X1832877Y518911D01*
G01X1835426Y497300D02*
X1837237Y499111D01*
G01X1833700Y497300D02*
X1835426D01*
G01X1779200Y582500D02*
X1777390Y584310D01*
G01X1779400Y582500D02*
X1779200D01*
G01X1828984Y536299D02*
X1822758D01*
G01X1829000Y536315D02*
X1828984Y536299D01*
G01X1811600Y528200D02*
Y526900D01*
G01X1814115Y530715D02*
X1811600Y528200D01*
G01X1814115Y541040D02*
Y530715D01*
G01X1810052Y545103D02*
X1814115Y541040D01*
G01X1806699Y529301D02*
X1803752D01*
G01X1827298Y585511D02*
X1822757D01*
G01X1828522Y584287D02*
X1827298Y585511D01*
G01X1829176Y584287D02*
X1828522D01*
G01X1822757Y587480D02*
X1816458D01*
G01X1780015Y564015D02*
X1781000Y565000D01*
G01X1807789Y561889D02*
X1800207D01*
G01X1812985Y567085D02*
X1807789Y561889D01*
G01X1812985Y578510D02*
Y567085D01*
G01X1812802Y578693D02*
X1812985Y578510D01*
G01X1794507Y579606D02*
X1800206D01*
G01X1793401Y578500D02*
X1794507Y579606D01*
G01X1793100Y578500D02*
X1793401D01*
G01X1778917Y569135D02*
X1780500Y570718D01*
G01X1828400Y533700D02*
Y528400D01*
G01X1827770Y534330D02*
X1828400Y533700D01*
G01X1822758Y534330D02*
X1827770D01*
G01X1807539Y559921D02*
X1800207D01*
G01X1814410Y566792D02*
X1807539Y559921D01*
G01X1814410Y569838D02*
Y566792D01*
G01X1816020Y571448D02*
X1814410Y569838D01*
G01X1795061Y585511D02*
X1800206D01*
G01X1793450Y583900D02*
X1795061Y585511D01*
G01X1792170Y583900D02*
X1793450D01*
G01X1779075Y566575D02*
X1780500Y568000D01*
G01X1795221Y587480D02*
X1800206D01*
G01X1793579Y589122D02*
X1795221Y587480D01*
G01X1828879Y559921D02*
X1822758D01*
G01X1829474Y559326D02*
X1828879Y559921D01*
G01X1829513Y559326D02*
X1829474D01*
G01X1830768Y558071D02*
X1829513Y559326D01*
G01X1839809Y558071D02*
X1830768D01*
G01X1830876Y569084D02*
X1832200Y567760D01*
G01X1830876Y569877D02*
Y569084D01*
G01X1829653Y571100D02*
X1830876Y569877D01*
G01X1828600Y571100D02*
X1829653D01*
G01X1827968Y571732D02*
X1828600Y571100D01*
G01X1822757Y571732D02*
X1827968D01*
G01X1833280Y568840D02*
Y570500D01*
G01X1832200Y567760D02*
X1833280Y568840D01*
G01X1781865Y556335D02*
X1782300Y555900D01*
G01X1822811Y548163D02*
X1822758Y548110D01*
G01X1831337Y548163D02*
X1822811D01*
G01X1831500Y548000D02*
X1831337Y548163D01*
G01X1837462Y579250D02*
X1835000D01*
G01X1830638Y577637D02*
X1822757D01*
G01X1832251Y579250D02*
X1830638Y577637D01*
G01X1835000Y579250D02*
X1832251D01*
G01X1780394Y561004D02*
Y561076D01*
G01X1779943Y561455D02*
X1780394Y561004D01*
G01X1795669Y575669D02*
X1794776Y574776D01*
G01X1800206Y575669D02*
X1795669D01*
G01X1827737Y579606D02*
X1822757D01*
G01X1828592Y580461D02*
X1827737Y579606D01*
G01X1831184Y580461D02*
X1828592D01*
G01X1833473Y582750D02*
X1831184Y580461D01*
G01X1835000Y582750D02*
X1833473D01*
G01X1836402D02*
X1835000D01*
G01X1795084Y555984D02*
X1800207D01*
G01X1794000Y554900D02*
X1795084Y555984D01*
G01X1794000Y552800D02*
Y554900D01*
G01X1812952Y550346D02*
Y545501D01*
G01X1809283Y554015D02*
X1812952Y550346D01*
G01X1800207Y554015D02*
X1809283D01*
G01X1828200Y573700D02*
X1822757D01*
G01X1829000Y572900D02*
X1828200Y573700D01*
G01X1829300Y572900D02*
X1829000D01*
G01X1794945Y537842D02*
Y528519D01*
G01X1795370Y538267D02*
X1794945Y537842D01*
G01X1800207Y538267D02*
X1795370D01*
G01X1831173Y544173D02*
X1831500Y544500D01*
G01X1822758Y544173D02*
X1831173D01*
G01X1834000Y529000D02*
X1840000D01*
G01X1834000D02*
X1831600D01*
G01X1788300Y586600D02*
Y585100D01*
G01X1780350Y594550D02*
X1788300Y586600D01*
G01Y583801D02*
Y585100D01*
G01X1790100Y582001D02*
X1788300Y583801D01*
G01X1793500Y582001D02*
X1790100D01*
G01X1793974Y582475D02*
X1793500Y582001D01*
G01X1794041Y582475D02*
X1793974D01*
G01X1795109Y583543D02*
X1794041Y582475D01*
G01X1800206Y583543D02*
X1795109D01*
G01X1777250Y581750D02*
X1779500Y579500D01*
G01X1829578Y550078D02*
X1831800Y552300D01*
G01X1822758Y550078D02*
X1829578D01*
G01X1795789Y577637D02*
X1800206D01*
G01X1792827Y574675D02*
X1795789Y577637D01*
G01X1792805Y574675D02*
X1792827D01*
G01X1834200Y549500D02*
X1835000Y550300D01*
G01X1834200Y544000D02*
Y549500D01*
G01X1836000Y542200D02*
X1834200Y544000D01*
G01X1829767Y538267D02*
X1822758D01*
G01X1830700Y539200D02*
X1829767Y538267D01*
G01X1831700Y539200D02*
X1830700D01*
G01X1832000Y539500D02*
X1831700Y539200D01*
G01X1832500Y539500D02*
X1832000D01*
G01X1817850Y538267D02*
X1822758D01*
G01X1817834Y538283D02*
X1817850Y538267D01*
G01X1817101Y537550D02*
X1817834Y538283D01*
G01X1817101Y533876D02*
Y537550D01*
G01X1818509Y532468D02*
X1817101Y533876D01*
G01X1818509Y527893D02*
Y532468D01*
G01X1777630Y586870D02*
X1779000Y585500D01*
G01X1816610Y583543D02*
X1816052Y584101D01*
G01X1822757Y583543D02*
X1816610D01*
G01X1800404Y593501D02*
X1800378Y593527D01*
G01X1813301Y593501D02*
X1800404D01*
G01X1814601Y594801D02*
X1813301Y593501D01*
G01X1818445Y594801D02*
X1814601D01*
G01X1819443Y593803D02*
X1818445Y594801D01*
G01X1819654Y593803D02*
X1819443D01*
G01X1805500Y598649D02*
X1800378Y593527D01*
G01X1805500Y603100D02*
Y598649D01*
G01X1786500Y620500D02*
X1788500D01*
G01X1784000Y618000D02*
X1786500Y620500D01*
G01X1784000Y614064D02*
Y618000D01*
G01X1786058Y612006D02*
X1784000Y614064D01*
G01X1788290Y612006D02*
X1786058D01*
G01X1795000Y592163D02*
Y599600D01*
G01X1795746Y591417D02*
X1795000Y592163D01*
G01X1800206Y591417D02*
X1795746D01*
G01X1791349Y589122D02*
X1793579D01*
G01X1778639Y592224D02*
X1778675D01*
G01X1778405Y591990D02*
X1778639Y592224D01*
G01X1778070Y589430D02*
X1779000Y588500D01*
G01D02*
X1782000D01*
G01X1795269Y589448D02*
X1800206D01*
G01X1791323Y593394D02*
X1795269Y589448D01*
G01X1791323Y594030D02*
Y593394D01*
G01X1796240Y616122D02*
X1795500Y615382D01*
G01X1799222Y616122D02*
X1796240D01*
G01X1800200Y617100D02*
X1799222Y616122D01*
G01X1800200Y621400D02*
Y617100D01*
G01X1798600Y623000D02*
X1800200Y621400D01*
G01X1786000Y623000D02*
X1798600D01*
G01X1782100Y619100D02*
X1786000Y623000D01*
G01X1782100Y611500D02*
Y619100D01*
G01X1782700Y610900D02*
X1782100Y611500D01*
G01X1827200Y589448D02*
X1822757D01*
G01X1829051Y591299D02*
X1827200Y589448D01*
G01X1795500Y614700D02*
Y615382D01*
G01X1796400Y613800D02*
X1795500Y614700D01*
G01X1798000Y613800D02*
X1796400D01*
G01X1801700Y610100D02*
X1798000Y613800D01*
G01X1821529Y610100D02*
X1801700D01*
G01X1829051Y602578D02*
X1821529Y610100D01*
G01X1829051Y591299D02*
Y602578D01*
G01X1778400Y622600D02*
Y618900D01*
G01X1777027Y623973D02*
X1778400Y622600D01*
G01X1776500Y621900D02*
Y621200D01*
G01X1775452Y622948D02*
X1776500Y621900D01*
G01X1785699Y591500D02*
X1787500D01*
G01X1784200Y592999D02*
X1785699Y591500D01*
G01X1784200Y593924D02*
Y592999D01*
G01X1788500Y609000D02*
X1780543D01*
G01X1790000Y610500D02*
X1788500Y609000D01*
G01X1790000Y613000D02*
Y610500D01*
G01X1789031Y613969D02*
X1790000Y613000D01*
G01X1786226Y613969D02*
X1789031D01*
G01X1785500Y614695D02*
X1786226Y613969D01*
G01X1785500Y617000D02*
Y614695D01*
G01X1786441Y617941D02*
X1785500Y617000D01*
G01X1788500Y617941D02*
X1786441D01*
G01X1788500D02*
X1795500D01*
G01X1798000Y620500D02*
X1795500D01*
G01X1798500Y620000D02*
X1798000Y620500D01*
G01X1798500Y618400D02*
Y620000D01*
G01X1798041Y617941D02*
X1798500Y618400D01*
G01X1795500Y617941D02*
X1798041D01*
G01X1776500Y607000D02*
Y604500D01*
G01X1778500Y609000D02*
X1776500Y607000D01*
G01X1780543Y609000D02*
X1778500D01*
G01X1844407Y14323D02*
Y17268D01*
G01X1845420Y13310D02*
X1844407Y14323D01*
G01X1837100Y-18500D02*
X1836700Y-18900D01*
G01X1837100Y-15700D02*
Y-18500D01*
G01X1837440Y-8540D02*
X1835874D01*
G01X1838376Y-9476D02*
X1837440Y-8540D01*
G01X1838537Y-10286D02*
X1838376Y-9476D01*
G01X1838537Y-10695D02*
Y-10286D01*
G01X1838542Y-10700D02*
X1838537Y-10695D01*
G01X1838542Y-12345D02*
Y-10700D01*
G01X1837100Y-13787D02*
X1838542Y-12345D01*
G01X1837100Y-15700D02*
Y-13787D01*
G01X1841257Y32609D02*
Y30668D01*
G01X1839400Y34466D02*
X1841257Y32609D01*
G01X1838107Y34563D02*
Y30668D01*
G01Y14493D02*
Y17268D01*
G01X1838850Y13750D02*
X1838107Y14493D01*
G01X1838850Y13160D02*
Y13750D01*
G01X1844407Y36843D02*
Y30668D01*
G01X1841257Y10557D02*
Y17268D01*
G01X1840400Y9700D02*
X1841257Y10557D01*
G01X1839400Y39500D02*
Y34466D01*
G01X1838500Y40400D02*
X1839400Y39500D01*
G01X1837500Y35170D02*
X1838107Y34563D01*
G01X1837500Y35700D02*
Y35170D01*
G01X1836359Y89175D02*
X1838400D01*
G01X1845744Y38180D02*
X1844407Y36843D01*
G01X1853017Y38180D02*
X1845744D01*
G01X1856333Y34864D02*
X1853017Y38180D01*
G01X1856333Y34518D02*
Y34864D01*
G01X1836750Y79650D02*
Y81300D01*
G01X1895354Y75650D02*
X1902588D01*
G01X1859500Y123190D02*
Y120500D01*
G01X1858800Y123890D02*
X1859500Y123190D01*
G01X1858800Y127839D02*
Y123890D01*
G01X1857020Y129619D02*
X1858800Y127839D01*
G01X1878500Y149144D02*
Y147750D01*
G01X1878096Y149548D02*
X1878500Y149144D01*
G01X1878096Y152843D02*
Y149548D01*
G01X1869600Y138200D02*
X1868541D01*
G01X1870000Y138600D02*
X1869600Y138200D01*
G01X1870000Y140750D02*
Y138600D01*
G01X1866809Y128390D02*
X1869250D01*
G01X1866150Y129049D02*
X1866809Y128390D01*
G01X1866150Y131721D02*
Y129049D01*
G01X1865748Y132123D02*
X1866150Y131721D01*
G01X1865748Y132164D02*
Y132123D01*
G01X1865500Y132412D02*
X1865748Y132164D01*
G01X1865500Y136449D02*
Y132412D01*
G01X1867251Y138200D02*
X1865500Y136449D01*
G01X1868541Y138200D02*
X1867251D01*
G01X1893750Y130360D02*
X1897400D01*
G01X1878500Y142027D02*
Y144250D01*
G01X1877111Y140638D02*
X1878500Y142027D01*
G01X1877111Y138991D02*
Y140638D01*
G01X1876570Y138450D02*
X1877111Y138991D01*
G01X1876570Y133750D02*
Y138450D01*
G01X1882480Y106876D02*
X1881165Y105561D01*
G01X1882480Y109250D02*
Y106876D01*
G01X1880510Y106216D02*
Y109250D01*
G01X1881165Y105561D02*
X1880510Y106216D01*
G01X1888870Y142370D02*
X1891350Y144850D01*
G01X1888870Y140100D02*
Y142370D01*
G01Y138270D02*
Y140100D01*
G01X1888390Y137790D02*
X1888870Y138270D01*
G01X1888390Y133750D02*
Y137790D01*
G01X1872031Y144250D02*
X1872400Y144619D01*
G01X1870000Y144250D02*
X1872031D01*
G01X1888390Y106337D02*
X1887497Y105444D01*
G01X1888390Y109250D02*
Y106337D01*
G01X1866500Y148100D02*
Y144250D01*
G01X1868100Y149700D02*
X1866500Y148100D01*
G01X1869700Y151300D02*
X1868100Y149700D01*
G01X1869700Y151772D02*
Y151300D01*
G01X1871521Y153593D02*
X1869700Y151772D01*
G01X1893750Y122480D02*
X1898323D01*
G01X1893750Y124450D02*
X1897507D01*
G01X1897165Y127355D02*
X1897420Y127100D01*
G01X1897149Y127355D02*
X1897165D01*
G01X1896114Y128390D02*
X1897149Y127355D01*
G01X1893750Y128390D02*
X1896114D01*
G01X1862632Y137382D02*
X1863358Y138108D01*
G01X1862632Y131943D02*
Y137382D01*
G01X1864804Y129771D02*
X1862632Y131943D01*
G01X1864804Y128545D02*
Y129771D01*
G01X1866929Y126420D02*
X1864804Y128545D01*
G01X1869250Y126420D02*
X1866929D01*
G01X1865375Y139625D02*
X1866500Y140750D01*
G01X1864875Y139625D02*
X1865375D01*
G01X1863358Y138108D02*
X1864875Y139625D01*
G01X1859337Y150348D02*
X1854637D01*
G01X1859931Y149754D02*
X1859337Y150348D01*
G01X1859931Y148432D02*
Y149754D01*
G01X1861932Y146431D02*
X1859931Y148432D01*
G01X1862500Y146999D02*
X1861932Y146431D01*
G01X1862500Y150000D02*
Y146999D01*
G01X1864500Y117500D02*
X1863000D01*
G01X1867400Y114600D02*
X1864500Y117500D01*
G01X1869250Y114600D02*
X1867400D01*
G01X1874178Y147750D02*
X1875500D01*
G01X1872928Y149000D02*
X1874178Y147750D01*
G01X1871738Y149000D02*
X1872928D01*
G01X1869668Y146930D02*
X1871738Y149000D01*
G01X1869668Y146750D02*
Y146930D01*
G01X1866606Y112204D02*
Y109967D01*
G01X1867032Y112630D02*
X1866606Y112204D01*
G01X1869250Y112630D02*
X1867032D01*
G01X1864500Y120500D02*
X1863000D01*
G01X1865500Y119500D02*
X1864500Y120500D01*
G01X1865500Y118500D02*
Y119500D01*
G01X1867430Y116570D02*
X1865500Y118500D01*
G01X1869250Y116570D02*
X1867430D01*
G01X1881500Y149651D02*
Y147750D01*
G01X1883153Y151304D02*
X1881500Y149651D01*
G01X1883153Y154168D02*
Y151304D01*
G01X1882915Y154406D02*
X1883153Y154168D01*
G01X1882849Y154406D02*
X1882915D01*
G01X1882266Y154989D02*
X1882849Y154406D01*
G01X1880001Y154989D02*
X1882266D01*
G01X1879605Y154593D02*
X1880001Y154989D01*
G01X1873707Y154593D02*
X1879605D01*
G01X1872700Y155600D02*
X1873707Y154593D01*
G01X1861000Y155600D02*
X1872700D01*
G01X1859563Y157037D02*
X1861000Y155600D01*
G01X1882743Y139957D02*
X1881700Y141000D01*
G01X1882743Y137291D02*
Y139957D01*
G01X1882480Y137028D02*
X1882743Y137291D01*
G01X1882480Y133750D02*
Y137028D01*
G01X1881500Y141200D02*
X1881700Y141000D01*
G01X1881500Y144250D02*
Y141200D01*
G01X1893750Y116570D02*
X1899000D01*
G01X1858500Y117500D02*
X1859500D01*
G01X1857810Y118190D02*
X1858500Y117500D01*
G01X1857810Y125829D02*
Y118190D01*
G01X1857020Y126619D02*
X1857810Y125829D01*
G01X1874600Y133750D02*
Y140762D01*
G01X1875500Y142901D02*
Y144250D01*
G01X1874600Y142001D02*
X1875500Y142901D01*
G01X1874600Y140762D02*
Y142001D01*
G01X1882116Y211752D02*
X1883800Y213436D01*
G01X1877028Y211752D02*
X1882116D01*
G01X1874000Y208724D02*
X1877028Y211752D01*
G01X1874000Y207150D02*
Y208724D01*
G01X1867500Y200650D02*
X1874000Y207150D01*
G01X1867500Y190000D02*
Y200650D01*
G01X1864000Y186500D02*
X1867500Y190000D01*
G01X1864000Y184900D02*
Y186500D01*
G01X1881400Y188099D02*
Y189350D01*
G01X1883350Y186149D02*
X1881400Y188099D01*
G01X1884951Y186149D02*
X1883350D01*
G01X1887173Y183927D02*
X1884951Y186149D01*
G01X1889300Y183927D02*
X1887173D01*
G01X1878500Y189350D02*
X1881400D01*
G01X1876900Y187750D02*
X1878500Y189350D01*
G01X1868250Y187750D02*
X1876900D01*
G01X1865400Y184900D02*
X1868250Y187750D01*
G01X1864000Y184900D02*
X1865400D01*
G01X1838346Y186937D02*
X1838350D01*
G01X1838346Y181246D02*
Y186937D01*
G01X1836800Y179700D02*
X1838346Y181246D01*
G01X1836100Y179700D02*
X1836800D01*
G01X1881400Y175832D02*
X1882548Y174684D01*
G01X1881400Y177850D02*
Y175832D01*
G01X1887189Y174084D02*
X1889300D01*
G01X1886948Y174325D02*
X1887189Y174084D01*
G01X1885102Y174325D02*
X1886948D01*
G01X1884680Y173903D02*
X1885102Y174325D01*
G01X1883329Y173903D02*
X1884680D01*
G01X1882548Y174684D02*
X1883329Y173903D01*
G01X1884508Y164242D02*
X1882650Y166100D01*
G01X1889300Y164242D02*
X1884508D01*
G01X1887737Y197496D02*
Y196600D01*
G01X1895026Y204785D02*
X1887737Y197496D01*
G01X1895614Y204785D02*
X1895026D01*
G01X1887737Y190299D02*
Y196600D01*
G01X1889300Y188736D02*
X1887737Y190299D01*
G01X1889300Y187864D02*
Y188736D01*
G01X1859463Y179600D02*
X1858686Y180377D01*
G01X1873600Y179600D02*
X1859463D01*
G01X1879880Y173320D02*
X1873600Y179600D01*
G01X1879880Y171780D02*
Y173320D01*
G01X1879150Y171050D02*
X1879880Y171780D01*
G01X1879150Y169100D02*
Y171050D01*
G01X1870140Y205940D02*
X1872100Y207900D01*
G01X1865940Y205940D02*
X1870140D01*
G01X1861757Y201757D02*
X1865940Y205940D01*
G01X1861757Y184178D02*
Y201757D01*
G01X1861243Y183664D02*
X1861757Y184178D01*
G01X1861243Y183100D02*
Y183664D01*
G01X1877900Y162600D02*
X1879150D01*
G01X1877650Y162350D02*
X1877900Y162600D01*
G01X1875900Y162350D02*
X1877650D01*
G01X1874746D02*
X1875900D01*
G01X1872362Y159966D02*
X1874746Y162350D01*
G01X1870050Y159966D02*
X1872362D01*
G01X1885465Y166285D02*
X1882650Y169100D01*
G01X1885540Y166210D02*
X1885465Y166285D01*
G01X1889300Y166210D02*
X1885540D01*
G01X1885801Y183700D02*
X1884400D01*
G01X1887543Y181958D02*
X1885801Y183700D01*
G01X1889300Y181958D02*
X1887543D01*
G01X1893586Y198506D02*
Y196570D01*
G01X1895100Y200020D02*
X1893586Y198506D01*
G01X1895100Y201770D02*
Y200020D01*
G01X1893586Y194265D02*
Y196570D01*
G01X1895673Y192178D02*
X1893586Y194265D01*
G01X1895673Y190300D02*
Y192178D01*
G01X1844650Y180750D02*
Y186937D01*
G01X1845700Y179700D02*
X1844650Y180750D01*
G01X1883050Y163000D02*
X1882650Y162600D01*
G01X1887101Y163000D02*
X1883050D01*
G01X1887828Y162273D02*
X1887101Y163000D01*
G01X1889300Y162273D02*
X1887828D01*
G01X1845387Y203499D02*
X1844650Y204236D01*
G01X1845387Y201299D02*
Y203499D01*
G01X1847000Y199686D02*
X1845387Y201299D01*
G01X1847000Y198600D02*
Y199686D01*
G01X1840900Y186337D02*
X1841500Y186937D01*
G01X1840900Y179700D02*
Y186337D01*
G01X1896710Y194140D02*
X1897642Y193208D01*
G01X1896710Y194380D02*
Y194140D01*
G01X1860332Y198268D02*
X1858500Y200100D01*
G01X1860332Y184812D02*
Y198268D01*
G01X1859563Y184043D02*
X1860332Y184812D01*
G01X1859563Y182497D02*
Y184043D01*
G01X1859580Y182480D02*
X1859563Y182497D01*
G01X1859580Y182411D02*
Y182480D01*
G01X1860554Y181437D02*
X1859580Y182411D01*
G01X1860623Y181437D02*
X1860554D01*
G01X1860960Y181100D02*
X1860623Y181437D01*
G01X1874116Y181100D02*
X1860960D01*
G01X1884313Y170903D02*
X1874116Y181100D01*
G01X1884313Y169688D02*
Y170903D01*
G01X1885822Y168179D02*
X1884313Y169688D01*
G01X1889300Y168179D02*
X1885822D01*
G01X1891990Y199268D02*
X1892791Y200069D01*
G01X1891958Y199268D02*
X1891990D01*
G01X1890830Y198140D02*
X1891958Y199268D01*
G01X1890830Y195270D02*
Y198140D01*
G01X1893705Y192395D02*
X1890830Y195270D01*
G01X1893705Y190300D02*
Y192395D01*
G01X1867584Y164400D02*
X1863750Y168234D01*
G01X1872800Y164400D02*
X1867584D01*
G01X1873750Y165350D02*
X1872800Y164400D01*
G01X1875900Y165350D02*
X1873750D01*
G01X1877050D02*
X1875900D01*
G01X1877800Y166100D02*
X1877050Y165350D01*
G01X1879150Y166100D02*
X1877800D01*
G01X1877517Y216038D02*
Y217988D01*
G01X1876660Y215181D02*
X1877517Y216038D01*
G01X1876660Y213770D02*
Y215181D01*
G01X1874224Y211334D02*
X1876660Y213770D01*
G01X1867382Y211334D02*
X1874224D01*
G01X1856837Y200789D02*
X1867382Y211334D01*
G01X1856837Y199021D02*
Y200789D01*
G01X1858907Y196951D02*
X1856837Y199021D01*
G01X1858907Y185403D02*
Y196951D01*
G01X1856806Y183302D02*
X1858907Y185403D01*
G01X1856806Y178894D02*
Y183302D01*
G01X1860200Y175500D02*
X1856806Y178894D01*
G01X1864200Y175500D02*
X1860200D01*
G01X1865100Y174600D02*
X1864200Y175500D01*
G01X1885000Y188100D02*
X1884000D01*
G01X1887205Y185895D02*
X1885000Y188100D01*
G01X1889300Y185895D02*
X1887205D01*
G01X1859563Y163681D02*
Y157037D01*
G01X1859567Y163685D02*
X1859563Y163681D01*
G01X1859567Y165063D02*
Y163685D01*
G01X1859563Y165067D02*
X1859567Y165063D01*
G01X1859563Y169915D02*
Y165067D01*
G01X1856489Y172989D02*
X1859563Y169915D01*
G01X1855459Y172989D02*
X1856489D01*
G01X1852537Y175911D02*
X1855459Y172989D01*
G01X1852537Y182336D02*
Y175911D01*
G01X1854868Y184667D02*
X1852537Y182336D01*
G01X1887600Y158300D02*
X1886000Y156700D01*
G01X1887600Y158336D02*
Y158300D01*
G01X1889300Y158336D02*
X1887600D01*
G01X1882650Y158292D02*
Y159100D01*
G01X1882958Y157984D02*
X1882650Y158292D01*
G01X1882958Y157542D02*
Y157984D01*
G01X1883800Y156700D02*
X1882958Y157542D01*
G01X1886000Y156700D02*
X1883800D01*
G01X1849616Y226701D02*
X1856874Y219443D01*
G01X1849616Y243112D02*
Y226701D01*
G01X1841382Y251346D02*
X1849616Y243112D01*
G01X1841382Y255467D02*
Y251346D01*
G01X1838076Y254059D02*
Y254412D01*
G01X1838075Y254058D02*
X1838076Y254059D01*
G01X1838075Y233875D02*
Y254058D01*
G01X1836900Y232700D02*
X1838075Y233875D01*
G01X1836900Y229000D02*
Y232700D01*
G01X1839957Y250755D02*
Y254547D01*
G01X1845726Y244986D02*
X1839957Y250755D01*
G01X1845726Y225317D02*
Y244986D01*
G01X1844444Y224035D02*
X1845726Y225317D01*
G01X1837250Y236918D02*
Y254071D01*
G01X1835936Y235604D02*
X1837250Y236918D01*
G01X1835825Y239209D02*
Y253809D01*
G01X1873232Y455632D02*
Y460603D01*
G01X1872400Y454800D02*
X1873232Y455632D01*
G01X1860630Y454800D02*
X1872400D01*
G01X1858633Y452803D02*
X1860630Y454800D01*
G01X1879531Y447669D02*
Y441754D01*
G01X1878663Y448537D02*
X1879531Y447669D01*
G01X1877411Y448537D02*
X1878663D01*
G01X1875900Y450048D02*
X1877411Y448537D01*
G01X1875900Y453600D02*
Y450048D01*
G01X1879527Y460603D02*
Y476926D01*
G01X1879531Y460603D02*
X1879527D01*
G01X1870082D02*
X1870092Y465920D01*
G01X1870082Y452289D02*
Y441754D01*
G01X1870815Y453022D02*
X1870082Y452289D01*
G01X1876381Y461456D02*
X1876414Y470785D01*
G01X1876382Y461455D02*
X1876381Y461456D01*
G01X1876382Y460603D02*
Y461455D01*
G01X1873232Y447578D02*
X1872860Y447950D01*
G01X1873232Y441754D02*
Y447578D01*
G01X1851185Y460603D02*
Y467091D01*
G01X1857480Y441758D02*
X1857484Y441754D01*
G01X1857480Y447281D02*
Y441758D01*
G01X1858275Y448076D02*
X1857480Y447281D01*
G01X1859059Y448076D02*
X1858275D01*
G01X1866933Y447333D02*
X1867500Y447900D01*
G01X1866933Y441754D02*
Y447333D01*
G01X1854334Y460603D02*
Y466334D01*
G01X1866933Y465951D02*
Y460603D01*
G01X1860633Y447298D02*
Y441754D01*
G01X1863137Y449802D02*
X1860633Y447298D01*
G01X1863137Y452710D02*
Y449802D01*
G01X1863783Y467718D02*
Y460603D01*
G01X1876382Y447028D02*
Y441754D01*
G01X1872860Y450550D02*
X1876382Y447028D01*
G01X1841299Y526000D02*
X1841835Y526536D01*
G01X1840000Y526000D02*
X1841299D01*
G01X1845374Y521126D02*
X1851504D01*
G01X1844900Y521600D02*
X1845374Y521126D01*
G01X1844900Y526000D02*
Y521600D01*
G01X1842764Y528136D02*
X1844900Y526000D01*
G01X1879527Y476926D02*
X1877407Y479046D01*
G01X1870092Y465930D02*
X1868167Y467855D01*
G01X1870092Y465920D02*
Y465930D01*
G01X1846692Y513252D02*
X1851504D01*
G01X1844570Y511130D02*
X1846692Y513252D01*
G01X1841300Y511130D02*
X1844570D01*
G01X1839430Y513000D02*
X1841300Y511130D01*
G01X1839000Y513000D02*
X1839430D01*
G01X1876414Y470785D02*
X1876945Y471316D01*
G01X1845778Y505378D02*
X1851504D01*
G01X1842700Y502300D02*
X1845778Y505378D01*
G01X1838900Y502300D02*
X1842700D01*
G01X1851185Y467091D02*
X1855206Y471112D01*
G01X1836396Y489346D02*
Y481349D01*
G01X1837300Y475700D02*
Y472276D01*
G01X1838900Y498800D02*
X1841900D01*
G01X1844220Y509500D02*
X1844490Y509230D01*
G01X1839000Y509500D02*
X1844220D01*
G01X1837325Y503662D02*
Y514463D01*
G01X1837237Y503574D02*
X1837325Y503662D01*
G01X1837237Y499111D02*
Y503574D01*
G01X1876400Y500265D02*
X1875973Y499838D01*
G01X1876400Y511600D02*
Y500265D01*
G01X1874748Y513252D02*
X1876400Y511600D01*
G01X1868204Y513252D02*
X1874748D01*
G01X1894385Y525415D02*
X1892720D01*
G01X1899200Y520600D02*
X1894385Y525415D01*
G01X1857450Y469450D02*
Y473654D01*
G01X1854334Y466334D02*
X1857450Y469450D01*
G01X1864658Y481658D02*
X1863000Y480000D01*
G01X1905873Y481658D02*
X1864658D01*
G01X1863247Y469637D02*
X1866933Y465951D01*
G01X1863247Y475650D02*
Y469637D01*
G01X1862496Y476401D02*
X1863247Y475650D01*
G01X1862496Y479496D02*
Y476401D01*
G01X1863000Y480000D02*
X1862496Y479496D01*
G01X1859600Y479734D02*
Y476200D01*
G01X1862549Y482683D02*
X1859600Y479734D01*
G01X1906157Y482683D02*
X1862549D01*
G01X1862322Y469179D02*
X1863783Y467718D01*
G01X1862322Y475266D02*
Y469179D01*
G01X1861388Y476200D02*
X1862322Y475266D01*
G01X1859600Y476200D02*
X1861388D01*
G01X1857996Y497504D02*
X1860000Y495500D01*
G01X1851504Y497504D02*
X1857996D01*
G01X1873510Y548190D02*
Y545500D01*
G01X1873200Y548500D02*
X1873510Y548190D01*
G01X1868250Y548500D02*
X1873200D01*
G01X1864750Y545000D02*
X1868250Y548500D01*
G01X1873510Y545500D02*
Y541710D01*
G01X1891560Y580940D02*
Y575700D01*
G01X1890600Y581900D02*
X1891560Y580940D01*
G01X1887500Y581900D02*
X1890600D01*
G01X1885100Y584300D02*
X1887500Y581900D01*
G01X1873200Y584300D02*
X1871100Y586400D01*
G01X1885100Y584300D02*
X1873200D01*
G01X1841835Y527207D02*
X1842764Y528136D01*
G01X1841835Y526536D02*
Y527207D01*
G01X1853122Y582750D02*
X1862500D01*
G01X1851250Y584622D02*
X1853122Y582750D01*
G01X1862500D02*
Y577750D01*
G01X1867400Y577600D02*
Y574350D01*
G01X1868000Y578200D02*
X1867400Y577600D01*
G01X1868000Y580750D02*
Y578200D01*
G01X1896200Y547000D02*
X1898248D01*
G01X1894600Y548600D02*
X1896200Y547000D01*
G01X1889600Y548600D02*
X1894600D01*
G01X1887100Y546100D02*
X1889600Y548600D01*
G01X1840690Y557190D02*
X1839809Y558071D01*
G01X1865100Y574900D02*
Y590900D01*
G01X1864450Y574250D02*
X1865100Y574900D01*
G01X1862500Y574250D02*
X1864450D01*
G01X1837534Y579322D02*
X1837462Y579250D01*
G01X1845148Y529000D02*
X1851504D01*
G01X1841648Y532500D02*
X1845148Y529000D01*
G01X1840000Y532500D02*
X1841648D01*
G01X1838506Y570500D02*
X1836780D01*
G01X1838627Y570379D02*
X1838506Y570500D01*
G01X1840129Y570379D02*
X1838627D01*
G01X1840250Y570500D02*
X1840129Y570379D01*
G01X1843200Y570500D02*
X1840250D01*
G01X1844650Y571950D02*
X1843200Y570500D01*
G01X1855050Y571950D02*
X1844650D01*
G01X1855587Y571413D02*
X1855050Y571950D01*
G01X1871637Y571413D02*
X1855587D01*
G01X1875850Y567200D02*
X1871637Y571413D01*
G01X1837006Y583354D02*
X1836402Y582750D01*
G01X1839126Y583354D02*
X1837006D01*
G01X1891560Y571440D02*
Y568300D01*
G01X1891000Y572000D02*
X1891560Y571440D01*
G01X1887500Y572000D02*
X1891000D01*
G01X1886440Y573060D02*
X1887500Y572000D01*
G01X1886440Y575700D02*
Y573060D01*
G01X1838559Y536459D02*
Y539500D01*
G01X1837000Y534900D02*
X1838559Y536459D01*
G01X1878996Y588061D02*
X1881806D01*
G01X1878678Y588379D02*
X1878996Y588061D01*
G01X1870950Y554950D02*
Y552500D01*
G01X1871300Y555300D02*
X1870950Y554950D01*
G01X1873100Y555300D02*
X1871300D01*
G01X1873510Y554890D02*
X1873100Y555300D01*
G01X1873510Y552500D02*
Y554890D01*
G01X1870950Y549950D02*
Y552500D01*
G01X1870500Y549500D02*
X1870950Y549950D01*
G01X1864750Y549500D02*
X1870500D01*
G01X1894512Y539500D02*
X1896450D01*
G01X1893349Y540663D02*
X1894512Y539500D01*
G01X1890660Y540663D02*
X1893349D01*
G01X1886865Y562500D02*
X1888250D01*
G01X1886440Y562925D02*
X1886865Y562500D01*
G01X1886440Y568300D02*
Y562925D01*
G01X1885050Y568300D02*
X1886440D01*
G01X1882300Y565550D02*
X1885050Y568300D01*
G01X1883000Y558950D02*
Y557160D01*
G01X1884250Y560200D02*
X1883000Y558950D01*
G01X1884250Y562500D02*
Y560200D01*
G01X1852126Y569750D02*
X1851250Y568874D01*
G01X1862000Y569750D02*
X1852126D01*
G01X1836000Y539500D02*
Y542200D01*
G01X1894060Y552040D02*
X1890400D01*
G01X1897300Y548800D02*
X1894060Y552040D01*
G01X1876070Y543290D02*
Y545500D01*
G01X1878697Y540663D02*
X1876070Y543290D01*
G01X1882660Y540663D02*
X1878697D01*
G01X1868000Y586800D02*
X1866800Y588000D01*
G01X1868000Y584250D02*
Y586800D01*
G01X1887660Y557160D02*
X1890400D01*
G01X1886800Y556300D02*
X1887660Y557160D01*
G01X1886800Y553051D02*
Y556300D01*
G01X1885789Y552040D02*
X1886800Y553051D01*
G01X1883000Y552040D02*
X1885789D01*
G01X1878875Y562925D02*
Y565475D01*
G01X1879300Y562500D02*
X1878875Y562925D01*
G01X1880750Y562500D02*
X1879300D01*
G01X1889833Y624365D02*
X1961517D01*
G01X1884643Y619175D02*
X1889833Y624365D01*
G01X1884643Y605759D02*
Y619175D01*
G01X1883600Y604716D02*
X1884643Y605759D01*
G01X1883600Y601300D02*
Y604716D01*
G01X1875020Y592720D02*
X1883600Y601300D01*
G01X1866920Y592720D02*
X1875020D01*
G01X1865100Y590900D02*
X1866920Y592720D01*
G01X1891932Y622432D02*
X1959418D01*
G01X1887000Y617500D02*
X1891932Y622432D01*
G01X1887000Y604084D02*
Y617500D01*
G01X1886200Y603284D02*
X1887000Y604084D01*
G01X1886200Y600600D02*
Y603284D01*
G01X1881806Y596206D02*
X1886200Y600600D01*
G01X1881806Y591561D02*
Y596206D01*
G01X1875721Y588379D02*
X1878678D01*
G01X1875600Y588500D02*
X1875721Y588379D01*
G01X1872700Y591500D02*
X1871100Y589900D01*
G01X1875350Y591500D02*
X1872700D01*
G01X1885025Y601175D02*
X1875350Y591500D01*
G01X1885025Y604125D02*
Y601175D01*
G01X1886074Y605174D02*
X1885025Y604125D01*
G01X1886074Y618590D02*
Y605174D01*
G01X1890841Y623357D02*
X1886074Y618590D01*
G01X1960509Y623357D02*
X1890841D01*
G01X1902588Y75650D02*
X1903648Y76710D01*
G01X1922800Y93800D02*
Y90900D01*
G01X1923300Y94300D02*
X1922800Y93800D01*
G01X1923100Y123200D02*
X1922526Y122626D01*
G01X1924625Y123200D02*
X1923100D01*
G01X1926028Y121797D02*
X1924625Y123200D01*
G01X1926298Y121797D02*
X1926028D01*
G01X1926892Y121203D02*
X1926298Y121797D01*
G01X1921144Y121244D02*
X1922526Y122626D01*
G01X1921144Y118844D02*
Y121244D01*
G01X1926952Y158970D02*
Y156049D01*
G01X1919451Y155744D02*
X1919295Y155900D01*
G01X1919451Y152461D02*
Y155744D01*
G01X1921189Y150723D02*
X1919451Y152461D01*
G01X1923523Y150723D02*
X1921189D01*
G01X1923800Y151000D02*
X1923523Y150723D01*
G01X1897760Y130000D02*
X1900200D01*
G01X1897400Y130360D02*
X1897760Y130000D01*
G01X1921139Y104528D02*
Y105424D01*
G01X1920307Y103696D02*
X1921139Y104528D01*
G01X1916094Y103696D02*
X1920307D01*
G01X1920323Y105424D02*
X1921139D01*
G01X1919409Y106338D02*
X1920323Y105424D01*
G01X1919409Y123009D02*
Y106338D01*
G01X1924100Y127700D02*
X1919409Y123009D01*
G01X1924100Y127254D02*
Y127700D01*
G01X1927810Y123544D02*
X1924100Y127254D01*
G01X1925500Y131984D02*
Y132500D01*
G01X1925925Y131559D02*
X1925500Y131984D01*
G01X1928126Y131559D02*
X1925925D01*
G01X1928648Y131037D02*
X1928126Y131559D01*
G01X1929756Y131037D02*
X1928648D01*
G01X1937337Y135638D02*
X1941449Y139750D01*
G01X1934815Y134594D02*
X1937337Y135638D01*
G01X1933849Y134594D02*
X1934815D01*
G01X1933849D02*
X1931550D01*
G01X1929494D02*
X1931550D01*
G01X1927400Y132500D02*
X1929494Y134594D01*
G01X1925500Y132500D02*
X1927400D01*
G01X1953055Y144173D02*
X1955531D01*
G01X1951685Y145543D02*
X1953055Y144173D01*
G01X1947242Y145543D02*
X1951685D01*
G01X1941449Y139750D02*
X1947242Y145543D01*
G01X1925040Y102760D02*
X1925300Y102500D01*
G01X1920740Y102760D02*
X1925040D01*
G01X1919645Y101665D02*
X1920740Y102760D01*
G01X1913319Y101665D02*
X1919645D01*
G01X1912894Y102090D02*
X1913319Y101665D01*
G01X1912894Y103646D02*
Y102090D01*
G01X1925300Y101446D02*
X1923329Y99475D01*
G01X1925300Y102500D02*
Y101446D01*
G01X1916526Y149892D02*
X1916310Y149676D01*
G01X1916526Y153474D02*
Y149892D01*
G01X1915358Y154642D02*
X1916526Y153474D01*
G01X1915358Y155900D02*
Y154642D01*
G01X1899495Y120075D02*
X1900290Y119280D01*
G01X1899495Y121308D02*
Y120075D01*
G01X1898323Y122480D02*
X1899495Y121308D01*
G01X1947584Y149415D02*
X1943835Y145666D01*
G01X1949570Y149415D02*
X1947584D01*
G01X1952202Y152047D02*
X1949570Y149415D01*
G01X1955531Y152047D02*
X1952202D01*
G01X1926531Y138531D02*
X1931550D01*
G01X1925300Y137300D02*
X1926531Y138531D01*
G01X1925300Y140627D02*
X1925358Y140685D01*
G01X1925300Y137300D02*
Y140627D01*
G01X1933849Y138531D02*
X1931550D01*
G01X1936700D02*
X1933849D01*
G01X1943835Y145666D02*
X1936700Y138531D01*
G01X1909620Y119000D02*
Y117370D01*
G01X1908280Y120340D02*
X1909620Y119000D01*
G01X1906180Y120340D02*
X1908280D01*
G01X1905120Y119280D02*
X1906180Y120340D01*
G01X1903790Y119280D02*
X1905120D01*
G01X1908986Y118004D02*
X1906414D01*
G01X1909620Y117370D02*
X1908986Y118004D01*
G01X1921959Y115344D02*
X1921144D01*
G01X1923837Y117222D02*
X1921959Y115344D01*
G01X1923837Y118800D02*
Y117222D01*
G01X1908225Y128267D02*
X1911750Y124742D01*
G01X1902709Y128267D02*
X1908225D01*
G01X1901542Y127100D02*
X1902709Y128267D01*
G01X1900200Y127100D02*
X1901542D01*
G01X1897420D02*
X1900200D01*
G01X1916991Y107196D02*
X1916094D01*
G01X1918017Y108222D02*
X1916991Y107196D01*
G01X1918017Y121090D02*
Y108222D01*
G01X1916765Y122342D02*
X1918017Y121090D01*
G01X1916765Y127065D02*
Y122342D01*
G01X1918201Y128501D02*
X1916765Y127065D01*
G01X1919702Y128501D02*
X1918201D01*
G01X1903815Y115305D02*
X1903790Y115280D01*
G01X1906467Y115305D02*
X1903815D01*
G01X1928400Y153600D02*
X1931500D01*
G01X1927000Y152200D02*
X1928400Y153600D01*
G01X1926100Y153100D02*
X1927000Y152200D01*
G01X1926100Y153400D02*
Y153100D01*
G01X1923700Y155800D02*
X1926100Y153400D01*
G01X1923700Y158336D02*
Y155800D01*
G01X1912944Y110696D02*
X1912894Y110646D01*
G01X1916094Y110696D02*
X1912944D01*
G01X1911300Y112240D02*
X1912894Y110646D01*
G01X1911300Y115700D02*
Y112240D01*
G01X1914200Y118600D02*
X1911300Y115700D01*
G01X1915854Y118600D02*
X1914200D01*
G01X1947000Y141574D02*
Y142600D01*
G01X1945415Y139989D02*
X1947000Y141574D01*
G01X1945415Y136315D02*
Y139989D01*
G01X1943900Y134800D02*
X1945415Y136315D01*
G01X1941656Y134800D02*
X1943900D01*
G01X1935589Y132289D02*
X1941656Y134800D01*
G01X1931800Y128500D02*
X1935589Y132289D01*
G01X1931800Y121698D02*
Y128500D01*
G01X1929377Y119275D02*
X1931800Y121698D01*
G01X1929377Y118916D02*
Y119275D01*
G01X1925881Y115420D02*
X1925097D01*
G01X1929377Y118916D02*
X1925881Y115420D01*
G01X1937800Y104200D02*
X1937300Y104700D01*
G01X1937800Y99513D02*
Y104200D01*
G01X1937728Y99441D02*
X1937800Y99513D01*
G01X1911646Y107146D02*
X1912894D01*
G01X1911012Y106512D02*
X1911646Y107146D01*
G01X1911012Y102083D02*
Y106512D01*
G01X1912496Y100599D02*
X1911012Y102083D01*
G01X1918837Y100599D02*
X1912496D01*
G01X1921711Y97725D02*
X1918837Y100599D01*
G01X1925025Y97725D02*
X1921711D01*
G01X1932000Y104700D02*
X1925025Y97725D01*
G01X1937300Y104700D02*
X1932000D01*
G01X1900200Y134040D02*
Y133500D01*
G01X1897640Y136600D02*
X1900200Y134040D01*
G01X1901860Y136600D02*
X1897640D01*
G01X1905450Y133010D02*
X1901860Y136600D01*
G01X1913390Y154257D02*
Y155900D01*
G01X1914610Y153037D02*
X1913390Y154257D01*
G01X1914610Y153020D02*
Y153037D01*
G01X1914690Y152940D02*
X1914610Y153020D01*
G01X1914690Y152580D02*
Y152940D01*
G01X1919484Y151016D02*
Y149500D01*
G01X1918400Y152100D02*
X1919484Y151016D01*
G01X1918400Y153100D02*
Y152100D01*
G01X1917327Y154173D02*
X1918400Y153100D01*
G01X1917327Y155900D02*
Y154173D01*
G01X1928930Y111920D02*
X1931250Y114240D01*
G01X1925097Y111920D02*
X1928930D01*
G01X1925021Y111844D02*
X1925097Y111920D01*
G01X1921144Y111844D02*
X1925021D01*
G01X1921139Y111839D02*
X1921144Y111844D01*
G01X1921139Y108924D02*
Y111839D01*
G01X1931250Y117690D02*
X1932998Y119438D01*
G01X1931250Y114240D02*
Y117690D01*
G01X1931000Y144000D02*
Y147000D01*
G01X1931550Y143450D02*
X1931000Y144000D01*
G01X1931550Y140500D02*
Y143450D01*
G01X1933849Y140500D02*
X1931550D01*
G01X1935207D02*
X1933849D01*
G01X1935663Y140956D02*
X1935207Y140500D01*
G01X1935695Y140956D02*
X1935663D01*
G01X1942665Y147926D02*
X1935695Y140956D01*
G01X1942665Y160414D02*
Y147926D01*
G01X1933900Y147000D02*
X1934000Y147100D01*
G01X1931000Y147000D02*
X1933900D01*
G01X1899000Y116570D02*
X1900290Y115280D01*
G01X1953096Y102580D02*
X1952726Y102950D01*
G01X1955426Y102580D02*
X1953096D01*
G01X1927300Y184100D02*
X1930150D01*
G01X1925158Y181958D02*
X1927300Y184100D01*
G01X1923700Y181958D02*
X1925158D01*
G01X1925617Y160305D02*
X1926952Y158970D01*
G01X1923700Y160305D02*
X1925617D01*
G01X1922800Y194900D02*
X1921500Y193600D01*
G01X1922800Y196050D02*
Y194900D01*
G01X1919296Y192396D02*
Y190300D01*
G01X1920500Y193600D02*
X1919296Y192396D01*
G01X1921500Y193600D02*
X1920500D01*
G01X1931950Y195020D02*
Y196100D01*
G01X1930120Y193190D02*
X1931950Y195020D01*
G01X1929090Y193190D02*
X1930120D01*
G01X1927900Y192000D02*
X1929090Y193190D01*
G01X1927900Y190100D02*
Y192000D01*
G01X1926500Y188700D02*
X1927900Y190100D01*
G01X1926500Y187500D02*
Y188700D01*
G01X1924895Y185895D02*
X1926500Y187500D01*
G01X1923700Y185895D02*
X1924895D01*
G01X1923700Y190700D02*
X1925000Y192000D01*
G01X1923700Y187864D02*
Y190700D01*
G01X1931574Y171421D02*
X1930300Y170147D01*
G01X1932661Y171421D02*
X1931574D01*
G01X1933250Y172010D02*
X1932661Y171421D01*
G01X1933250Y173600D02*
Y172010D01*
G01X1925252Y170147D02*
X1923700D01*
G01X1926699Y168700D02*
X1925252Y170147D01*
G01X1928853Y168700D02*
X1926699D01*
G01X1930300Y170147D02*
X1928853Y168700D01*
G01X1950531Y187480D02*
X1955531D01*
G01X1949901Y188110D02*
X1950531Y187480D01*
G01X1939870Y169600D02*
X1940240Y169970D01*
G01X1936750Y169600D02*
X1939870D01*
G01X1933650Y192950D02*
Y190100D01*
G01X1934100Y193400D02*
X1933650Y192950D01*
G01X1936750Y165600D02*
X1939550D01*
G01X1934400Y177500D02*
X1935600Y176300D01*
G01X1934400Y179056D02*
Y177500D01*
G01X1933650Y179806D02*
X1934400Y179056D01*
G01X1933650Y181100D02*
Y179806D01*
G01X1930780Y167130D02*
X1929336D01*
G01X1933250Y169600D02*
X1930780Y167130D01*
G01X1925121Y168179D02*
X1923700D01*
G01X1926170Y167130D02*
X1925121Y168179D01*
G01X1929336Y167130D02*
X1926170D01*
G01X1930150Y189050D02*
Y190100D01*
G01X1925027Y183927D02*
X1930150Y189050D01*
G01X1923700Y183927D02*
X1925027D01*
G01X1897642Y193208D02*
Y190300D01*
G01X1930000Y157600D02*
X1929000Y158600D01*
G01X1933250Y157600D02*
X1930000D01*
G01X1925883Y162273D02*
X1923700D01*
G01X1929000Y159156D02*
X1925883Y162273D01*
G01X1929000Y158600D02*
Y159156D01*
G01X1925850Y195850D02*
X1925400Y196300D01*
G01X1928000Y195850D02*
X1925850D01*
G01X1922214Y190300D02*
X1921264D01*
G01X1922820Y190906D02*
X1922214Y190300D01*
G01X1922820Y192420D02*
Y190906D01*
G01X1925100Y194700D02*
X1922820Y192420D01*
G01X1925100Y196000D02*
Y194700D01*
G01X1925400Y196300D02*
X1925100Y196000D01*
G01X1917024Y195624D02*
Y193600D01*
G01X1917450Y196050D02*
X1917024Y195624D01*
G01X1919800Y196050D02*
X1917450D01*
G01X1917327Y193297D02*
Y190300D01*
G01X1917024Y193600D02*
X1917327Y193297D01*
G01X1927000Y170400D02*
X1927500D01*
G01X1925284Y172116D02*
X1927000Y170400D01*
G01X1923700Y172116D02*
X1925284D01*
G01X1930645Y175520D02*
X1931065D01*
G01X1928794Y173669D02*
X1930645Y175520D01*
G01X1925985Y173669D02*
X1928794D01*
G01X1925570Y174084D02*
X1925985Y173669D01*
G01X1923700Y174084D02*
X1925570D01*
G01X1932950Y165300D02*
X1933250Y165600D01*
G01X1927350Y165300D02*
X1932950D01*
G01X1926440Y166210D02*
X1927350Y165300D01*
G01X1923700Y166210D02*
X1926440D01*
G01X1943590Y167389D02*
X1943803Y167176D01*
G01X1934662Y167389D02*
X1943590D01*
G01X1933250Y165977D02*
X1934662Y167389D01*
G01X1933250Y165600D02*
Y165977D01*
G01X1936750Y157600D02*
X1940500D01*
G01X1937909Y188693D02*
X1941000Y191784D01*
G01X1937909Y186846D02*
Y188693D01*
G01X1941012Y191784D02*
X1941000D01*
G01X1942700Y191800D02*
X1944300Y190200D01*
G01X1941016Y191800D02*
X1942700D01*
G01X1941000Y191784D02*
X1941016Y191800D01*
G01X1933650Y185887D02*
Y184100D01*
G01X1932837Y186700D02*
X1933650Y185887D01*
G01X1898800Y193799D02*
Y195344D01*
G01X1899701Y192898D02*
X1898800Y193799D01*
G01X1899701Y190390D02*
Y192898D01*
G01X1899611Y190300D02*
X1899701Y190390D01*
G01X1897760Y197649D02*
Y198710D01*
G01X1898800Y196609D02*
X1897760Y197649D01*
G01X1898800Y195344D02*
Y196609D01*
G01X1960130Y183543D02*
X1955531D01*
G01X1950043D02*
X1955531D01*
G01X1946500Y180000D02*
X1950043Y183543D01*
G01X1948332Y163227D02*
X1946925D01*
G01X1951638Y159921D02*
X1948332Y163227D01*
G01X1955531Y159921D02*
X1951638D01*
G01X1945478Y163227D02*
X1942665Y160414D01*
G01X1946925Y163227D02*
X1945478D01*
G01X1937100Y196100D02*
X1939400Y198400D01*
G01X1935450Y196100D02*
X1937100D01*
G01X1944553Y172047D02*
X1946200D01*
G01X1941609Y174991D02*
X1944553Y172047D01*
G01X1941609Y183346D02*
Y174991D01*
G01Y183346D02*
X1937909D01*
G01X1951250Y167795D02*
X1955531D01*
G01X1950981Y168064D02*
X1951250Y167795D01*
G01X1950183Y168064D02*
X1950981D01*
G01X1946200Y172047D02*
X1950183Y168064D01*
G01X1925290Y179990D02*
X1923700D01*
G01X1926900Y181600D02*
X1925290Y179990D01*
G01X1929650Y181600D02*
X1926900D01*
G01X1930150Y181100D02*
X1929650Y181600D01*
G01X1928530Y206630D02*
X1933290Y201870D01*
G01X1927998Y206630D02*
X1928530D01*
G01X1927064Y207564D02*
X1927998Y206630D01*
G01X1944701Y176299D02*
X1944550Y176450D01*
G01X1951434Y176299D02*
X1944701D01*
G01X1952064Y175669D02*
X1951434Y176299D01*
G01X1955531Y175669D02*
X1952064D01*
G01X1926700Y163400D02*
X1929700D01*
G01X1925858Y164242D02*
X1926700Y163400D01*
G01X1923700Y164242D02*
X1925858D01*
G01X1931500Y161600D02*
X1933250D01*
G01X1929700Y163400D02*
X1931500Y161600D01*
G01X1899092Y231294D02*
X1902907D01*
G01X1920476Y465952D02*
Y460603D01*
G01X1928000Y482090D02*
X1928620Y482710D01*
G01X1923900Y482090D02*
X1928000D01*
G01X1923900Y477510D02*
X1925980Y475430D01*
G01X1923900Y479530D02*
Y477510D01*
G01X1920901Y466377D02*
X1920476Y465952D01*
G01X1935838Y466377D02*
X1920901D01*
G01X1937430Y464785D02*
X1935838Y466377D01*
G01X1954620Y520339D02*
X1962401Y528120D01*
G01X1954620Y505600D02*
Y520339D01*
G01X1953130Y504110D02*
X1954620Y505600D01*
G01X1953130Y497990D02*
Y504110D01*
G01X1956196Y494924D02*
X1953130Y497990D01*
G01X1962401Y494924D02*
X1956196D01*
G01X1937360Y482090D02*
X1933900D01*
G01X1937960Y482690D02*
X1937360Y482090D01*
G01X1940110Y482690D02*
X1937960D01*
G01X1941890Y484470D02*
X1940110Y482690D01*
G01X1941890Y489090D02*
Y484470D01*
G01X1942970Y490170D02*
X1941890Y489090D01*
G01X1944620Y490170D02*
X1942970D01*
G01X1945610Y489180D02*
X1944620Y490170D01*
G01X1899200Y517600D02*
Y520600D01*
G01X1902300Y514500D02*
X1899200Y517600D01*
G01X1908300Y514500D02*
X1902300D01*
G01X1910856Y476675D02*
X1905873Y481658D01*
G01X1917935Y476675D02*
X1910856D01*
G01X1919510Y475100D02*
X1917935Y476675D01*
G01X1911184Y477656D02*
X1906157Y482683D01*
G01X1917966Y477656D02*
X1911184D01*
G01X1919510Y479200D02*
X1917966Y477656D01*
G01X1936740Y484650D02*
X1933900D01*
G01X1937740Y483650D02*
X1936740Y484650D01*
G01X1939712Y483650D02*
X1937740D01*
G01X1940930Y484868D02*
X1939712Y483650D01*
G01X1940930Y489488D02*
Y484868D01*
G01X1942572Y491130D02*
X1940930Y489488D01*
G01X1944400Y491130D02*
X1942572D01*
G01X1945550Y492280D02*
X1944400Y491130D01*
G01X1950270Y490340D02*
X1949110Y489180D01*
G01X1951250Y490340D02*
X1950270D01*
G01X1951860Y489730D02*
X1951250Y490340D01*
G01X1951860Y478220D02*
Y489730D01*
G01X1953480Y476600D02*
X1951860Y478220D01*
G01X1955232Y476600D02*
X1953480D01*
G01X1957063Y474769D02*
X1955232Y476600D01*
G01X1951000Y492280D02*
X1949050D01*
G01X1952820Y490460D02*
X1951000Y492280D01*
G01X1952820Y478600D02*
Y490460D01*
G01X1953870Y477550D02*
X1952820Y478600D01*
G01X1955241Y477550D02*
X1953870D01*
G01X1957212Y479521D02*
X1955241Y477550D01*
G01X1924000Y545200D02*
X1922500Y546700D01*
G01X1934200Y545200D02*
X1924000D01*
G01X1936100Y543300D02*
X1934200Y545200D01*
G01X1939400Y543300D02*
X1936100D01*
G01X1939800Y543700D02*
X1939400Y543300D01*
G01X1899348Y548100D02*
X1899800D01*
G01X1898248Y547000D02*
X1899348Y548100D01*
G01X1900600Y548900D02*
X1899800Y548100D01*
G01X1904000Y548900D02*
X1900600D01*
G01X1923600Y566350D02*
Y565100D01*
G01X1926750Y569500D02*
X1923600Y566350D01*
G01X1926750Y569442D02*
Y569500D01*
G01X1929750Y557050D02*
X1934600Y561900D01*
G01X1929750Y548500D02*
Y557050D01*
G01X1926000Y543325D02*
Y540000D01*
G01X1925575Y543750D02*
X1926000Y543325D01*
G01X1922000Y543750D02*
X1925575D01*
G01X1944882Y550518D02*
Y558464D01*
G01X1945500Y549900D02*
X1944882Y550518D01*
G01X1945900Y549900D02*
X1945500D01*
G01X1936400Y567500D02*
X1936900Y568000D01*
G01X1933500Y567500D02*
X1936400D01*
G01X1932080Y568920D02*
X1933500Y567500D01*
G01X1930772Y568920D02*
X1932080D01*
G01X1930250Y569442D02*
X1930772Y568920D01*
G01X1939720Y571500D02*
X1944882Y566338D01*
G01X1932308Y571500D02*
X1939720D01*
G01X1930250Y569442D02*
X1932308Y571500D01*
G01X1926750Y559650D02*
X1926600Y559500D01*
G01X1926750Y566442D02*
Y559650D01*
G01X1960517Y540467D02*
X1958940Y538890D01*
G01X1908394Y548900D02*
X1911000D01*
G01X1907200Y550094D02*
X1908394Y548900D01*
G01X1907200Y551600D02*
Y550094D01*
G01X1915344Y538000D02*
X1917744Y540400D01*
G01X1913100Y538000D02*
X1915344D01*
G01X1925803Y581103D02*
Y578500D01*
G01X1926400Y581700D02*
X1925803Y581103D01*
G01X1930808Y581700D02*
X1926400D01*
G01X1932610Y583502D02*
X1930808Y581700D01*
G01X1932610Y584500D02*
Y583502D01*
G01X1934150Y586040D02*
X1932610Y584500D01*
G01X1947280Y586040D02*
X1934150D01*
G01X1948960Y587720D02*
X1947280Y586040D01*
G01X1948960Y591380D02*
Y587720D01*
G01X1930250Y566500D02*
Y566442D01*
G01X1934500Y566500D02*
X1930250D01*
G01X1938400Y562600D02*
X1934500Y566500D01*
G01X1949018Y562600D02*
X1938400D01*
G01X1952756Y566338D02*
X1949018Y562600D01*
G01X1930800Y564300D02*
X1932800D01*
G01X1930250Y564850D02*
X1930800Y564300D01*
G01X1930250Y566442D02*
Y564850D01*
G01X1901893Y557807D02*
X1901804D01*
G01X1905800Y553900D02*
X1901893Y557807D01*
G01X1908200Y553900D02*
X1905800D01*
G01X1911000Y556700D02*
X1908200Y553900D01*
G01X1901804Y572496D02*
Y576807D01*
G01X1903400Y570900D02*
X1901804Y572496D01*
G01X1903400Y568300D02*
Y570900D01*
G01X1901804Y566704D02*
X1903400Y568300D01*
G01X1901804Y557807D02*
Y566704D01*
G01X1913982Y543782D02*
X1911000D01*
G01X1914750Y544550D02*
X1913982Y543782D01*
G01X1914750Y544863D02*
Y544550D01*
G01X1958500Y551009D02*
X1956191Y548700D01*
G01X1958500Y582900D02*
Y551009D01*
G01X1965600Y590000D02*
X1958500Y582900D01*
G01X1907500Y544754D02*
Y545600D01*
G01X1906528Y543782D02*
X1907500Y544754D01*
G01X1904000Y543782D02*
X1906528D01*
G01X1934749Y599040D02*
X1934776D01*
G01X1937676Y605040D02*
X1944882Y597834D01*
G01X1934699Y605040D02*
X1937676D01*
G01X1915299Y594001D02*
X1914700Y594600D01*
G01X1919504Y594001D02*
X1915299D01*
G01X1919504Y600296D02*
Y594001D01*
G01X1918000Y601800D02*
X1919504Y600296D01*
G01X1918000Y605201D02*
Y601800D01*
G01X1919504Y606705D02*
X1918000Y605201D01*
G01X1919504Y613001D02*
Y606705D01*
G01Y619704D02*
Y613001D01*
G01X1921407Y621607D02*
X1919504Y619704D01*
G01X1956275Y621607D02*
X1921407D01*
G01X1956700Y621182D02*
X1956275Y621607D01*
G01X1956700Y601778D02*
Y621182D01*
G01X1952756Y597834D02*
X1956700Y601778D01*
G01X1946330Y594010D02*
X1948960Y591380D01*
G01X1942660Y594010D02*
X1946330D01*
G01X1941292Y592642D02*
X1942660Y594010D01*
G01X1935100Y592642D02*
X1941292D01*
G01X1933929Y593813D02*
X1935100Y592642D01*
G01X1932389Y593813D02*
X1933929D01*
G01X1931239Y594963D02*
X1932389Y593813D01*
G01X1931239Y596040D02*
Y594963D01*
G01X1931249Y596050D02*
X1931239Y596040D01*
G01X1931249Y599040D02*
Y596050D01*
G01X1931199Y599090D02*
X1931249Y599040D01*
G01X1931199Y602040D02*
Y599090D01*
G01X1937570Y602040D02*
X1938130Y601480D01*
G01X1934699Y602040D02*
X1937570D01*
G01X1960760Y184173D02*
X1960130Y183543D01*
G01X1970071Y547321D02*
X1972700Y549950D01*
G01X1970071Y545979D02*
Y547321D01*
G01X1960191Y545979D02*
X1959120Y547050D01*
G01X1963071Y545979D02*
X1960191D01*
G01X1970071Y539529D02*
X1972800Y536800D01*
G01X1970071Y540467D02*
Y539529D01*
G01X1964850Y568500D02*
X1962950Y566600D01*
G01X1968000Y568500D02*
X1964850D01*
G01X1962401Y532451D02*
X1964890Y534940D01*
G01X1962401Y528120D02*
Y532451D01*
G01X1964640Y554500D02*
X1968000D01*
G01X1963501Y555639D02*
X1964640Y554500D01*
G01X1961715Y555639D02*
X1963501D01*
G01X1963071Y540467D02*
X1960517D01*
G01X1963600Y576000D02*
X1968000D01*
G01X1962500Y577100D02*
X1963600Y576000D01*
G01X1962500Y578500D02*
Y577100D01*
G01X1965400Y620482D02*
Y619500D01*
G01X1961517Y624365D02*
X1965400Y620482D01*
G01X1961700Y620150D02*
Y619500D01*
G01X1959418Y622432D02*
X1961700Y620150D01*
G01X1964600Y611500D02*
X1968000D01*
G01X1963300Y612800D02*
X1964600Y611500D01*
G01X1962244Y591744D02*
X1961771D01*
G01X1968000Y597500D02*
X1962244Y591744D01*
G01X1968000Y590000D02*
X1965600D01*
G01X1963700Y620166D02*
X1960509Y623357D01*
G01X1963700Y618700D02*
Y620166D01*
G01X1961700Y616700D02*
X1963700Y618700D01*
M02*
